G04 ================== begin FILE IDENTIFICATION RECORD ==================*
G04 Layout Name:  15105-sa.brd*
G04 Film Name:    NOTICE*
G04 File Format:  Gerber RS274X*
G04 File Origin:  Cadence Allegro 16.5-S056*
G04 Origin Date:  Wed Nov 16 02:02:04 2016*
G04 *
G04 Layer:  MANUFACTURING/THERMAL*
G04 *
G04 Offset:    (0.00 0.00)*
G04 Mirror:    No*
G04 Mode:      Positive*
G04 Rotation:  0*
G04 FullContactRelief:  No*
G04 UndefLineWidth:     6.00*
G04 ================== end FILE IDENTIFICATION RECORD ====================*
%FSLAX35Y35*MOIN*%
%IR0*IPPOS*OFA0.00000B0.00000*MIA0B0*SFA1.00000B1.00000*%
%ADD10C,.004*%
%ADD11C,.006*%
%ADD12C,.0033*%
%ADD13C,.008*%
%ADD14C,.0055*%
G75*
%LPD*%
G75*
G36*
G01X298620Y274980D02*
X307300D01*
G03X341410Y274970I17058J11442D01*
G01X348960D01*
X338090Y253970D01*
X309590D01*
X298620Y274980D01*
G37*
G36*
G01X301800Y213890D02*
G02X352500Y214150I25558J-40503D01*
G01X341350Y192820D01*
X312850D01*
X301800Y213890D01*
G37*
G54D10*
G01X820009Y167889D02*
X770009D01*
G01D02*
Y177889D01*
G01Y207889D02*
Y217889D01*
G01X790009Y207889D02*
X770009D01*
G01Y177889D02*
X790009D01*
G01X770009Y217889D02*
X790009D01*
G01X770009Y257889D02*
X790009D01*
G01X770009Y247889D02*
Y257889D01*
G01X790009Y247889D02*
X770009D01*
G01Y297889D02*
X810009D01*
G01X770009Y287889D02*
Y297889D01*
G01X790009Y287889D02*
X770009D01*
G01X796594Y153868D02*
X820594D01*
G01X790009Y177889D02*
Y207889D01*
G01Y217889D02*
Y247889D01*
G01Y257889D02*
Y287889D01*
G01X820594Y153868D02*
X808594Y155868D01*
G01X820009Y224740D02*
Y167889D01*
G01X820594Y161868D02*
Y141868D01*
G01X808594Y155868D02*
Y151868D01*
G01D02*
X820594Y153868D01*
G01X810005Y234744D02*
X810009Y234740D01*
G01Y297889D02*
Y234740D01*
G01D02*
X820009Y224740D01*
G01X838514Y309548D02*
Y305548D01*
G01X850514Y307548D02*
X838514Y309548D01*
G01Y305548D02*
X850514Y307548D01*
G01X810514Y319548D02*
Y299548D01*
G01X822514Y305548D02*
Y309548D01*
G01X810514Y307548D02*
X822514Y305548D01*
G01Y309548D02*
X810514Y307548D01*
G01D02*
X850514D01*
G01X852594Y151868D02*
Y155868D01*
G01X840009Y167889D02*
X890009D01*
G01X840009Y225249D02*
Y167889D01*
G01X859454Y153868D02*
X840594D01*
G01X852594Y155868D02*
X840594Y153868D01*
G01Y141868D02*
Y161868D01*
G01Y153868D02*
X852594Y151868D01*
G01X870009Y207889D02*
X890009D01*
G01X870009Y177889D02*
Y207889D01*
G01X890009Y177889D02*
X870009D01*
G01X845009Y225249D02*
X961000D01*
G01X870009Y217889D02*
Y247889D01*
G01X890009Y217889D02*
X870009D01*
G01X850009Y297889D02*
Y235249D01*
G01D02*
X840009Y225249D01*
G01X870009Y257889D02*
Y287889D01*
G01X890009Y257889D02*
X870009D01*
G01Y247889D02*
X890009D01*
G01X870009Y287889D02*
X890009D01*
G01X850514Y319548D02*
Y299548D01*
G01Y307548D02*
X859374D01*
G01X890009Y297889D02*
X850009D01*
G01X890009Y167889D02*
Y177889D01*
G01Y207889D02*
X890000Y217800D01*
G01X895009Y217889D02*
X961000D01*
G01X890009Y247889D02*
Y257889D01*
G01Y287889D02*
Y297889D01*
G01X958000Y205889D02*
X956000Y217889D01*
X954000Y205889D01*
X958000D01*
G01X956000Y193889D02*
Y217889D01*
G01X954000Y237249D02*
X956000Y225249D01*
X958000Y237249D01*
X954000D01*
G01X956000Y249249D02*
Y225249D01*
G01X1081654Y169388D02*
X1121654D01*
G01X1081654Y179388D02*
Y169388D01*
G01X1101654Y209388D02*
Y179388D01*
G01D02*
X1081654D01*
G01X1101654Y249388D02*
Y219388D01*
G01X1081654Y209388D02*
X1101654D01*
G01X1081654Y219388D02*
Y209388D01*
G01X1101654Y219388D02*
X1081654D01*
G01X1101654Y289388D02*
Y259388D01*
G01X1081654Y249388D02*
X1101654D01*
G01X1081654Y259388D02*
Y249388D01*
G01X1101654Y259388D02*
X1081654D01*
G01X1131654Y299388D02*
X1081654D01*
G01Y289388D02*
X1101654D01*
G01X1081654Y299388D02*
Y289388D01*
G01X1107654Y319388D02*
X1131654D01*
G01X1121654Y169388D02*
Y232028D01*
G01X1133654Y149388D02*
Y153388D01*
G01X1121654Y151388D02*
X1133654Y149388D01*
G01Y153388D02*
X1121654Y151388D01*
G01D02*
X1161654D01*
G01X1121654Y163388D02*
Y143388D01*
G01X1131654Y242028D02*
Y299388D01*
G01X1121654Y232028D02*
X1131654Y242028D01*
G01Y327388D02*
Y307388D01*
G01X1119654Y321388D02*
Y317388D01*
G01X1131654Y319388D02*
X1119654Y321388D01*
G01Y317388D02*
X1131654Y319388D01*
G01X1161654Y169388D02*
Y232537D01*
G01X1201654Y169388D02*
X1161654D01*
G01X1149654Y153388D02*
Y149388D01*
G01X1161654Y151388D02*
X1149654Y153388D01*
G01Y149388D02*
X1161654Y151388D01*
G01D02*
X1170514D01*
G01X1161654Y163388D02*
Y143388D01*
G01X1161658Y232533D02*
X1161654Y232537D01*
G01X1151654Y242537D02*
Y299388D01*
G01X1161654Y232537D02*
X1151654Y242537D01*
G01Y307388D02*
Y327388D01*
G01Y299388D02*
X1201654D01*
G01X1163654Y317388D02*
Y321388D01*
G01X1170514Y319388D02*
X1151654D01*
G01D02*
X1163654Y317388D01*
G01Y321388D02*
X1151654Y319388D01*
G01X1201654Y179388D02*
Y169388D01*
G01X1181654Y179388D02*
X1201654D01*
G01X1181654Y209388D02*
Y179388D01*
G01X1201654Y219388D02*
Y209388D01*
G01D02*
X1181654D01*
G01Y219388D02*
X1201654D01*
G01X1181654Y249388D02*
Y219388D01*
G01X1201654Y259388D02*
Y249388D01*
G01D02*
X1181654D01*
G01Y259388D02*
X1201654D01*
G01X1181654Y289388D02*
Y259388D01*
G01X1201654Y299388D02*
Y289388D01*
G01D02*
X1181654D01*
G54D11*
G01X4300Y524700D02*
X4250D01*
G01X54300Y770700D02*
X54250D01*
G01X288350Y208820D02*
X283350D01*
Y182820D01*
X288350D01*
G01Y187820D02*
X307850D01*
X296850Y208820D01*
X288350D01*
Y213820D01*
X301850D01*
X312850Y192820D01*
X341350D01*
X352350Y213820D01*
X365850D01*
Y208820D01*
X357350D01*
X346350Y187820D01*
X365850D01*
G01X288350D02*
Y182820D01*
X365850D01*
Y187820D01*
G01X285090Y269970D02*
X280090D01*
Y243970D01*
X285090D01*
G01Y248970D02*
X304590D01*
X293590Y269970D01*
X285090D01*
Y274970D01*
X298590D01*
X309590Y253970D01*
X338090D01*
X349090Y274970D01*
X362590D01*
Y269970D01*
X354090D01*
X343090Y248970D01*
X362590D01*
G01X285090D02*
Y243970D01*
X362590D01*
Y248970D01*
G01X283590Y340830D02*
X278590D01*
Y314830D01*
X283590D01*
G01Y319830D02*
Y314830D01*
X361090D01*
Y319830D01*
G01X283590D02*
X303090D01*
X292090Y340830D01*
X283590D01*
Y345830D01*
X297090D01*
X308090Y324830D01*
X336590D01*
X347590Y345830D01*
X361090D01*
Y340830D01*
X352590D01*
X341590Y319830D01*
X361090D01*
G01X304090Y354830D02*
X292090Y352830D01*
X304090Y350830D01*
Y354830D01*
G01X311290Y352830D02*
X292090D01*
G01X332370Y221310D02*
X388140D01*
G01X329290Y266000D02*
X387990D01*
G01X329590Y306830D02*
X341590Y308830D01*
X329590Y310830D01*
Y306830D01*
G01X315090Y310830D02*
X303090Y308830D01*
X315090Y306830D01*
Y310830D01*
G01X306290Y308830D02*
X303090D01*
G01X339590D02*
X304090D01*
G01X365850Y208820D02*
X370850D01*
Y182820D01*
X365850D01*
G01X357370Y214130D02*
X388140D01*
G01X346210Y275010D02*
X387990D01*
G01X362590Y269970D02*
X367590D01*
Y243970D01*
X362590D01*
G01X339890Y308830D02*
X341590D01*
G01X361090Y340830D02*
X366090D01*
Y314830D01*
X361090D01*
G01X340590Y350830D02*
X352590Y352830D01*
X340590Y354830D01*
Y350830D01*
G01X334890Y352830D02*
X352590D01*
G01X385140Y202130D02*
X383140Y214130D01*
X381140Y202130D01*
X385140D01*
G01X383140Y197250D02*
Y214130D01*
G01X385140Y233310D02*
X383140Y221310D01*
X381140Y233310D01*
X385140D01*
G01X383140Y237850D02*
Y221310D01*
G01X384990Y287010D02*
X382990Y275010D01*
X380990Y287010D01*
X384990D01*
G01X382990Y275010D02*
Y290150D01*
G01X384990Y254000D02*
X382990Y266000D01*
X380990Y254000D01*
X384990D01*
G01X382990Y250500D02*
Y266000D01*
G01X849500Y-12451D02*
X821000Y-12500D01*
G01X837503Y-14472D02*
X849500Y-12451D01*
X837497Y-10472D01*
X837503Y-14472D01*
G01X827500Y639629D02*
X830000Y624629D01*
X832500Y639629D01*
X827500D01*
G01X830000Y661875D02*
Y624629D01*
G01X931340D02*
X820000D01*
G01X832500Y710829D02*
X830000Y725829D01*
X827500Y710829D01*
X832500D01*
G01X830000Y693125D02*
Y725829D01*
G01X846340D02*
X820000D01*
G01X849500Y-12500D02*
Y59500D01*
X893500D01*
Y-12500D01*
X849500D01*
G01X864500Y72000D02*
X849500Y69500D01*
X864500Y67000D01*
Y72000D01*
G01X893500Y69500D02*
X849500D01*
G01Y64500D02*
Y79500D01*
G01X903500Y-12500D02*
X944500D01*
G01X903500Y59500D02*
X944500D01*
G01X878500Y67000D02*
X893500Y69500D01*
X878500Y72000D01*
Y67000D01*
G01X901475Y69500D02*
X893500D01*
G01Y64500D02*
Y79500D01*
G01X932000Y2500D02*
X934500Y-12500D01*
X937000Y2500D01*
X932000D01*
G01X934500Y11875D02*
Y-12500D01*
G01X937000Y44500D02*
X934500Y59500D01*
X932000Y44500D01*
X937000D01*
G01X934500Y43125D02*
Y59500D01*
G01X1114953Y628479D02*
X1131500Y617000D01*
X1132500D01*
G01X1119916Y626861D02*
X1114953Y628479D01*
X1118206Y624397D01*
X1119916Y626861D01*
G01X1156654Y242537D02*
X1274500D01*
G01X1206654Y249388D02*
X1274500D01*
G01X1271500Y230537D02*
X1269500Y242537D01*
X1267500Y230537D01*
X1271500D01*
G01X1269500Y218537D02*
Y242537D01*
G01X1267500Y261388D02*
X1269500Y249388D01*
X1271500Y261388D01*
X1267500D01*
G01X1269500Y277200D02*
Y249388D01*
G01X0Y716000D02*
Y-69500D01*
G01D02*
X694500D01*
G01X11750Y-48833D02*
X12417Y-49250D01*
X13167Y-49500D01*
X13833D01*
X14500Y-49250D01*
X15000Y-48833D01*
X15250Y-48250D01*
X15083Y-47667D01*
X14667Y-47167D01*
X13917Y-46833D01*
X12917Y-46667D01*
X12333Y-46333D01*
X12083Y-45750D01*
X12250Y-45167D01*
X12667Y-44750D01*
X13250Y-44500D01*
X13833D01*
X14417Y-44667D01*
X14917Y-45083D01*
G01X19100Y-46167D02*
Y-49500D01*
G01Y-44833D02*
X18933Y-44750D01*
Y-44583D01*
X19100Y-44500D01*
X19267Y-44583D01*
Y-44750D01*
X19100Y-44833D01*
G01X24700Y-49500D02*
Y-44500D01*
G01X28883Y-49500D02*
Y-44500D01*
G01X31550Y-46167D02*
X28883Y-48083D01*
G01X29967Y-47333D02*
X31717Y-49500D01*
G01X34650Y-48917D02*
X35067Y-49250D01*
X35650Y-49500D01*
X36150D01*
X36650Y-49333D01*
X36983Y-49083D01*
X37150Y-48750D01*
X37067Y-48250D01*
X36733Y-48000D01*
X35233Y-47500D01*
X34900Y-46917D01*
X35067Y-46500D01*
X35400Y-46250D01*
X35900Y-46167D01*
X36400Y-46250D01*
X36900Y-46500D01*
G01X42833Y-46583D02*
X42250Y-46250D01*
X41750Y-46167D01*
X41083Y-46333D01*
X40583Y-46667D01*
X40250Y-47250D01*
X40167Y-47833D01*
X40250Y-48417D01*
X40583Y-48917D01*
X41083Y-49333D01*
X41750Y-49500D01*
X42333Y-49333D01*
X42833Y-49000D01*
G01X45933Y-49500D02*
Y-46167D01*
G01Y-46833D02*
X46350Y-46500D01*
X46767Y-46250D01*
X47350Y-46167D01*
X47767Y-46250D01*
X48267Y-46500D01*
G01X51450Y-47250D02*
X54117D01*
X53867Y-46667D01*
X53450Y-46333D01*
X52867Y-46167D01*
X52283Y-46250D01*
X51783Y-46500D01*
X51450Y-47083D01*
X51283Y-47583D01*
Y-48083D01*
X51450Y-48583D01*
X51867Y-49083D01*
X52367Y-49417D01*
X52950Y-49500D01*
X53533Y-49333D01*
X54117Y-48833D01*
G01X57050Y-47250D02*
X59717D01*
X59467Y-46667D01*
X59050Y-46333D01*
X58467Y-46167D01*
X57883Y-46250D01*
X57383Y-46500D01*
X57050Y-47083D01*
X56883Y-47583D01*
Y-48083D01*
X57050Y-48583D01*
X57467Y-49083D01*
X57967Y-49417D01*
X58550Y-49500D01*
X59133Y-49333D01*
X59717Y-48833D01*
G01X62483Y-49500D02*
Y-46167D01*
G01Y-47000D02*
X62817Y-46583D01*
X63317Y-46250D01*
X63983Y-46167D01*
X64567Y-46250D01*
X65067Y-46583D01*
X65317Y-47167D01*
Y-49500D01*
G01X11750Y-3833D02*
X12417Y-4250D01*
X13167Y-4500D01*
X13833D01*
X14500Y-4250D01*
X15000Y-3833D01*
X15250Y-3250D01*
X15083Y-2667D01*
X14667Y-2167D01*
X13917Y-1833D01*
X12917Y-1667D01*
X12333Y-1333D01*
X12083Y-750D01*
X12250Y-167D01*
X12667Y250D01*
X13250Y500D01*
X13833D01*
X14417Y333D01*
X14917Y-83D01*
G01X19100Y-4500D02*
X18600Y-4417D01*
X18100Y-4083D01*
X17767Y-3500D01*
X17600Y-2833D01*
X17767Y-2167D01*
X18100Y-1583D01*
X18600Y-1250D01*
X19100Y-1167D01*
X19600Y-1250D01*
X20100Y-1583D01*
X20433Y-2167D01*
X20517Y-2833D01*
X20433Y-3500D01*
X20100Y-4083D01*
X19600Y-4417D01*
X19100Y-4500D01*
G01X24700D02*
Y500D01*
G01X31800D02*
Y-4500D01*
G01Y-3750D02*
X31467Y-4167D01*
X30967Y-4417D01*
X30383Y-4500D01*
X29717Y-4333D01*
X29217Y-3917D01*
X28883Y-3417D01*
X28800Y-2833D01*
X28883Y-2250D01*
X29217Y-1750D01*
X29717Y-1333D01*
X30383Y-1167D01*
X30967Y-1250D01*
X31383Y-1417D01*
X31800Y-1750D01*
G01X34650Y-2250D02*
X37317D01*
X37067Y-1667D01*
X36650Y-1333D01*
X36067Y-1167D01*
X35483Y-1250D01*
X34983Y-1500D01*
X34650Y-2083D01*
X34483Y-2583D01*
Y-3083D01*
X34650Y-3583D01*
X35067Y-4083D01*
X35567Y-4417D01*
X36150Y-4500D01*
X36733Y-4333D01*
X37317Y-3833D01*
G01X40333Y-4500D02*
Y-1167D01*
G01Y-1833D02*
X40750Y-1500D01*
X41167Y-1250D01*
X41750Y-1167D01*
X42167Y-1250D01*
X42667Y-1500D01*
G01X50200Y-4500D02*
Y-1167D01*
G01Y-2083D02*
X50450Y-1667D01*
X50867Y-1333D01*
X51450Y-1167D01*
X52033Y-1333D01*
X52450Y-1667D01*
X52700Y-2083D01*
Y-4500D01*
G01Y-2083D02*
X52950Y-1667D01*
X53367Y-1333D01*
X53950Y-1167D01*
X54533Y-1333D01*
X54950Y-1667D01*
X55200Y-2167D01*
Y-4500D01*
G01X59800D02*
Y-1167D01*
G01Y-1750D02*
X59467Y-1417D01*
X58967Y-1250D01*
X58383Y-1167D01*
X57800Y-1333D01*
X57300Y-1667D01*
X56967Y-2167D01*
X56800Y-2833D01*
X56967Y-3500D01*
X57300Y-4000D01*
X57800Y-4333D01*
X58383Y-4500D01*
X58967Y-4417D01*
X59467Y-4167D01*
X59800Y-3833D01*
G01X62650Y-3917D02*
X63067Y-4250D01*
X63650Y-4500D01*
X64150D01*
X64650Y-4333D01*
X64983Y-4083D01*
X65150Y-3750D01*
X65067Y-3250D01*
X64733Y-3000D01*
X63233Y-2500D01*
X62900Y-1917D01*
X63067Y-1500D01*
X63400Y-1250D01*
X63900Y-1167D01*
X64400Y-1250D01*
X64900Y-1500D01*
G01X68083Y-4500D02*
Y500D01*
G01X70750Y-1167D02*
X68083Y-3083D01*
G01X69167Y-2333D02*
X70917Y-4500D01*
G01X0Y-24500D02*
X694500D01*
G01X0Y19500D02*
X694500D01*
G01X15167Y64000D02*
X11833D01*
Y69000D01*
X15167D01*
G01X13833Y66583D02*
X11833D01*
G01X19100Y69000D02*
Y64000D01*
G01X17933Y67333D02*
X20267D01*
G01X26033Y66917D02*
X25450Y67250D01*
X24950Y67333D01*
X24283Y67167D01*
X23783Y66833D01*
X23450Y66250D01*
X23367Y65667D01*
X23450Y65083D01*
X23783Y64583D01*
X24283Y64167D01*
X24950Y64000D01*
X25533Y64167D01*
X26033Y64500D01*
G01X28883Y64000D02*
Y69000D01*
G01Y66583D02*
X29300Y67000D01*
X29717Y67250D01*
X30383Y67333D01*
X30883Y67250D01*
X31467Y66917D01*
X31717Y66417D01*
Y64000D01*
G01X0Y105500D02*
X694500D01*
G01X15167Y111500D02*
X11833D01*
Y116500D01*
X15167D01*
G01X13833Y114083D02*
X11833D01*
G01X17850Y114833D02*
X20350Y111500D01*
G01Y114833D02*
X17850Y111500D01*
G01X24700Y116500D02*
Y111500D01*
G01X23533Y114833D02*
X25867D01*
G01X29050Y113750D02*
X31717D01*
X31467Y114333D01*
X31050Y114667D01*
X30467Y114833D01*
X29883Y114750D01*
X29383Y114500D01*
X29050Y113917D01*
X28883Y113417D01*
Y112917D01*
X29050Y112417D01*
X29467Y111917D01*
X29967Y111583D01*
X30550Y111500D01*
X31133Y111667D01*
X31717Y112167D01*
G01X34733Y111500D02*
Y114833D01*
G01Y114167D02*
X35150Y114500D01*
X35567Y114750D01*
X36150Y114833D01*
X36567Y114750D01*
X37067Y114500D01*
G01X40083Y111500D02*
Y114833D01*
G01Y114000D02*
X40417Y114417D01*
X40917Y114750D01*
X41583Y114833D01*
X42167Y114750D01*
X42667Y114417D01*
X42917Y113833D01*
Y111500D01*
G01X48600D02*
Y114833D01*
G01Y114250D02*
X48267Y114583D01*
X47767Y114750D01*
X47183Y114833D01*
X46600Y114667D01*
X46100Y114333D01*
X45767Y113833D01*
X45600Y113167D01*
X45767Y112500D01*
X46100Y112000D01*
X46600Y111667D01*
X47183Y111500D01*
X47767Y111583D01*
X48267Y111833D01*
X48600Y112167D01*
G01X52700Y111500D02*
Y116500D01*
G01X63900Y111500D02*
Y116500D01*
G01X71000Y111500D02*
Y114833D01*
G01Y114250D02*
X70667Y114583D01*
X70167Y114750D01*
X69583Y114833D01*
X69000Y114667D01*
X68500Y114333D01*
X68167Y113833D01*
X68000Y113167D01*
X68167Y112500D01*
X68500Y112000D01*
X69000Y111667D01*
X69583Y111500D01*
X70167Y111583D01*
X70667Y111833D01*
X71000Y112167D01*
G01X73350Y110000D02*
X73850Y109833D01*
X74517Y110000D01*
X74933Y110333D01*
X75267Y110750D01*
X75767Y112083D01*
X76850Y114833D01*
G01X74183D02*
X75767Y112083D01*
G01X79450Y113750D02*
X82117D01*
X81867Y114333D01*
X81450Y114667D01*
X80867Y114833D01*
X80283Y114750D01*
X79783Y114500D01*
X79450Y113917D01*
X79283Y113417D01*
Y112917D01*
X79450Y112417D01*
X79867Y111917D01*
X80367Y111583D01*
X80950Y111500D01*
X81533Y111667D01*
X82117Y112167D01*
G01X85133Y111500D02*
Y114833D01*
G01Y114167D02*
X85550Y114500D01*
X85967Y114750D01*
X86550Y114833D01*
X86967Y114750D01*
X87467Y114500D01*
G01X15333Y146083D02*
X14833Y146333D01*
X14250Y146500D01*
X13583D01*
X12833Y146250D01*
X12250Y145833D01*
X11833Y145333D01*
X11500Y144500D01*
X11417Y143750D01*
X11583Y143000D01*
X11833Y142500D01*
X12333Y142000D01*
X12917Y141667D01*
X13500Y141500D01*
X14083D01*
X14667Y141667D01*
X15167Y141917D01*
X15583Y142250D01*
G01X19100Y141500D02*
X18600Y141583D01*
X18100Y141917D01*
X17767Y142500D01*
X17600Y143167D01*
X17767Y143833D01*
X18100Y144417D01*
X18600Y144750D01*
X19100Y144833D01*
X19600Y144750D01*
X20100Y144417D01*
X20433Y143833D01*
X20517Y143167D01*
X20433Y142500D01*
X20100Y141917D01*
X19600Y141583D01*
X19100Y141500D01*
G01X23200Y139833D02*
Y144833D01*
G01Y144083D02*
X23617Y144500D01*
X24033Y144750D01*
X24700Y144833D01*
X25283Y144750D01*
X25867Y144333D01*
X26117Y143750D01*
X26200Y143167D01*
X26117Y142583D01*
X25867Y142000D01*
X25367Y141667D01*
X24700Y141500D01*
X24117Y141583D01*
X23533Y141833D01*
X23200Y142167D01*
G01X28800Y139833D02*
Y144833D01*
G01Y144083D02*
X29217Y144500D01*
X29633Y144750D01*
X30300Y144833D01*
X30883Y144750D01*
X31467Y144333D01*
X31717Y143750D01*
X31800Y143167D01*
X31717Y142583D01*
X31467Y142000D01*
X30967Y141667D01*
X30300Y141500D01*
X29717Y141583D01*
X29133Y141833D01*
X28800Y142167D01*
G01X34650Y143750D02*
X37317D01*
X37067Y144333D01*
X36650Y144667D01*
X36067Y144833D01*
X35483Y144750D01*
X34983Y144500D01*
X34650Y143917D01*
X34483Y143417D01*
Y142917D01*
X34650Y142417D01*
X35067Y141917D01*
X35567Y141583D01*
X36150Y141500D01*
X36733Y141667D01*
X37317Y142167D01*
G01X40333Y141500D02*
Y144833D01*
G01Y144167D02*
X40750Y144500D01*
X41167Y144750D01*
X41750Y144833D01*
X42167Y144750D01*
X42667Y144500D01*
G01X51033Y141500D02*
Y146500D01*
X53033D01*
X53700Y146250D01*
X54200Y145667D01*
X54367Y145000D01*
X54200Y144333D01*
X53783Y143833D01*
X53033Y143583D01*
X51033D01*
G01X58300Y141500D02*
Y146500D01*
G01X65400Y141500D02*
Y144833D01*
G01Y144250D02*
X65067Y144583D01*
X64567Y144750D01*
X63983Y144833D01*
X63400Y144667D01*
X62900Y144333D01*
X62567Y143833D01*
X62400Y143167D01*
X62567Y142500D01*
X62900Y142000D01*
X63400Y141667D01*
X63983Y141500D01*
X64567Y141583D01*
X65067Y141833D01*
X65400Y142167D01*
G01X69500Y146500D02*
Y141500D01*
G01X68333Y144833D02*
X70667D01*
G01X75100D02*
Y141500D01*
G01Y146167D02*
X74933Y146250D01*
Y146417D01*
X75100Y146500D01*
X75267Y146417D01*
Y146250D01*
X75100Y146167D01*
G01X79283Y141500D02*
Y144833D01*
G01Y144000D02*
X79617Y144417D01*
X80117Y144750D01*
X80783Y144833D01*
X81367Y144750D01*
X81867Y144417D01*
X82117Y143833D01*
Y141500D01*
G01X85133Y140250D02*
X85717Y139917D01*
X86383Y139833D01*
X86967Y139917D01*
X87467Y140333D01*
X87800Y140917D01*
Y144833D01*
G01Y144167D02*
X87467Y144500D01*
X86967Y144750D01*
X86383Y144833D01*
X85717Y144667D01*
X85300Y144333D01*
X84967Y143750D01*
X84800Y143167D01*
X84883Y142667D01*
X85217Y142083D01*
X85717Y141667D01*
X86383Y141500D01*
X86883Y141583D01*
X87467Y141917D01*
X87800Y142250D01*
G01X0Y120500D02*
X694500D01*
G01X1500Y175500D02*
X694500D01*
G01X11667Y459000D02*
Y464000D01*
X13333D01*
X14000Y463750D01*
X14500Y463417D01*
X14917Y462917D01*
X15250Y462333D01*
X15333Y461500D01*
X15250Y460667D01*
X14917Y460083D01*
X14500Y459583D01*
X14000Y459250D01*
X13333Y459000D01*
X11667D01*
G01X17933D02*
Y462333D01*
G01Y461667D02*
X18350Y462000D01*
X18767Y462250D01*
X19350Y462333D01*
X19767Y462250D01*
X20267Y462000D01*
G01X24700Y462333D02*
Y459000D01*
G01Y463667D02*
X24533Y463750D01*
Y463917D01*
X24700Y464000D01*
X24867Y463917D01*
Y463750D01*
X24700Y463667D01*
G01X30300Y459000D02*
Y464000D01*
G01X35900Y459000D02*
Y464000D01*
G01X0Y599000D02*
X694500D01*
G01X24960Y626740D02*
X26960D01*
G01X25960D02*
Y621740D01*
G01X24960D02*
X26960D01*
G01X30143D02*
Y625073D01*
G01Y624240D02*
X30477Y624657D01*
X30977Y624990D01*
X31643Y625073D01*
X32227Y624990D01*
X32727Y624657D01*
X32977Y624073D01*
Y621740D01*
G01X35743D02*
Y625073D01*
G01Y624240D02*
X36077Y624657D01*
X36577Y624990D01*
X37243Y625073D01*
X37827Y624990D01*
X38327Y624657D01*
X38577Y624073D01*
Y621740D01*
G01X41510Y623990D02*
X44177D01*
X43927Y624573D01*
X43510Y624907D01*
X42927Y625073D01*
X42343Y624990D01*
X41843Y624740D01*
X41510Y624157D01*
X41343Y623657D01*
Y623157D01*
X41510Y622657D01*
X41927Y622157D01*
X42427Y621823D01*
X43010Y621740D01*
X43593Y621907D01*
X44177Y622407D01*
G01X47193Y621740D02*
Y625073D01*
G01Y624407D02*
X47610Y624740D01*
X48027Y624990D01*
X48610Y625073D01*
X49027Y624990D01*
X49527Y624740D01*
G01X59560Y621740D02*
Y626740D01*
G01X66660Y621740D02*
Y625073D01*
G01Y624490D02*
X66327Y624823D01*
X65827Y624990D01*
X65243Y625073D01*
X64660Y624907D01*
X64160Y624573D01*
X63827Y624073D01*
X63660Y623407D01*
X63827Y622740D01*
X64160Y622240D01*
X64660Y621907D01*
X65243Y621740D01*
X65827Y621823D01*
X66327Y622073D01*
X66660Y622407D01*
G01X69010Y620240D02*
X69510Y620073D01*
X70177Y620240D01*
X70593Y620573D01*
X70927Y620990D01*
X71427Y622323D01*
X72510Y625073D01*
G01X69843D02*
X71427Y622323D01*
G01X75110Y623990D02*
X77777D01*
X77527Y624573D01*
X77110Y624907D01*
X76527Y625073D01*
X75943Y624990D01*
X75443Y624740D01*
X75110Y624157D01*
X74943Y623657D01*
Y623157D01*
X75110Y622657D01*
X75527Y622157D01*
X76027Y621823D01*
X76610Y621740D01*
X77193Y621907D01*
X77777Y622407D01*
G01X80793Y621740D02*
Y625073D01*
G01Y624407D02*
X81210Y624740D01*
X81627Y624990D01*
X82210Y625073D01*
X82627Y624990D01*
X83127Y624740D01*
G01X0Y679000D02*
X694500D01*
G01X-1000Y654000D02*
X694500D01*
G01X9917Y693667D02*
X10417Y694167D01*
X11000Y694417D01*
X11667Y694500D01*
X12500Y694333D01*
X13083Y693917D01*
X13250Y693417D01*
X13167Y692917D01*
X12833Y692500D01*
X11167Y691667D01*
X10417Y691083D01*
X9917Y690250D01*
X9750Y689500D01*
X13250D01*
G01X17100Y689333D02*
X16933Y689417D01*
Y689583D01*
X17100Y689667D01*
X17267Y689583D01*
Y689417D01*
X17100Y689333D01*
G01X22700Y694500D02*
Y689500D01*
G01X20783Y694500D02*
X24617D01*
G01X28300Y689500D02*
X27800Y689583D01*
X27300Y689917D01*
X26967Y690500D01*
X26800Y691167D01*
X26967Y691833D01*
X27300Y692417D01*
X27800Y692750D01*
X28300Y692833D01*
X28800Y692750D01*
X29300Y692417D01*
X29633Y691833D01*
X29717Y691167D01*
X29633Y690500D01*
X29300Y689917D01*
X28800Y689583D01*
X28300Y689500D01*
G01X33900D02*
Y694500D01*
G01X38250Y691750D02*
X40917D01*
X40667Y692333D01*
X40250Y692667D01*
X39667Y692833D01*
X39083Y692750D01*
X38583Y692500D01*
X38250Y691917D01*
X38083Y691417D01*
Y690917D01*
X38250Y690417D01*
X38667Y689917D01*
X39167Y689583D01*
X39750Y689500D01*
X40333Y689667D01*
X40917Y690167D01*
G01X43933Y689500D02*
Y692833D01*
G01Y692167D02*
X44350Y692500D01*
X44767Y692750D01*
X45350Y692833D01*
X45767Y692750D01*
X46267Y692500D01*
G01X52200Y689500D02*
Y692833D01*
G01Y692250D02*
X51867Y692583D01*
X51367Y692750D01*
X50783Y692833D01*
X50200Y692667D01*
X49700Y692333D01*
X49367Y691833D01*
X49200Y691167D01*
X49367Y690500D01*
X49700Y690000D01*
X50200Y689667D01*
X50783Y689500D01*
X51367Y689583D01*
X51867Y689833D01*
X52200Y690167D01*
G01X54883Y689500D02*
Y692833D01*
G01Y692000D02*
X55217Y692417D01*
X55717Y692750D01*
X56383Y692833D01*
X56967Y692750D01*
X57467Y692417D01*
X57717Y691833D01*
Y689500D01*
G01X63233Y692417D02*
X62650Y692750D01*
X62150Y692833D01*
X61483Y692667D01*
X60983Y692333D01*
X60650Y691750D01*
X60567Y691167D01*
X60650Y690583D01*
X60983Y690083D01*
X61483Y689667D01*
X62150Y689500D01*
X62733Y689667D01*
X63233Y690000D01*
G01X66250Y691750D02*
X68917D01*
X68667Y692333D01*
X68250Y692667D01*
X67667Y692833D01*
X67083Y692750D01*
X66583Y692500D01*
X66250Y691917D01*
X66083Y691417D01*
Y690917D01*
X66250Y690417D01*
X66667Y689917D01*
X67167Y689583D01*
X67750Y689500D01*
X68333Y689667D01*
X68917Y690167D01*
G01X78700Y694500D02*
Y689500D01*
G01X77533Y692833D02*
X79867D01*
G01X85800Y689500D02*
Y692833D01*
G01Y692250D02*
X85467Y692583D01*
X84967Y692750D01*
X84383Y692833D01*
X83800Y692667D01*
X83300Y692333D01*
X82967Y691833D01*
X82800Y691167D01*
X82967Y690500D01*
X83300Y690000D01*
X83800Y689667D01*
X84383Y689500D01*
X84967Y689583D01*
X85467Y689833D01*
X85800Y690167D01*
G01X88400Y689500D02*
Y694500D01*
G01Y692000D02*
X88817Y692500D01*
X89317Y692750D01*
X89817Y692833D01*
X90567Y692667D01*
X91067Y692333D01*
X91400Y691750D01*
Y691083D01*
X91233Y690417D01*
X90900Y689917D01*
X90317Y689583D01*
X89817Y689500D01*
X89317Y689583D01*
X88817Y689833D01*
X88400Y690250D01*
G01X95500Y689500D02*
Y694500D01*
G01X99850Y691750D02*
X102517D01*
X102267Y692333D01*
X101850Y692667D01*
X101267Y692833D01*
X100683Y692750D01*
X100183Y692500D01*
X99850Y691917D01*
X99683Y691417D01*
Y690917D01*
X99850Y690417D01*
X100267Y689917D01*
X100767Y689583D01*
X101350Y689500D01*
X101933Y689667D01*
X102517Y690167D01*
G01X106700Y689333D02*
X106533Y689417D01*
Y689583D01*
X106700Y689667D01*
X106867Y689583D01*
Y689417D01*
X106700Y689333D01*
G01Y691583D02*
X106533Y691667D01*
Y691833D01*
X106700Y691917D01*
X106867Y691833D01*
Y691667D01*
X106700Y691583D01*
G01X0Y850500D02*
Y709000D01*
X694500D01*
Y850500D01*
G01X7000Y832500D02*
Y837500D01*
X6000Y836500D01*
G01Y832500D02*
X8000D01*
G01X12600Y832333D02*
X12433Y832417D01*
Y832583D01*
X12600Y832667D01*
X12767Y832583D01*
Y832417D01*
X12600Y832333D01*
G01X16450Y833167D02*
X17117Y832750D01*
X17867Y832500D01*
X18533D01*
X19200Y832750D01*
X19700Y833167D01*
X19950Y833750D01*
X19783Y834333D01*
X19367Y834833D01*
X18617Y835167D01*
X17617Y835333D01*
X17033Y835667D01*
X16783Y836250D01*
X16950Y836833D01*
X17367Y837250D01*
X17950Y837500D01*
X18533D01*
X19117Y837333D01*
X19617Y836917D01*
G01X22300Y830833D02*
Y835833D01*
G01Y835083D02*
X22717Y835500D01*
X23133Y835750D01*
X23800Y835833D01*
X24383Y835750D01*
X24967Y835333D01*
X25217Y834750D01*
X25300Y834167D01*
X25217Y833583D01*
X24967Y833000D01*
X24467Y832667D01*
X23800Y832500D01*
X23217Y832583D01*
X22633Y832833D01*
X22300Y833167D01*
G01X28150Y834750D02*
X30817D01*
X30567Y835333D01*
X30150Y835667D01*
X29567Y835833D01*
X28983Y835750D01*
X28483Y835500D01*
X28150Y834917D01*
X27983Y834417D01*
Y833917D01*
X28150Y833417D01*
X28567Y832917D01*
X29067Y832583D01*
X29650Y832500D01*
X30233Y832667D01*
X30817Y833167D01*
G01X36333Y835417D02*
X35750Y835750D01*
X35250Y835833D01*
X34583Y835667D01*
X34083Y835333D01*
X33750Y834750D01*
X33667Y834167D01*
X33750Y833583D01*
X34083Y833083D01*
X34583Y832667D01*
X35250Y832500D01*
X35833Y832667D01*
X36333Y833000D01*
G01X40600Y835833D02*
Y832500D01*
G01Y837167D02*
X40433Y837250D01*
Y837417D01*
X40600Y837500D01*
X40767Y837417D01*
Y837250D01*
X40600Y837167D01*
G01X45700Y832500D02*
Y836750D01*
X45867Y837167D01*
X46200Y837417D01*
X46700Y837500D01*
X47200Y837333D01*
X47450Y836917D01*
G01X46450Y835500D02*
X44783D01*
G01X51800Y835833D02*
Y832500D01*
G01Y837167D02*
X51633Y837250D01*
Y837417D01*
X51800Y837500D01*
X51967Y837417D01*
Y837250D01*
X51800Y837167D01*
G01X58733Y835417D02*
X58150Y835750D01*
X57650Y835833D01*
X56983Y835667D01*
X56483Y835333D01*
X56150Y834750D01*
X56067Y834167D01*
X56150Y833583D01*
X56483Y833083D01*
X56983Y832667D01*
X57650Y832500D01*
X58233Y832667D01*
X58733Y833000D01*
G01X64500Y832500D02*
Y835833D01*
G01Y835250D02*
X64167Y835583D01*
X63667Y835750D01*
X63083Y835833D01*
X62500Y835667D01*
X62000Y835333D01*
X61667Y834833D01*
X61500Y834167D01*
X61667Y833500D01*
X62000Y833000D01*
X62500Y832667D01*
X63083Y832500D01*
X63667Y832583D01*
X64167Y832833D01*
X64500Y833167D01*
G01X68600Y837500D02*
Y832500D01*
G01X67433Y835833D02*
X69767D01*
G01X74200D02*
Y832500D01*
G01Y837167D02*
X74033Y837250D01*
Y837417D01*
X74200Y837500D01*
X74367Y837417D01*
Y837250D01*
X74200Y837167D01*
G01X79800Y832500D02*
X79300Y832583D01*
X78800Y832917D01*
X78467Y833500D01*
X78300Y834167D01*
X78467Y834833D01*
X78800Y835417D01*
X79300Y835750D01*
X79800Y835833D01*
X80300Y835750D01*
X80800Y835417D01*
X81133Y834833D01*
X81217Y834167D01*
X81133Y833500D01*
X80800Y832917D01*
X80300Y832583D01*
X79800Y832500D01*
G01X83983D02*
Y835833D01*
G01Y835000D02*
X84317Y835417D01*
X84817Y835750D01*
X85483Y835833D01*
X86067Y835750D01*
X86567Y835417D01*
X86817Y834833D01*
Y832500D01*
G01X98100Y837500D02*
Y832500D01*
G01Y833250D02*
X97767Y832833D01*
X97267Y832583D01*
X96683Y832500D01*
X96017Y832667D01*
X95517Y833083D01*
X95183Y833583D01*
X95100Y834167D01*
X95183Y834750D01*
X95517Y835250D01*
X96017Y835667D01*
X96683Y835833D01*
X97267Y835750D01*
X97683Y835583D01*
X98100Y835250D01*
G01X102200Y832500D02*
X101700Y832583D01*
X101200Y832917D01*
X100867Y833500D01*
X100700Y834167D01*
X100867Y834833D01*
X101200Y835417D01*
X101700Y835750D01*
X102200Y835833D01*
X102700Y835750D01*
X103200Y835417D01*
X103533Y834833D01*
X103617Y834167D01*
X103533Y833500D01*
X103200Y832917D01*
X102700Y832583D01*
X102200Y832500D01*
G01X109133Y835417D02*
X108550Y835750D01*
X108050Y835833D01*
X107383Y835667D01*
X106883Y835333D01*
X106550Y834750D01*
X106467Y834167D01*
X106550Y833583D01*
X106883Y833083D01*
X107383Y832667D01*
X108050Y832500D01*
X108633Y832667D01*
X109133Y833000D01*
G01X111983Y835833D02*
Y833500D01*
X112317Y832917D01*
X112817Y832583D01*
X113400Y832500D01*
X113983Y832583D01*
X114483Y832917D01*
X114817Y833500D01*
G01Y832500D02*
Y835833D01*
G01X116500Y832500D02*
Y835833D01*
G01Y834917D02*
X116750Y835333D01*
X117167Y835667D01*
X117750Y835833D01*
X118333Y835667D01*
X118750Y835333D01*
X119000Y834917D01*
Y832500D01*
G01Y834917D02*
X119250Y835333D01*
X119667Y835667D01*
X120250Y835833D01*
X120833Y835667D01*
X121250Y835333D01*
X121500Y834833D01*
Y832500D01*
G01X123350Y834750D02*
X126017D01*
X125767Y835333D01*
X125350Y835667D01*
X124767Y835833D01*
X124183Y835750D01*
X123683Y835500D01*
X123350Y834917D01*
X123183Y834417D01*
Y833917D01*
X123350Y833417D01*
X123767Y832917D01*
X124267Y832583D01*
X124850Y832500D01*
X125433Y832667D01*
X126017Y833167D01*
G01X128783Y832500D02*
Y835833D01*
G01Y835000D02*
X129117Y835417D01*
X129617Y835750D01*
X130283Y835833D01*
X130867Y835750D01*
X131367Y835417D01*
X131617Y834833D01*
Y832500D01*
G01X135800Y837500D02*
Y832500D01*
G01X134633Y835833D02*
X136967D01*
G01X141400Y832333D02*
X141233Y832417D01*
Y832583D01*
X141400Y832667D01*
X141567Y832583D01*
Y832417D01*
X141400Y832333D01*
G01Y834583D02*
X141233Y834667D01*
Y834833D01*
X141400Y834917D01*
X141567Y834833D01*
Y834667D01*
X141400Y834583D01*
G01X0Y820500D02*
X694500D01*
G01X0Y850500D02*
X694500D01*
G01X34000Y663333D02*
Y668333D01*
G01Y667583D02*
X34417Y668000D01*
X34833Y668250D01*
X35500Y668333D01*
X36083Y668250D01*
X36667Y667833D01*
X36917Y667250D01*
X37000Y666667D01*
X36917Y666083D01*
X36667Y665500D01*
X36167Y665167D01*
X35500Y665000D01*
X34917Y665083D01*
X34333Y665333D01*
X34000Y665667D01*
G01X39933Y665000D02*
Y668333D01*
G01Y667667D02*
X40350Y668000D01*
X40767Y668250D01*
X41350Y668333D01*
X41767Y668250D01*
X42267Y668000D01*
G01X46700Y665000D02*
X46200Y665083D01*
X45700Y665417D01*
X45367Y666000D01*
X45200Y666667D01*
X45367Y667333D01*
X45700Y667917D01*
X46200Y668250D01*
X46700Y668333D01*
X47200Y668250D01*
X47700Y667917D01*
X48033Y667333D01*
X48117Y666667D01*
X48033Y666000D01*
X47700Y665417D01*
X47200Y665083D01*
X46700Y665000D01*
G01X53633Y667917D02*
X53050Y668250D01*
X52550Y668333D01*
X51883Y668167D01*
X51383Y667833D01*
X51050Y667250D01*
X50967Y666667D01*
X51050Y666083D01*
X51383Y665583D01*
X51883Y665167D01*
X52550Y665000D01*
X53133Y665167D01*
X53633Y665500D01*
G01X56650Y667250D02*
X59317D01*
X59067Y667833D01*
X58650Y668167D01*
X58067Y668333D01*
X57483Y668250D01*
X56983Y668000D01*
X56650Y667417D01*
X56483Y666917D01*
Y666417D01*
X56650Y665917D01*
X57067Y665417D01*
X57567Y665083D01*
X58150Y665000D01*
X58733Y665167D01*
X59317Y665667D01*
G01X62250Y665583D02*
X62667Y665250D01*
X63250Y665000D01*
X63750D01*
X64250Y665167D01*
X64583Y665417D01*
X64750Y665750D01*
X64667Y666250D01*
X64333Y666500D01*
X62833Y667000D01*
X62500Y667583D01*
X62667Y668000D01*
X63000Y668250D01*
X63500Y668333D01*
X64000Y668250D01*
X64500Y668000D01*
G01X67850Y665583D02*
X68267Y665250D01*
X68850Y665000D01*
X69350D01*
X69850Y665167D01*
X70183Y665417D01*
X70350Y665750D01*
X70267Y666250D01*
X69933Y666500D01*
X68433Y667000D01*
X68100Y667583D01*
X68267Y668000D01*
X68600Y668250D01*
X69100Y668333D01*
X69600Y668250D01*
X70100Y668000D01*
G01X57000Y802500D02*
X59000D01*
G01X58000D02*
Y797500D01*
G01X57000D02*
X59000D01*
G01X63100D02*
Y801750D01*
X63267Y802167D01*
X63600Y802417D01*
X64100Y802500D01*
X64600Y802333D01*
X64850Y801917D01*
G01X63850Y800500D02*
X62183D01*
G01X74800Y802500D02*
Y797500D01*
G01X73633Y800833D02*
X75967D01*
G01X78983Y797500D02*
Y802500D01*
G01Y800083D02*
X79400Y800500D01*
X79817Y800750D01*
X80483Y800833D01*
X80983Y800750D01*
X81567Y800417D01*
X81817Y799917D01*
Y797500D01*
G01X84750Y799750D02*
X87417D01*
X87167Y800333D01*
X86750Y800667D01*
X86167Y800833D01*
X85583Y800750D01*
X85083Y800500D01*
X84750Y799917D01*
X84583Y799417D01*
Y798917D01*
X84750Y798417D01*
X85167Y797917D01*
X85667Y797583D01*
X86250Y797500D01*
X86833Y797667D01*
X87417Y798167D01*
G01X98533Y800417D02*
X97950Y800750D01*
X97450Y800833D01*
X96783Y800667D01*
X96283Y800333D01*
X95950Y799750D01*
X95867Y799167D01*
X95950Y798583D01*
X96283Y798083D01*
X96783Y797667D01*
X97450Y797500D01*
X98033Y797667D01*
X98533Y798000D01*
G01X101633Y797500D02*
Y800833D01*
G01Y800167D02*
X102050Y800500D01*
X102467Y800750D01*
X103050Y800833D01*
X103467Y800750D01*
X103967Y800500D01*
G01X108400Y800833D02*
Y797500D01*
G01Y802167D02*
X108233Y802250D01*
Y802417D01*
X108400Y802500D01*
X108567Y802417D01*
Y802250D01*
X108400Y802167D01*
G01X114000Y802500D02*
Y797500D01*
G01X112833Y800833D02*
X115167D01*
G01X118350Y799750D02*
X121017D01*
X120767Y800333D01*
X120350Y800667D01*
X119767Y800833D01*
X119183Y800750D01*
X118683Y800500D01*
X118350Y799917D01*
X118183Y799417D01*
Y798917D01*
X118350Y798417D01*
X118767Y797917D01*
X119267Y797583D01*
X119850Y797500D01*
X120433Y797667D01*
X121017Y798167D01*
G01X124033Y797500D02*
Y800833D01*
G01Y800167D02*
X124450Y800500D01*
X124867Y800750D01*
X125450Y800833D01*
X125867Y800750D01*
X126367Y800500D01*
G01X130800Y800833D02*
Y797500D01*
G01Y802167D02*
X130633Y802250D01*
Y802417D01*
X130800Y802500D01*
X130967Y802417D01*
Y802250D01*
X130800Y802167D01*
G01X137900Y797500D02*
Y800833D01*
G01Y800250D02*
X137567Y800583D01*
X137067Y800750D01*
X136483Y800833D01*
X135900Y800667D01*
X135400Y800333D01*
X135067Y799833D01*
X134900Y799167D01*
X135067Y798500D01*
X135400Y798000D01*
X135900Y797667D01*
X136483Y797500D01*
X137067Y797583D01*
X137567Y797833D01*
X137900Y798167D01*
G01X147600Y800833D02*
Y797500D01*
G01Y802167D02*
X147433Y802250D01*
Y802417D01*
X147600Y802500D01*
X147767Y802417D01*
Y802250D01*
X147600Y802167D01*
G01X151950Y798083D02*
X152367Y797750D01*
X152950Y797500D01*
X153450D01*
X153950Y797667D01*
X154283Y797917D01*
X154450Y798250D01*
X154367Y798750D01*
X154033Y799000D01*
X152533Y799500D01*
X152200Y800083D01*
X152367Y800500D01*
X152700Y800750D01*
X153200Y800833D01*
X153700Y800750D01*
X154200Y800500D01*
G01X162983Y797500D02*
Y800833D01*
G01Y800000D02*
X163317Y800417D01*
X163817Y800750D01*
X164483Y800833D01*
X165067Y800750D01*
X165567Y800417D01*
X165817Y799833D01*
Y797500D01*
G01X170000D02*
X169500Y797583D01*
X169000Y797917D01*
X168667Y798500D01*
X168500Y799167D01*
X168667Y799833D01*
X169000Y800417D01*
X169500Y800750D01*
X170000Y800833D01*
X170500Y800750D01*
X171000Y800417D01*
X171333Y799833D01*
X171417Y799167D01*
X171333Y798500D01*
X171000Y797917D01*
X170500Y797583D01*
X170000Y797500D01*
G01X175600Y802500D02*
Y797500D01*
G01X174433Y800833D02*
X176767D01*
G01X185550Y798083D02*
X185967Y797750D01*
X186550Y797500D01*
X187050D01*
X187550Y797667D01*
X187883Y797917D01*
X188050Y798250D01*
X187967Y798750D01*
X187633Y799000D01*
X186133Y799500D01*
X185800Y800083D01*
X185967Y800500D01*
X186300Y800750D01*
X186800Y800833D01*
X187300Y800750D01*
X187800Y800500D01*
G01X190900Y795833D02*
Y800833D01*
G01Y800083D02*
X191317Y800500D01*
X191733Y800750D01*
X192400Y800833D01*
X192983Y800750D01*
X193567Y800333D01*
X193817Y799750D01*
X193900Y799167D01*
X193817Y798583D01*
X193567Y798000D01*
X193067Y797667D01*
X192400Y797500D01*
X191817Y797583D01*
X191233Y797833D01*
X190900Y798167D01*
G01X196750Y799750D02*
X199417D01*
X199167Y800333D01*
X198750Y800667D01*
X198167Y800833D01*
X197583Y800750D01*
X197083Y800500D01*
X196750Y799917D01*
X196583Y799417D01*
Y798917D01*
X196750Y798417D01*
X197167Y797917D01*
X197667Y797583D01*
X198250Y797500D01*
X198833Y797667D01*
X199417Y798167D01*
G01X204933Y800417D02*
X204350Y800750D01*
X203850Y800833D01*
X203183Y800667D01*
X202683Y800333D01*
X202350Y799750D01*
X202267Y799167D01*
X202350Y798583D01*
X202683Y798083D01*
X203183Y797667D01*
X203850Y797500D01*
X204433Y797667D01*
X204933Y798000D01*
G01X209200Y800833D02*
Y797500D01*
G01Y802167D02*
X209033Y802250D01*
Y802417D01*
X209200Y802500D01*
X209367Y802417D01*
Y802250D01*
X209200Y802167D01*
G01X214300Y797500D02*
Y801750D01*
X214467Y802167D01*
X214800Y802417D01*
X215300Y802500D01*
X215800Y802333D01*
X216050Y801917D01*
G01X215050Y800500D02*
X213383D01*
G01X220400Y800833D02*
Y797500D01*
G01Y802167D02*
X220233Y802250D01*
Y802417D01*
X220400Y802500D01*
X220567Y802417D01*
Y802250D01*
X220400Y802167D01*
G01X224750Y799750D02*
X227417D01*
X227167Y800333D01*
X226750Y800667D01*
X226167Y800833D01*
X225583Y800750D01*
X225083Y800500D01*
X224750Y799917D01*
X224583Y799417D01*
Y798917D01*
X224750Y798417D01*
X225167Y797917D01*
X225667Y797583D01*
X226250Y797500D01*
X226833Y797667D01*
X227417Y798167D01*
G01X233100Y802500D02*
Y797500D01*
G01Y798250D02*
X232767Y797833D01*
X232267Y797583D01*
X231683Y797500D01*
X231017Y797667D01*
X230517Y798083D01*
X230183Y798583D01*
X230100Y799167D01*
X230183Y799750D01*
X230517Y800250D01*
X231017Y800667D01*
X231683Y800833D01*
X232267Y800750D01*
X232683Y800583D01*
X233100Y800250D01*
G01X242800Y800833D02*
Y797500D01*
G01Y802167D02*
X242633Y802250D01*
Y802417D01*
X242800Y802500D01*
X242967Y802417D01*
Y802250D01*
X242800Y802167D01*
G01X246983Y797500D02*
Y800833D01*
G01Y800000D02*
X247317Y800417D01*
X247817Y800750D01*
X248483Y800833D01*
X249067Y800750D01*
X249567Y800417D01*
X249817Y799833D01*
Y797500D01*
G01X259600Y802500D02*
Y797500D01*
G01X258433Y800833D02*
X260767D01*
G01X263783Y797500D02*
Y802500D01*
G01Y800083D02*
X264200Y800500D01*
X264617Y800750D01*
X265283Y800833D01*
X265783Y800750D01*
X266367Y800417D01*
X266617Y799917D01*
Y797500D01*
G01X269550Y799750D02*
X272217D01*
X271967Y800333D01*
X271550Y800667D01*
X270967Y800833D01*
X270383Y800750D01*
X269883Y800500D01*
X269550Y799917D01*
X269383Y799417D01*
Y798917D01*
X269550Y798417D01*
X269967Y797917D01*
X270467Y797583D01*
X271050Y797500D01*
X271633Y797667D01*
X272217Y798167D01*
G01X282000Y802500D02*
Y797500D01*
G01X280833Y800833D02*
X283167D01*
G01X289100Y797500D02*
Y800833D01*
G01Y800250D02*
X288767Y800583D01*
X288267Y800750D01*
X287683Y800833D01*
X287100Y800667D01*
X286600Y800333D01*
X286267Y799833D01*
X286100Y799167D01*
X286267Y798500D01*
X286600Y798000D01*
X287100Y797667D01*
X287683Y797500D01*
X288267Y797583D01*
X288767Y797833D01*
X289100Y798167D01*
G01X291700Y797500D02*
Y802500D01*
G01Y800000D02*
X292117Y800500D01*
X292617Y800750D01*
X293117Y800833D01*
X293867Y800667D01*
X294367Y800333D01*
X294700Y799750D01*
Y799083D01*
X294533Y798417D01*
X294200Y797917D01*
X293617Y797583D01*
X293117Y797500D01*
X292617Y797583D01*
X292117Y797833D01*
X291700Y798250D01*
G01X298800Y797500D02*
Y802500D01*
G01X303150Y799750D02*
X305817D01*
X305567Y800333D01*
X305150Y800667D01*
X304567Y800833D01*
X303983Y800750D01*
X303483Y800500D01*
X303150Y799917D01*
X302983Y799417D01*
Y798917D01*
X303150Y798417D01*
X303567Y797917D01*
X304067Y797583D01*
X304650Y797500D01*
X305233Y797667D01*
X305817Y798167D01*
G01X310000Y797333D02*
X309833Y797417D01*
Y797583D01*
X310000Y797667D01*
X310167Y797583D01*
Y797417D01*
X310000Y797333D01*
G01Y799583D02*
X309833Y799667D01*
Y799833D01*
X310000Y799917D01*
X310167Y799833D01*
Y799667D01*
X310000Y799583D01*
G01X57833Y806500D02*
Y811500D01*
X59833D01*
X60500Y811250D01*
X61000Y810667D01*
X61167Y810000D01*
X61000Y809333D01*
X60583Y808833D01*
X59833Y808583D01*
X57833D01*
G01X65100Y806500D02*
Y811500D01*
G01X69450Y808750D02*
X72117D01*
X71867Y809333D01*
X71450Y809667D01*
X70867Y809833D01*
X70283Y809750D01*
X69783Y809500D01*
X69450Y808917D01*
X69283Y808417D01*
Y807917D01*
X69450Y807417D01*
X69867Y806917D01*
X70367Y806583D01*
X70950Y806500D01*
X71533Y806667D01*
X72117Y807167D01*
G01X77800Y806500D02*
Y809833D01*
G01Y809250D02*
X77467Y809583D01*
X76967Y809750D01*
X76383Y809833D01*
X75800Y809667D01*
X75300Y809333D01*
X74967Y808833D01*
X74800Y808167D01*
X74967Y807500D01*
X75300Y807000D01*
X75800Y806667D01*
X76383Y806500D01*
X76967Y806583D01*
X77467Y806833D01*
X77800Y807167D01*
G01X80650Y807083D02*
X81067Y806750D01*
X81650Y806500D01*
X82150D01*
X82650Y806667D01*
X82983Y806917D01*
X83150Y807250D01*
X83067Y807750D01*
X82733Y808000D01*
X81233Y808500D01*
X80900Y809083D01*
X81067Y809500D01*
X81400Y809750D01*
X81900Y809833D01*
X82400Y809750D01*
X82900Y809500D01*
G01X86250Y808750D02*
X88917D01*
X88667Y809333D01*
X88250Y809667D01*
X87667Y809833D01*
X87083Y809750D01*
X86583Y809500D01*
X86250Y808917D01*
X86083Y808417D01*
Y807917D01*
X86250Y807417D01*
X86667Y806917D01*
X87167Y806583D01*
X87750Y806500D01*
X88333Y806667D01*
X88917Y807167D01*
G01X98200Y806500D02*
Y810750D01*
X98367Y811167D01*
X98700Y811417D01*
X99200Y811500D01*
X99700Y811333D01*
X99950Y810917D01*
G01X98950Y809500D02*
X97283D01*
G01X104300Y806500D02*
X103800Y806583D01*
X103300Y806917D01*
X102967Y807500D01*
X102800Y808167D01*
X102967Y808833D01*
X103300Y809417D01*
X103800Y809750D01*
X104300Y809833D01*
X104800Y809750D01*
X105300Y809417D01*
X105633Y808833D01*
X105717Y808167D01*
X105633Y807500D01*
X105300Y806917D01*
X104800Y806583D01*
X104300Y806500D01*
G01X109900D02*
Y811500D01*
G01X115500Y806500D02*
Y811500D01*
G01X121100Y806500D02*
X120600Y806583D01*
X120100Y806917D01*
X119767Y807500D01*
X119600Y808167D01*
X119767Y808833D01*
X120100Y809417D01*
X120600Y809750D01*
X121100Y809833D01*
X121600Y809750D01*
X122100Y809417D01*
X122433Y808833D01*
X122517Y808167D01*
X122433Y807500D01*
X122100Y806917D01*
X121600Y806583D01*
X121100Y806500D01*
G01X124617Y809833D02*
X125617Y806500D01*
X126700Y809833D01*
X127783Y806500D01*
X128783Y809833D01*
G01X137900Y811500D02*
Y806500D01*
G01X136733Y809833D02*
X139067D01*
G01X142083Y806500D02*
Y811500D01*
G01Y809083D02*
X142500Y809500D01*
X142917Y809750D01*
X143583Y809833D01*
X144083Y809750D01*
X144667Y809417D01*
X144917Y808917D01*
Y806500D01*
G01X147850Y808750D02*
X150517D01*
X150267Y809333D01*
X149850Y809667D01*
X149267Y809833D01*
X148683Y809750D01*
X148183Y809500D01*
X147850Y808917D01*
X147683Y808417D01*
Y807917D01*
X147850Y807417D01*
X148267Y806917D01*
X148767Y806583D01*
X149350Y806500D01*
X149933Y806667D01*
X150517Y807167D01*
G01X159050Y807083D02*
X159467Y806750D01*
X160050Y806500D01*
X160550D01*
X161050Y806667D01*
X161383Y806917D01*
X161550Y807250D01*
X161467Y807750D01*
X161133Y808000D01*
X159633Y808500D01*
X159300Y809083D01*
X159467Y809500D01*
X159800Y809750D01*
X160300Y809833D01*
X160800Y809750D01*
X161300Y809500D01*
G01X164400Y804833D02*
Y809833D01*
G01Y809083D02*
X164817Y809500D01*
X165233Y809750D01*
X165900Y809833D01*
X166483Y809750D01*
X167067Y809333D01*
X167317Y808750D01*
X167400Y808167D01*
X167317Y807583D01*
X167067Y807000D01*
X166567Y806667D01*
X165900Y806500D01*
X165317Y806583D01*
X164733Y806833D01*
X164400Y807167D01*
G01X170250Y808750D02*
X172917D01*
X172667Y809333D01*
X172250Y809667D01*
X171667Y809833D01*
X171083Y809750D01*
X170583Y809500D01*
X170250Y808917D01*
X170083Y808417D01*
Y807917D01*
X170250Y807417D01*
X170667Y806917D01*
X171167Y806583D01*
X171750Y806500D01*
X172333Y806667D01*
X172917Y807167D01*
G01X178433Y809417D02*
X177850Y809750D01*
X177350Y809833D01*
X176683Y809667D01*
X176183Y809333D01*
X175850Y808750D01*
X175767Y808167D01*
X175850Y807583D01*
X176183Y807083D01*
X176683Y806667D01*
X177350Y806500D01*
X177933Y806667D01*
X178433Y807000D01*
G01X182700Y809833D02*
Y806500D01*
G01Y811167D02*
X182533Y811250D01*
Y811417D01*
X182700Y811500D01*
X182867Y811417D01*
Y811250D01*
X182700Y811167D01*
G01X187800Y806500D02*
Y810750D01*
X187967Y811167D01*
X188300Y811417D01*
X188800Y811500D01*
X189300Y811333D01*
X189550Y810917D01*
G01X188550Y809500D02*
X186883D01*
G01X193900Y809833D02*
Y806500D01*
G01Y811167D02*
X193733Y811250D01*
Y811417D01*
X193900Y811500D01*
X194067Y811417D01*
Y811250D01*
X193900Y811167D01*
G01X200833Y809417D02*
X200250Y809750D01*
X199750Y809833D01*
X199083Y809667D01*
X198583Y809333D01*
X198250Y808750D01*
X198167Y808167D01*
X198250Y807583D01*
X198583Y807083D01*
X199083Y806667D01*
X199750Y806500D01*
X200333Y806667D01*
X200833Y807000D01*
G01X206600Y806500D02*
Y809833D01*
G01Y809250D02*
X206267Y809583D01*
X205767Y809750D01*
X205183Y809833D01*
X204600Y809667D01*
X204100Y809333D01*
X203767Y808833D01*
X203600Y808167D01*
X203767Y807500D01*
X204100Y807000D01*
X204600Y806667D01*
X205183Y806500D01*
X205767Y806583D01*
X206267Y806833D01*
X206600Y807167D01*
G01X210700Y811500D02*
Y806500D01*
G01X209533Y809833D02*
X211867D01*
G01X216300D02*
Y806500D01*
G01Y811167D02*
X216133Y811250D01*
Y811417D01*
X216300Y811500D01*
X216467Y811417D01*
Y811250D01*
X216300Y811167D01*
G01X221900Y806500D02*
X221400Y806583D01*
X220900Y806917D01*
X220567Y807500D01*
X220400Y808167D01*
X220567Y808833D01*
X220900Y809417D01*
X221400Y809750D01*
X221900Y809833D01*
X222400Y809750D01*
X222900Y809417D01*
X223233Y808833D01*
X223317Y808167D01*
X223233Y807500D01*
X222900Y806917D01*
X222400Y806583D01*
X221900Y806500D01*
G01X226083D02*
Y809833D01*
G01Y809000D02*
X226417Y809417D01*
X226917Y809750D01*
X227583Y809833D01*
X228167Y809750D01*
X228667Y809417D01*
X228917Y808833D01*
Y806500D01*
G01X240200Y811500D02*
Y806500D01*
G01Y807250D02*
X239867Y806833D01*
X239367Y806583D01*
X238783Y806500D01*
X238117Y806667D01*
X237617Y807083D01*
X237283Y807583D01*
X237200Y808167D01*
X237283Y808750D01*
X237617Y809250D01*
X238117Y809667D01*
X238783Y809833D01*
X239367Y809750D01*
X239783Y809583D01*
X240200Y809250D01*
G01X244300Y806500D02*
X243800Y806583D01*
X243300Y806917D01*
X242967Y807500D01*
X242800Y808167D01*
X242967Y808833D01*
X243300Y809417D01*
X243800Y809750D01*
X244300Y809833D01*
X244800Y809750D01*
X245300Y809417D01*
X245633Y808833D01*
X245717Y808167D01*
X245633Y807500D01*
X245300Y806917D01*
X244800Y806583D01*
X244300Y806500D01*
G01X251233Y809417D02*
X250650Y809750D01*
X250150Y809833D01*
X249483Y809667D01*
X248983Y809333D01*
X248650Y808750D01*
X248567Y808167D01*
X248650Y807583D01*
X248983Y807083D01*
X249483Y806667D01*
X250150Y806500D01*
X250733Y806667D01*
X251233Y807000D01*
G01X254083Y809833D02*
Y807500D01*
X254417Y806917D01*
X254917Y806583D01*
X255500Y806500D01*
X256083Y806583D01*
X256583Y806917D01*
X256917Y807500D01*
G01Y806500D02*
Y809833D01*
G01X258600Y806500D02*
Y809833D01*
G01Y808917D02*
X258850Y809333D01*
X259267Y809667D01*
X259850Y809833D01*
X260433Y809667D01*
X260850Y809333D01*
X261100Y808917D01*
Y806500D01*
G01Y808917D02*
X261350Y809333D01*
X261767Y809667D01*
X262350Y809833D01*
X262933Y809667D01*
X263350Y809333D01*
X263600Y808833D01*
Y806500D01*
G01X265450Y808750D02*
X268117D01*
X267867Y809333D01*
X267450Y809667D01*
X266867Y809833D01*
X266283Y809750D01*
X265783Y809500D01*
X265450Y808917D01*
X265283Y808417D01*
Y807917D01*
X265450Y807417D01*
X265867Y806917D01*
X266367Y806583D01*
X266950Y806500D01*
X267533Y806667D01*
X268117Y807167D01*
G01X270883Y806500D02*
Y809833D01*
G01Y809000D02*
X271217Y809417D01*
X271717Y809750D01*
X272383Y809833D01*
X272967Y809750D01*
X273467Y809417D01*
X273717Y808833D01*
Y806500D01*
G01X277900Y811500D02*
Y806500D01*
G01X276733Y809833D02*
X279067D01*
G01X282250Y807083D02*
X282667Y806750D01*
X283250Y806500D01*
X283750D01*
X284250Y806667D01*
X284583Y806917D01*
X284750Y807250D01*
X284667Y807750D01*
X284333Y808000D01*
X282833Y808500D01*
X282500Y809083D01*
X282667Y809500D01*
X283000Y809750D01*
X283500Y809833D01*
X284000Y809750D01*
X284500Y809500D01*
G01X294700Y809833D02*
Y806500D01*
G01Y811167D02*
X294533Y811250D01*
Y811417D01*
X294700Y811500D01*
X294867Y811417D01*
Y811250D01*
X294700Y811167D01*
G01X298883Y806500D02*
Y809833D01*
G01Y809000D02*
X299217Y809417D01*
X299717Y809750D01*
X300383Y809833D01*
X300967Y809750D01*
X301467Y809417D01*
X301717Y808833D01*
Y806500D01*
G01X312833Y809417D02*
X312250Y809750D01*
X311750Y809833D01*
X311083Y809667D01*
X310583Y809333D01*
X310250Y808750D01*
X310167Y808167D01*
X310250Y807583D01*
X310583Y807083D01*
X311083Y806667D01*
X311750Y806500D01*
X312333Y806667D01*
X312833Y807000D01*
G01X317100Y806500D02*
Y811500D01*
G01X324200Y806500D02*
Y809833D01*
G01Y809250D02*
X323867Y809583D01*
X323367Y809750D01*
X322783Y809833D01*
X322200Y809667D01*
X321700Y809333D01*
X321367Y808833D01*
X321200Y808167D01*
X321367Y807500D01*
X321700Y807000D01*
X322200Y806667D01*
X322783Y806500D01*
X323367Y806583D01*
X323867Y806833D01*
X324200Y807167D01*
G01X327050Y807083D02*
X327467Y806750D01*
X328050Y806500D01*
X328550D01*
X329050Y806667D01*
X329383Y806917D01*
X329550Y807250D01*
X329467Y807750D01*
X329133Y808000D01*
X327633Y808500D01*
X327300Y809083D01*
X327467Y809500D01*
X327800Y809750D01*
X328300Y809833D01*
X328800Y809750D01*
X329300Y809500D01*
G01X332650Y807083D02*
X333067Y806750D01*
X333650Y806500D01*
X334150D01*
X334650Y806667D01*
X334983Y806917D01*
X335150Y807250D01*
X335067Y807750D01*
X334733Y808000D01*
X333233Y808500D01*
X332900Y809083D01*
X333067Y809500D01*
X333400Y809750D01*
X333900Y809833D01*
X334400Y809750D01*
X334900Y809500D01*
G01X343517Y810667D02*
X344017Y811167D01*
X344600Y811417D01*
X345267Y811500D01*
X346100Y811333D01*
X346683Y810917D01*
X346850Y810417D01*
X346767Y809917D01*
X346433Y809500D01*
X344767Y808667D01*
X344017Y808083D01*
X343517Y807250D01*
X343350Y806500D01*
X346850D01*
G01X357800D02*
Y809833D01*
G01Y809250D02*
X357467Y809583D01*
X356967Y809750D01*
X356383Y809833D01*
X355800Y809667D01*
X355300Y809333D01*
X354967Y808833D01*
X354800Y808167D01*
X354967Y807500D01*
X355300Y807000D01*
X355800Y806667D01*
X356383Y806500D01*
X356967Y806583D01*
X357467Y806833D01*
X357800Y807167D01*
G01X360483Y806500D02*
Y809833D01*
G01Y809000D02*
X360817Y809417D01*
X361317Y809750D01*
X361983Y809833D01*
X362567Y809750D01*
X363067Y809417D01*
X363317Y808833D01*
Y806500D01*
G01X369000Y811500D02*
Y806500D01*
G01Y807250D02*
X368667Y806833D01*
X368167Y806583D01*
X367583Y806500D01*
X366917Y806667D01*
X366417Y807083D01*
X366083Y807583D01*
X366000Y808167D01*
X366083Y808750D01*
X366417Y809250D01*
X366917Y809667D01*
X367583Y809833D01*
X368167Y809750D01*
X368583Y809583D01*
X369000Y809250D01*
G01X378700Y811500D02*
Y806500D01*
G01X377533Y809833D02*
X379867D01*
G01X382883Y806500D02*
Y811500D01*
G01Y809083D02*
X383300Y809500D01*
X383717Y809750D01*
X384383Y809833D01*
X384883Y809750D01*
X385467Y809417D01*
X385717Y808917D01*
Y806500D01*
G01X388650Y808750D02*
X391317D01*
X391067Y809333D01*
X390650Y809667D01*
X390067Y809833D01*
X389483Y809750D01*
X388983Y809500D01*
X388650Y808917D01*
X388483Y808417D01*
Y807917D01*
X388650Y807417D01*
X389067Y806917D01*
X389567Y806583D01*
X390150Y806500D01*
X390733Y806667D01*
X391317Y807167D01*
G01X401100Y806500D02*
Y811500D01*
G01X408200Y806500D02*
Y809833D01*
G01Y809250D02*
X407867Y809583D01*
X407367Y809750D01*
X406783Y809833D01*
X406200Y809667D01*
X405700Y809333D01*
X405367Y808833D01*
X405200Y808167D01*
X405367Y807500D01*
X405700Y807000D01*
X406200Y806667D01*
X406783Y806500D01*
X407367Y806583D01*
X407867Y806833D01*
X408200Y807167D01*
G01X412300Y811500D02*
Y806500D01*
G01X411133Y809833D02*
X413467D01*
G01X416650Y808750D02*
X419317D01*
X419067Y809333D01*
X418650Y809667D01*
X418067Y809833D01*
X417483Y809750D01*
X416983Y809500D01*
X416650Y808917D01*
X416483Y808417D01*
Y807917D01*
X416650Y807417D01*
X417067Y806917D01*
X417567Y806583D01*
X418150Y806500D01*
X418733Y806667D01*
X419317Y807167D01*
G01X422250Y807083D02*
X422667Y806750D01*
X423250Y806500D01*
X423750D01*
X424250Y806667D01*
X424583Y806917D01*
X424750Y807250D01*
X424667Y807750D01*
X424333Y808000D01*
X422833Y808500D01*
X422500Y809083D01*
X422667Y809500D01*
X423000Y809750D01*
X423500Y809833D01*
X424000Y809750D01*
X424500Y809500D01*
G01X429100Y811500D02*
Y806500D01*
G01X427933Y809833D02*
X430267D01*
G01X438800D02*
X440300Y806500D01*
X441800Y809833D01*
G01X444650Y808750D02*
X447317D01*
X447067Y809333D01*
X446650Y809667D01*
X446067Y809833D01*
X445483Y809750D01*
X444983Y809500D01*
X444650Y808917D01*
X444483Y808417D01*
Y807917D01*
X444650Y807417D01*
X445067Y806917D01*
X445567Y806583D01*
X446150Y806500D01*
X446733Y806667D01*
X447317Y807167D01*
G01X450333Y806500D02*
Y809833D01*
G01Y809167D02*
X450750Y809500D01*
X451167Y809750D01*
X451750Y809833D01*
X452167Y809750D01*
X452667Y809500D01*
G01X455850Y807083D02*
X456267Y806750D01*
X456850Y806500D01*
X457350D01*
X457850Y806667D01*
X458183Y806917D01*
X458350Y807250D01*
X458267Y807750D01*
X457933Y808000D01*
X456433Y808500D01*
X456100Y809083D01*
X456267Y809500D01*
X456600Y809750D01*
X457100Y809833D01*
X457600Y809750D01*
X458100Y809500D01*
G01X462700Y809833D02*
Y806500D01*
G01Y811167D02*
X462533Y811250D01*
Y811417D01*
X462700Y811500D01*
X462867Y811417D01*
Y811250D01*
X462700Y811167D01*
G01X468300Y806500D02*
X467800Y806583D01*
X467300Y806917D01*
X466967Y807500D01*
X466800Y808167D01*
X466967Y808833D01*
X467300Y809417D01*
X467800Y809750D01*
X468300Y809833D01*
X468800Y809750D01*
X469300Y809417D01*
X469633Y808833D01*
X469717Y808167D01*
X469633Y807500D01*
X469300Y806917D01*
X468800Y806583D01*
X468300Y806500D01*
G01X472483D02*
Y809833D01*
G01Y809000D02*
X472817Y809417D01*
X473317Y809750D01*
X473983Y809833D01*
X474567Y809750D01*
X475067Y809417D01*
X475317Y808833D01*
Y806500D01*
G01X485100Y809833D02*
Y806500D01*
G01Y811167D02*
X484933Y811250D01*
Y811417D01*
X485100Y811500D01*
X485267Y811417D01*
Y811250D01*
X485100Y811167D01*
G01X489450Y807083D02*
X489867Y806750D01*
X490450Y806500D01*
X490950D01*
X491450Y806667D01*
X491783Y806917D01*
X491950Y807250D01*
X491867Y807750D01*
X491533Y808000D01*
X490033Y808500D01*
X489700Y809083D01*
X489867Y809500D01*
X490200Y809750D01*
X490700Y809833D01*
X491200Y809750D01*
X491700Y809500D01*
G01X500733Y806500D02*
Y809833D01*
G01Y809167D02*
X501150Y809500D01*
X501567Y809750D01*
X502150Y809833D01*
X502567Y809750D01*
X503067Y809500D01*
G01X506250Y808750D02*
X508917D01*
X508667Y809333D01*
X508250Y809667D01*
X507667Y809833D01*
X507083Y809750D01*
X506583Y809500D01*
X506250Y808917D01*
X506083Y808417D01*
Y807917D01*
X506250Y807417D01*
X506667Y806917D01*
X507167Y806583D01*
X507750Y806500D01*
X508333Y806667D01*
X508917Y807167D01*
G01X514600Y804833D02*
Y809833D01*
G01Y809083D02*
X514183Y809500D01*
X513683Y809750D01*
X513100Y809833D01*
X512600Y809750D01*
X512017Y809333D01*
X511683Y808750D01*
X511600Y808167D01*
X511683Y807583D01*
X512017Y807000D01*
X512600Y806583D01*
X513100Y806500D01*
X513683Y806583D01*
X514183Y806833D01*
X514600Y807250D01*
G01X517283Y809833D02*
Y807500D01*
X517617Y806917D01*
X518117Y806583D01*
X518700Y806500D01*
X519283Y806583D01*
X519783Y806917D01*
X520117Y807500D01*
G01Y806500D02*
Y809833D01*
G01X524300D02*
Y806500D01*
G01Y811167D02*
X524133Y811250D01*
Y811417D01*
X524300Y811500D01*
X524467Y811417D01*
Y811250D01*
X524300Y811167D01*
G01X528733Y806500D02*
Y809833D01*
G01Y809167D02*
X529150Y809500D01*
X529567Y809750D01*
X530150Y809833D01*
X530567Y809750D01*
X531067Y809500D01*
G01X534250Y808750D02*
X536917D01*
X536667Y809333D01*
X536250Y809667D01*
X535667Y809833D01*
X535083Y809750D01*
X534583Y809500D01*
X534250Y808917D01*
X534083Y808417D01*
Y807917D01*
X534250Y807417D01*
X534667Y806917D01*
X535167Y806583D01*
X535750Y806500D01*
X536333Y806667D01*
X536917Y807167D01*
G01X542600Y811500D02*
Y806500D01*
G01Y807250D02*
X542267Y806833D01*
X541767Y806583D01*
X541183Y806500D01*
X540517Y806667D01*
X540017Y807083D01*
X539683Y807583D01*
X539600Y808167D01*
X539683Y808750D01*
X540017Y809250D01*
X540517Y809667D01*
X541183Y809833D01*
X541767Y809750D01*
X542183Y809583D01*
X542600Y809250D01*
G01X546533Y805583D02*
X546867Y806667D01*
G01X67000Y743433D02*
X66833Y743517D01*
Y743683D01*
X67000Y743767D01*
X67167Y743683D01*
Y743517D01*
X67000Y743433D01*
G01X71000Y729600D02*
X73000D01*
G01X72000D02*
Y724600D01*
G01X71000D02*
X73000D01*
G01X75933D02*
Y729600D01*
X77933D01*
X78600Y729350D01*
X79100Y728767D01*
X79267Y728100D01*
X79100Y727433D01*
X78683Y726933D01*
X77933Y726683D01*
X75933D01*
G01X85033Y729183D02*
X84533Y729433D01*
X83950Y729600D01*
X83283D01*
X82533Y729350D01*
X81950Y728933D01*
X81533Y728433D01*
X81200Y727600D01*
X81117Y726850D01*
X81283Y726100D01*
X81533Y725600D01*
X82033Y725100D01*
X82617Y724767D01*
X83200Y724600D01*
X83783D01*
X84367Y724767D01*
X84867Y725017D01*
X85283Y725350D01*
G01X87717Y726267D02*
X89883D01*
G01X92733Y729600D02*
Y724600D01*
X96067D01*
G01X98917Y726267D02*
X101083D01*
G01X105600Y724600D02*
Y729600D01*
X104600Y728600D01*
G01Y724600D02*
X106600D01*
G01X111200Y729600D02*
X110533Y729433D01*
X110033Y729017D01*
X109700Y728517D01*
X109450Y727850D01*
X109367Y727100D01*
X109450Y726350D01*
X109700Y725683D01*
X110033Y725183D01*
X110533Y724767D01*
X111200Y724600D01*
X111867Y724767D01*
X112367Y725183D01*
X112700Y725683D01*
X112950Y726350D01*
X113033Y727100D01*
X112950Y727850D01*
X112700Y728517D01*
X112367Y729017D01*
X111867Y729433D01*
X111200Y729600D01*
G01X115383Y725183D02*
X115967Y724767D01*
X116633Y724600D01*
X117300Y724767D01*
X117883Y725267D01*
X118300Y726017D01*
X118467Y726767D01*
Y727683D01*
X118300Y728433D01*
X117883Y729100D01*
X117383Y729433D01*
X116800Y729600D01*
X116133Y729433D01*
X115633Y729100D01*
X115300Y728600D01*
X115133Y727933D01*
X115300Y727350D01*
X115717Y726767D01*
X116217Y726433D01*
X116800Y726350D01*
X117467Y726517D01*
X117967Y726933D01*
X118467Y727683D01*
G01X126250Y725267D02*
X126917Y724850D01*
X127667Y724600D01*
X128333D01*
X129000Y724850D01*
X129500Y725267D01*
X129750Y725850D01*
X129583Y726433D01*
X129167Y726933D01*
X128417Y727267D01*
X127417Y727433D01*
X126833Y727767D01*
X126583Y728350D01*
X126750Y728933D01*
X127167Y729350D01*
X127750Y729600D01*
X128333D01*
X128917Y729433D01*
X129417Y729017D01*
G01X132100Y722933D02*
Y727933D01*
G01Y727183D02*
X132517Y727600D01*
X132933Y727850D01*
X133600Y727933D01*
X134183Y727850D01*
X134767Y727433D01*
X135017Y726850D01*
X135100Y726267D01*
X135017Y725683D01*
X134767Y725100D01*
X134267Y724767D01*
X133600Y724600D01*
X133017Y724683D01*
X132433Y724933D01*
X132100Y725267D01*
G01X137950Y726850D02*
X140617D01*
X140367Y727433D01*
X139950Y727767D01*
X139367Y727933D01*
X138783Y727850D01*
X138283Y727600D01*
X137950Y727017D01*
X137783Y726517D01*
Y726017D01*
X137950Y725517D01*
X138367Y725017D01*
X138867Y724683D01*
X139450Y724600D01*
X140033Y724767D01*
X140617Y725267D01*
G01X146133Y727517D02*
X145550Y727850D01*
X145050Y727933D01*
X144383Y727767D01*
X143883Y727433D01*
X143550Y726850D01*
X143467Y726267D01*
X143550Y725683D01*
X143883Y725183D01*
X144383Y724767D01*
X145050Y724600D01*
X145633Y724767D01*
X146133Y725100D01*
G01X150400Y727933D02*
Y724600D01*
G01Y729267D02*
X150233Y729350D01*
Y729517D01*
X150400Y729600D01*
X150567Y729517D01*
Y729350D01*
X150400Y729267D01*
G01X155500Y724600D02*
Y728850D01*
X155667Y729267D01*
X156000Y729517D01*
X156500Y729600D01*
X157000Y729433D01*
X157250Y729017D01*
G01X156250Y727600D02*
X154583D01*
G01X161600Y727933D02*
Y724600D01*
G01Y729267D02*
X161433Y729350D01*
Y729517D01*
X161600Y729600D01*
X161767Y729517D01*
Y729350D01*
X161600Y729267D01*
G01X168533Y727517D02*
X167950Y727850D01*
X167450Y727933D01*
X166783Y727767D01*
X166283Y727433D01*
X165950Y726850D01*
X165867Y726267D01*
X165950Y725683D01*
X166283Y725183D01*
X166783Y724767D01*
X167450Y724600D01*
X168033Y724767D01*
X168533Y725100D01*
G01X174300Y724600D02*
Y727933D01*
G01Y727350D02*
X173967Y727683D01*
X173467Y727850D01*
X172883Y727933D01*
X172300Y727767D01*
X171800Y727433D01*
X171467Y726933D01*
X171300Y726267D01*
X171467Y725600D01*
X171800Y725100D01*
X172300Y724767D01*
X172883Y724600D01*
X173467Y724683D01*
X173967Y724933D01*
X174300Y725267D01*
G01X178400Y729600D02*
Y724600D01*
G01X177233Y727933D02*
X179567D01*
G01X184000D02*
Y724600D01*
G01Y729267D02*
X183833Y729350D01*
Y729517D01*
X184000Y729600D01*
X184167Y729517D01*
Y729350D01*
X184000Y729267D01*
G01X189600Y724600D02*
X189100Y724683D01*
X188600Y725017D01*
X188267Y725600D01*
X188100Y726267D01*
X188267Y726933D01*
X188600Y727517D01*
X189100Y727850D01*
X189600Y727933D01*
X190100Y727850D01*
X190600Y727517D01*
X190933Y726933D01*
X191017Y726267D01*
X190933Y725600D01*
X190600Y725017D01*
X190100Y724683D01*
X189600Y724600D01*
G01X193783D02*
Y727933D01*
G01Y727100D02*
X194117Y727517D01*
X194617Y727850D01*
X195283Y727933D01*
X195867Y727850D01*
X196367Y727517D01*
X196617Y726933D01*
Y724600D01*
G01X205900D02*
Y728850D01*
X206067Y729267D01*
X206400Y729517D01*
X206900Y729600D01*
X207400Y729433D01*
X207650Y729017D01*
G01X206650Y727600D02*
X204983D01*
G01X212000Y724600D02*
X211500Y724683D01*
X211000Y725017D01*
X210667Y725600D01*
X210500Y726267D01*
X210667Y726933D01*
X211000Y727517D01*
X211500Y727850D01*
X212000Y727933D01*
X212500Y727850D01*
X213000Y727517D01*
X213333Y726933D01*
X213417Y726267D01*
X213333Y725600D01*
X213000Y725017D01*
X212500Y724683D01*
X212000Y724600D01*
G01X216433D02*
Y727933D01*
G01Y727267D02*
X216850Y727600D01*
X217267Y727850D01*
X217850Y727933D01*
X218267Y727850D01*
X218767Y727600D01*
G01X227133Y724600D02*
Y729600D01*
X229217D01*
X229883Y729350D01*
X230300Y729017D01*
X230467Y728350D01*
X230300Y727683D01*
X229800Y727267D01*
X229217Y727017D01*
X227133D01*
G01X229217D02*
X230467Y724600D01*
G01X233150Y726850D02*
X235817D01*
X235567Y727433D01*
X235150Y727767D01*
X234567Y727933D01*
X233983Y727850D01*
X233483Y727600D01*
X233150Y727017D01*
X232983Y726517D01*
Y726017D01*
X233150Y725517D01*
X233567Y725017D01*
X234067Y724683D01*
X234650Y724600D01*
X235233Y724767D01*
X235817Y725267D01*
G01X238750Y725183D02*
X239167Y724850D01*
X239750Y724600D01*
X240250D01*
X240750Y724767D01*
X241083Y725017D01*
X241250Y725350D01*
X241167Y725850D01*
X240833Y726100D01*
X239333Y726600D01*
X239000Y727183D01*
X239167Y727600D01*
X239500Y727850D01*
X240000Y727933D01*
X240500Y727850D01*
X241000Y727600D01*
G01X245600Y727933D02*
Y724600D01*
G01Y729267D02*
X245433Y729350D01*
Y729517D01*
X245600Y729600D01*
X245767Y729517D01*
Y729350D01*
X245600Y729267D01*
G01X249783Y724600D02*
Y727933D01*
G01Y727100D02*
X250117Y727517D01*
X250617Y727850D01*
X251283Y727933D01*
X251867Y727850D01*
X252367Y727517D01*
X252617Y726933D01*
Y724600D01*
G01X261400Y729600D02*
X263400D01*
G01X262400D02*
Y724600D01*
G01X261400D02*
X263400D01*
G01X265500D02*
Y727933D01*
G01Y727017D02*
X265750Y727433D01*
X266167Y727767D01*
X266750Y727933D01*
X267333Y727767D01*
X267750Y727433D01*
X268000Y727017D01*
Y724600D01*
G01Y727017D02*
X268250Y727433D01*
X268667Y727767D01*
X269250Y727933D01*
X269833Y727767D01*
X270250Y727433D01*
X270500Y726933D01*
Y724600D01*
G01X272100Y722933D02*
Y727933D01*
G01Y727183D02*
X272517Y727600D01*
X272933Y727850D01*
X273600Y727933D01*
X274183Y727850D01*
X274767Y727433D01*
X275017Y726850D01*
X275100Y726267D01*
X275017Y725683D01*
X274767Y725100D01*
X274267Y724767D01*
X273600Y724600D01*
X273017Y724683D01*
X272433Y724933D01*
X272100Y725267D01*
G01X278033Y724600D02*
Y727933D01*
G01Y727267D02*
X278450Y727600D01*
X278867Y727850D01*
X279450Y727933D01*
X279867Y727850D01*
X280367Y727600D01*
G01X283550Y726850D02*
X286217D01*
X285967Y727433D01*
X285550Y727767D01*
X284967Y727933D01*
X284383Y727850D01*
X283883Y727600D01*
X283550Y727017D01*
X283383Y726517D01*
Y726017D01*
X283550Y725517D01*
X283967Y725017D01*
X284467Y724683D01*
X285050Y724600D01*
X285633Y724767D01*
X286217Y725267D01*
G01X289233Y723350D02*
X289817Y723017D01*
X290483Y722933D01*
X291067Y723017D01*
X291567Y723433D01*
X291900Y724017D01*
Y727933D01*
G01Y727267D02*
X291567Y727600D01*
X291067Y727850D01*
X290483Y727933D01*
X289817Y727767D01*
X289400Y727433D01*
X289067Y726850D01*
X288900Y726267D01*
X288983Y725767D01*
X289317Y725183D01*
X289817Y724767D01*
X290483Y724600D01*
X290983Y724683D01*
X291567Y725017D01*
X291900Y725350D01*
G01X294583Y724600D02*
Y727933D01*
G01Y727100D02*
X294917Y727517D01*
X295417Y727850D01*
X296083Y727933D01*
X296667Y727850D01*
X297167Y727517D01*
X297417Y726933D01*
Y724600D01*
G01X303100D02*
Y727933D01*
G01Y727350D02*
X302767Y727683D01*
X302267Y727850D01*
X301683Y727933D01*
X301100Y727767D01*
X300600Y727433D01*
X300267Y726933D01*
X300100Y726267D01*
X300267Y725600D01*
X300600Y725100D01*
X301100Y724767D01*
X301683Y724600D01*
X302267Y724683D01*
X302767Y724933D01*
X303100Y725267D01*
G01X307200Y729600D02*
Y724600D01*
G01X306033Y727933D02*
X308367D01*
G01X311550Y726850D02*
X314217D01*
X313967Y727433D01*
X313550Y727767D01*
X312967Y727933D01*
X312383Y727850D01*
X311883Y727600D01*
X311550Y727017D01*
X311383Y726517D01*
Y726017D01*
X311550Y725517D01*
X311967Y725017D01*
X312467Y724683D01*
X313050Y724600D01*
X313633Y724767D01*
X314217Y725267D01*
G01X319900Y729600D02*
Y724600D01*
G01Y725350D02*
X319567Y724933D01*
X319067Y724683D01*
X318483Y724600D01*
X317817Y724767D01*
X317317Y725183D01*
X316983Y725683D01*
X316900Y726267D01*
X316983Y726850D01*
X317317Y727350D01*
X317817Y727767D01*
X318483Y727933D01*
X319067Y727850D01*
X319483Y727683D01*
X319900Y727350D01*
G01X328017Y724600D02*
Y729600D01*
X331183D01*
G01X330017Y727183D02*
X328017D01*
G01X336700Y724600D02*
Y727933D01*
G01Y727350D02*
X336367Y727683D01*
X335867Y727850D01*
X335283Y727933D01*
X334700Y727767D01*
X334200Y727433D01*
X333867Y726933D01*
X333700Y726267D01*
X333867Y725600D01*
X334200Y725100D01*
X334700Y724767D01*
X335283Y724600D01*
X335867Y724683D01*
X336367Y724933D01*
X336700Y725267D01*
G01X339300Y724600D02*
Y729600D01*
G01Y727100D02*
X339717Y727600D01*
X340217Y727850D01*
X340717Y727933D01*
X341467Y727767D01*
X341967Y727433D01*
X342300Y726850D01*
Y726183D01*
X342133Y725517D01*
X341800Y725017D01*
X341217Y724683D01*
X340717Y724600D01*
X340217Y724683D01*
X339717Y724933D01*
X339300Y725350D01*
G01X345233Y724600D02*
Y727933D01*
G01Y727267D02*
X345650Y727600D01*
X346067Y727850D01*
X346650Y727933D01*
X347067Y727850D01*
X347567Y727600D01*
G01X352000Y727933D02*
Y724600D01*
G01Y729267D02*
X351833Y729350D01*
Y729517D01*
X352000Y729600D01*
X352167Y729517D01*
Y729350D01*
X352000Y729267D01*
G01X358933Y727517D02*
X358350Y727850D01*
X357850Y727933D01*
X357183Y727767D01*
X356683Y727433D01*
X356350Y726850D01*
X356267Y726267D01*
X356350Y725683D01*
X356683Y725183D01*
X357183Y724767D01*
X357850Y724600D01*
X358433Y724767D01*
X358933Y725100D01*
G01X362783Y722933D02*
X361950Y723767D01*
X361533Y724600D01*
Y727933D01*
X361950Y728767D01*
X362783Y729600D01*
G01X367133Y724600D02*
Y729600D01*
X369133D01*
X369800Y729350D01*
X370300Y728767D01*
X370467Y728100D01*
X370300Y727433D01*
X369883Y726933D01*
X369133Y726683D01*
X367133D01*
G01X373233Y724600D02*
Y727933D01*
G01Y727267D02*
X373650Y727600D01*
X374067Y727850D01*
X374650Y727933D01*
X375067Y727850D01*
X375567Y727600D01*
G01X378750Y726850D02*
X381417D01*
X381167Y727433D01*
X380750Y727767D01*
X380167Y727933D01*
X379583Y727850D01*
X379083Y727600D01*
X378750Y727017D01*
X378583Y726517D01*
Y726017D01*
X378750Y725517D01*
X379167Y725017D01*
X379667Y724683D01*
X380250Y724600D01*
X380833Y724767D01*
X381417Y725267D01*
G01X384100Y722933D02*
Y727933D01*
G01Y727183D02*
X384517Y727600D01*
X384933Y727850D01*
X385600Y727933D01*
X386183Y727850D01*
X386767Y727433D01*
X387017Y726850D01*
X387100Y726267D01*
X387017Y725683D01*
X386767Y725100D01*
X386267Y724767D01*
X385600Y724600D01*
X385017Y724683D01*
X384433Y724933D01*
X384100Y725267D01*
G01X390033Y724600D02*
Y727933D01*
G01Y727267D02*
X390450Y727600D01*
X390867Y727850D01*
X391450Y727933D01*
X391867Y727850D01*
X392367Y727600D01*
G01X395550Y726850D02*
X398217D01*
X397967Y727433D01*
X397550Y727767D01*
X396967Y727933D01*
X396383Y727850D01*
X395883Y727600D01*
X395550Y727017D01*
X395383Y726517D01*
Y726017D01*
X395550Y725517D01*
X395967Y725017D01*
X396467Y724683D01*
X397050Y724600D01*
X397633Y724767D01*
X398217Y725267D01*
G01X401233Y723350D02*
X401817Y723017D01*
X402483Y722933D01*
X403067Y723017D01*
X403567Y723433D01*
X403900Y724017D01*
Y727933D01*
G01Y727267D02*
X403567Y727600D01*
X403067Y727850D01*
X402483Y727933D01*
X401817Y727767D01*
X401400Y727433D01*
X401067Y726850D01*
X400900Y726267D01*
X400983Y725767D01*
X401317Y725183D01*
X401817Y724767D01*
X402483Y724600D01*
X402983Y724683D01*
X403567Y725017D01*
X403900Y725350D01*
G01X408417Y722933D02*
X409250Y723767D01*
X409667Y724600D01*
Y727933D01*
X409250Y728767D01*
X408417Y729600D01*
G01X418700Y724600D02*
Y728850D01*
X418867Y729267D01*
X419200Y729517D01*
X419700Y729600D01*
X420200Y729433D01*
X420450Y729017D01*
G01X419450Y727600D02*
X417783D01*
G01X424800Y724600D02*
X424300Y724683D01*
X423800Y725017D01*
X423467Y725600D01*
X423300Y726267D01*
X423467Y726933D01*
X423800Y727517D01*
X424300Y727850D01*
X424800Y727933D01*
X425300Y727850D01*
X425800Y727517D01*
X426133Y726933D01*
X426217Y726267D01*
X426133Y725600D01*
X425800Y725017D01*
X425300Y724683D01*
X424800Y724600D01*
G01X429233D02*
Y727933D01*
G01Y727267D02*
X429650Y727600D01*
X430067Y727850D01*
X430650Y727933D01*
X431067Y727850D01*
X431567Y727600D01*
G01X439433Y724600D02*
Y729600D01*
X441600Y725433D01*
X443767Y729600D01*
Y724600D01*
G01X445783Y727933D02*
Y725600D01*
X446117Y725017D01*
X446617Y724683D01*
X447200Y724600D01*
X447783Y724683D01*
X448283Y725017D01*
X448617Y725600D01*
G01Y724600D02*
Y727933D01*
G01X452800Y724600D02*
Y729600D01*
G01X458400D02*
Y724600D01*
G01X457233Y727933D02*
X459567D01*
G01X464000D02*
Y724600D01*
G01Y729267D02*
X463833Y729350D01*
Y729517D01*
X464000Y729600D01*
X464167Y729517D01*
Y729350D01*
X464000Y729267D01*
G01X469600Y724600D02*
Y729600D01*
G01X476700Y724600D02*
Y727933D01*
G01Y727350D02*
X476367Y727683D01*
X475867Y727850D01*
X475283Y727933D01*
X474700Y727767D01*
X474200Y727433D01*
X473867Y726933D01*
X473700Y726267D01*
X473867Y725600D01*
X474200Y725100D01*
X474700Y724767D01*
X475283Y724600D01*
X475867Y724683D01*
X476367Y724933D01*
X476700Y725267D01*
G01X479050Y723100D02*
X479550Y722933D01*
X480217Y723100D01*
X480633Y723433D01*
X480967Y723850D01*
X481467Y725183D01*
X482550Y727933D01*
G01X479883D02*
X481467Y725183D01*
G01X485150Y726850D02*
X487817D01*
X487567Y727433D01*
X487150Y727767D01*
X486567Y727933D01*
X485983Y727850D01*
X485483Y727600D01*
X485150Y727017D01*
X484983Y726517D01*
Y726017D01*
X485150Y725517D01*
X485567Y725017D01*
X486067Y724683D01*
X486650Y724600D01*
X487233Y724767D01*
X487817Y725267D01*
G01X490833Y724600D02*
Y727933D01*
G01Y727267D02*
X491250Y727600D01*
X491667Y727850D01*
X492250Y727933D01*
X492667Y727850D01*
X493167Y727600D01*
G01X501533Y724600D02*
Y729600D01*
X503533D01*
X504200Y729350D01*
X504700Y728767D01*
X504867Y728100D01*
X504700Y727433D01*
X504283Y726933D01*
X503533Y726683D01*
X501533D01*
G01X507633Y724600D02*
Y727933D01*
G01Y727267D02*
X508050Y727600D01*
X508467Y727850D01*
X509050Y727933D01*
X509467Y727850D01*
X509967Y727600D01*
G01X514400Y727933D02*
Y724600D01*
G01Y729267D02*
X514233Y729350D01*
Y729517D01*
X514400Y729600D01*
X514567Y729517D01*
Y729350D01*
X514400Y729267D01*
G01X518583Y724600D02*
Y727933D01*
G01Y727100D02*
X518917Y727517D01*
X519417Y727850D01*
X520083Y727933D01*
X520667Y727850D01*
X521167Y727517D01*
X521417Y726933D01*
Y724600D01*
G01X525600Y729600D02*
Y724600D01*
G01X524433Y727933D02*
X526767D01*
G01X529950Y726850D02*
X532617D01*
X532367Y727433D01*
X531950Y727767D01*
X531367Y727933D01*
X530783Y727850D01*
X530283Y727600D01*
X529950Y727017D01*
X529783Y726517D01*
Y726017D01*
X529950Y725517D01*
X530367Y725017D01*
X530867Y724683D01*
X531450Y724600D01*
X532033Y724767D01*
X532617Y725267D01*
G01X538300Y729600D02*
Y724600D01*
G01Y725350D02*
X537967Y724933D01*
X537467Y724683D01*
X536883Y724600D01*
X536217Y724767D01*
X535717Y725183D01*
X535383Y725683D01*
X535300Y726267D01*
X535383Y726850D01*
X535717Y727350D01*
X536217Y727767D01*
X536883Y727933D01*
X537467Y727850D01*
X537883Y727683D01*
X538300Y727350D01*
G01X548667Y727267D02*
X549000Y727517D01*
X549250Y727933D01*
X549417Y728517D01*
X549250Y729017D01*
X548917Y729350D01*
X548333Y729600D01*
X546083D01*
Y724600D01*
X548833D01*
X549417Y724933D01*
X549750Y725433D01*
X549917Y726017D01*
X549750Y726600D01*
X549250Y727100D01*
X548667Y727267D01*
X546083D01*
G01X553600Y724600D02*
X553100Y724683D01*
X552600Y725017D01*
X552267Y725600D01*
X552100Y726267D01*
X552267Y726933D01*
X552600Y727517D01*
X553100Y727850D01*
X553600Y727933D01*
X554100Y727850D01*
X554600Y727517D01*
X554933Y726933D01*
X555017Y726267D01*
X554933Y725600D01*
X554600Y725017D01*
X554100Y724683D01*
X553600Y724600D01*
G01X560700D02*
Y727933D01*
G01Y727350D02*
X560367Y727683D01*
X559867Y727850D01*
X559283Y727933D01*
X558700Y727767D01*
X558200Y727433D01*
X557867Y726933D01*
X557700Y726267D01*
X557867Y725600D01*
X558200Y725100D01*
X558700Y724767D01*
X559283Y724600D01*
X559867Y724683D01*
X560367Y724933D01*
X560700Y725267D01*
G01X563633Y724600D02*
Y727933D01*
G01Y727267D02*
X564050Y727600D01*
X564467Y727850D01*
X565050Y727933D01*
X565467Y727850D01*
X565967Y727600D01*
G01X571900Y729600D02*
Y724600D01*
G01Y725350D02*
X571567Y724933D01*
X571067Y724683D01*
X570483Y724600D01*
X569817Y724767D01*
X569317Y725183D01*
X568983Y725683D01*
X568900Y726267D01*
X568983Y726850D01*
X569317Y727350D01*
X569817Y727767D01*
X570483Y727933D01*
X571067Y727850D01*
X571483Y727683D01*
X571900Y727350D01*
G01X574750Y725183D02*
X575167Y724850D01*
X575750Y724600D01*
X576250D01*
X576750Y724767D01*
X577083Y725017D01*
X577250Y725350D01*
X577167Y725850D01*
X576833Y726100D01*
X575333Y726600D01*
X575000Y727183D01*
X575167Y727600D01*
X575500Y727850D01*
X576000Y727933D01*
X576500Y727850D01*
X577000Y727600D01*
G01X71000Y738600D02*
X73000D01*
G01X72000D02*
Y733600D01*
G01X71000D02*
X73000D01*
G01X75933D02*
Y738600D01*
X77933D01*
X78600Y738350D01*
X79100Y737767D01*
X79267Y737100D01*
X79100Y736433D01*
X78683Y735933D01*
X77933Y735683D01*
X75933D01*
G01X85033Y738183D02*
X84533Y738433D01*
X83950Y738600D01*
X83283D01*
X82533Y738350D01*
X81950Y737933D01*
X81533Y737433D01*
X81200Y736600D01*
X81117Y735850D01*
X81283Y735100D01*
X81533Y734600D01*
X82033Y734100D01*
X82617Y733767D01*
X83200Y733600D01*
X83783D01*
X84367Y733767D01*
X84867Y734017D01*
X85283Y734350D01*
G01X87717Y735267D02*
X89883D01*
G01X92233Y733600D02*
Y738600D01*
X94400Y734433D01*
X96567Y738600D01*
Y733600D01*
G01X98417D02*
Y738600D01*
X101583D01*
G01X100417Y736183D02*
X98417D01*
G01X104517Y735267D02*
X106683D01*
G01X111200Y733600D02*
Y738600D01*
X110200Y737600D01*
G01Y733600D02*
X112200D01*
G01X114967Y734350D02*
X115467Y733933D01*
X116050Y733683D01*
X116800Y733600D01*
X117550Y733767D01*
X118133Y734100D01*
X118550Y734683D01*
X118633Y735350D01*
X118467Y736017D01*
X118050Y736433D01*
X117467Y736767D01*
X116883Y736850D01*
X116300Y736767D01*
X115550Y736433D01*
X115800Y738600D01*
X118050D01*
G01X122400D02*
X121733Y738433D01*
X121233Y738017D01*
X120900Y737517D01*
X120650Y736850D01*
X120567Y736100D01*
X120650Y735350D01*
X120900Y734683D01*
X121233Y734183D01*
X121733Y733767D01*
X122400Y733600D01*
X123067Y733767D01*
X123567Y734183D01*
X123900Y734683D01*
X124150Y735350D01*
X124233Y736100D01*
X124150Y736850D01*
X123900Y737517D01*
X123567Y738017D01*
X123067Y738433D01*
X122400Y738600D01*
G01X131433Y733600D02*
Y738600D01*
X133600Y734433D01*
X135767Y738600D01*
Y733600D01*
G01X137950Y735850D02*
X140617D01*
X140367Y736433D01*
X139950Y736767D01*
X139367Y736933D01*
X138783Y736850D01*
X138283Y736600D01*
X137950Y736017D01*
X137783Y735517D01*
Y735017D01*
X137950Y734517D01*
X138367Y734017D01*
X138867Y733683D01*
X139450Y733600D01*
X140033Y733767D01*
X140617Y734267D01*
G01X144800Y738600D02*
Y733600D01*
G01X143633Y736933D02*
X145967D01*
G01X151900Y733600D02*
Y736933D01*
G01Y736350D02*
X151567Y736683D01*
X151067Y736850D01*
X150483Y736933D01*
X149900Y736767D01*
X149400Y736433D01*
X149067Y735933D01*
X148900Y735267D01*
X149067Y734600D01*
X149400Y734100D01*
X149900Y733767D01*
X150483Y733600D01*
X151067Y733683D01*
X151567Y733933D01*
X151900Y734267D01*
G01X156000Y733600D02*
Y738600D01*
G01X165617Y733600D02*
Y738600D01*
X168783D01*
G01X167617Y736183D02*
X165617D01*
G01X172800Y733600D02*
X172300Y733683D01*
X171800Y734017D01*
X171467Y734600D01*
X171300Y735267D01*
X171467Y735933D01*
X171800Y736517D01*
X172300Y736850D01*
X172800Y736933D01*
X173300Y736850D01*
X173800Y736517D01*
X174133Y735933D01*
X174217Y735267D01*
X174133Y734600D01*
X173800Y734017D01*
X173300Y733683D01*
X172800Y733600D01*
G01X178400Y736933D02*
Y733600D01*
G01Y738267D02*
X178233Y738350D01*
Y738517D01*
X178400Y738600D01*
X178567Y738517D01*
Y738350D01*
X178400Y738267D01*
G01X184000Y733600D02*
Y738600D01*
G01X194700Y733600D02*
Y737850D01*
X194867Y738267D01*
X195200Y738517D01*
X195700Y738600D01*
X196200Y738433D01*
X196450Y738017D01*
G01X195450Y736600D02*
X193783D01*
G01X200800Y733600D02*
X200300Y733683D01*
X199800Y734017D01*
X199467Y734600D01*
X199300Y735267D01*
X199467Y735933D01*
X199800Y736517D01*
X200300Y736850D01*
X200800Y736933D01*
X201300Y736850D01*
X201800Y736517D01*
X202133Y735933D01*
X202217Y735267D01*
X202133Y734600D01*
X201800Y734017D01*
X201300Y733683D01*
X200800Y733600D01*
G01X205233D02*
Y736933D01*
G01Y736267D02*
X205650Y736600D01*
X206067Y736850D01*
X206650Y736933D01*
X207067Y736850D01*
X207567Y736600D01*
G01X215933Y733600D02*
Y738600D01*
X217933D01*
X218600Y738350D01*
X219100Y737767D01*
X219267Y737100D01*
X219100Y736433D01*
X218683Y735933D01*
X217933Y735683D01*
X215933D01*
G01X222033Y733600D02*
Y736933D01*
G01Y736267D02*
X222450Y736600D01*
X222867Y736850D01*
X223450Y736933D01*
X223867Y736850D01*
X224367Y736600D01*
G01X228800Y736933D02*
Y733600D01*
G01Y738267D02*
X228633Y738350D01*
Y738517D01*
X228800Y738600D01*
X228967Y738517D01*
Y738350D01*
X228800Y738267D01*
G01X232983Y733600D02*
Y736933D01*
G01Y736100D02*
X233317Y736517D01*
X233817Y736850D01*
X234483Y736933D01*
X235067Y736850D01*
X235567Y736517D01*
X235817Y735933D01*
Y733600D01*
G01X240000Y738600D02*
Y733600D01*
G01X238833Y736933D02*
X241167D01*
G01X244350Y735850D02*
X247017D01*
X246767Y736433D01*
X246350Y736767D01*
X245767Y736933D01*
X245183Y736850D01*
X244683Y736600D01*
X244350Y736017D01*
X244183Y735517D01*
Y735017D01*
X244350Y734517D01*
X244767Y734017D01*
X245267Y733683D01*
X245850Y733600D01*
X246433Y733767D01*
X247017Y734267D01*
G01X252700Y738600D02*
Y733600D01*
G01Y734350D02*
X252367Y733933D01*
X251867Y733683D01*
X251283Y733600D01*
X250617Y733767D01*
X250117Y734183D01*
X249783Y734683D01*
X249700Y735267D01*
X249783Y735850D01*
X250117Y736350D01*
X250617Y736767D01*
X251283Y736933D01*
X251867Y736850D01*
X252283Y736683D01*
X252700Y736350D01*
G01X259900Y738600D02*
X261067Y733600D01*
X262400Y738600D01*
X263733Y733600D01*
X264900Y738600D01*
G01X268000Y736933D02*
Y733600D01*
G01Y738267D02*
X267833Y738350D01*
Y738517D01*
X268000Y738600D01*
X268167Y738517D01*
Y738350D01*
X268000Y738267D01*
G01X272433Y733600D02*
Y736933D01*
G01Y736267D02*
X272850Y736600D01*
X273267Y736850D01*
X273850Y736933D01*
X274267Y736850D01*
X274767Y736600D01*
G01X279200Y736933D02*
Y733600D01*
G01Y738267D02*
X279033Y738350D01*
Y738517D01*
X279200Y738600D01*
X279367Y738517D01*
Y738350D01*
X279200Y738267D01*
G01X283383Y733600D02*
Y736933D01*
G01Y736100D02*
X283717Y736517D01*
X284217Y736850D01*
X284883Y736933D01*
X285467Y736850D01*
X285967Y736517D01*
X286217Y735933D01*
Y733600D01*
G01X289233Y732350D02*
X289817Y732017D01*
X290483Y731933D01*
X291067Y732017D01*
X291567Y732433D01*
X291900Y733017D01*
Y736933D01*
G01Y736267D02*
X291567Y736600D01*
X291067Y736850D01*
X290483Y736933D01*
X289817Y736767D01*
X289400Y736433D01*
X289067Y735850D01*
X288900Y735267D01*
X288983Y734767D01*
X289317Y734183D01*
X289817Y733767D01*
X290483Y733600D01*
X290983Y733683D01*
X291567Y734017D01*
X291900Y734350D01*
G01X299517Y733600D02*
X301600Y738600D01*
X303683Y733600D01*
G01X302933Y735350D02*
X300267D01*
G01X305700Y731933D02*
Y736933D01*
G01Y736183D02*
X306117Y736600D01*
X306533Y736850D01*
X307200Y736933D01*
X307783Y736850D01*
X308367Y736433D01*
X308617Y735850D01*
X308700Y735267D01*
X308617Y734683D01*
X308367Y734100D01*
X307867Y733767D01*
X307200Y733600D01*
X306617Y733683D01*
X306033Y733933D01*
X305700Y734267D01*
G01X311300Y731933D02*
Y736933D01*
G01Y736183D02*
X311717Y736600D01*
X312133Y736850D01*
X312800Y736933D01*
X313383Y736850D01*
X313967Y736433D01*
X314217Y735850D01*
X314300Y735267D01*
X314217Y734683D01*
X313967Y734100D01*
X313467Y733767D01*
X312800Y733600D01*
X312217Y733683D01*
X311633Y733933D01*
X311300Y734267D01*
G01X318400Y733600D02*
Y738600D01*
G01X324000Y736933D02*
Y733600D01*
G01Y738267D02*
X323833Y738350D01*
Y738517D01*
X324000Y738600D01*
X324167Y738517D01*
Y738350D01*
X324000Y738267D01*
G01X330933Y736517D02*
X330350Y736850D01*
X329850Y736933D01*
X329183Y736767D01*
X328683Y736433D01*
X328350Y735850D01*
X328267Y735267D01*
X328350Y734683D01*
X328683Y734183D01*
X329183Y733767D01*
X329850Y733600D01*
X330433Y733767D01*
X330933Y734100D01*
G01X336700Y733600D02*
Y736933D01*
G01Y736350D02*
X336367Y736683D01*
X335867Y736850D01*
X335283Y736933D01*
X334700Y736767D01*
X334200Y736433D01*
X333867Y735933D01*
X333700Y735267D01*
X333867Y734600D01*
X334200Y734100D01*
X334700Y733767D01*
X335283Y733600D01*
X335867Y733683D01*
X336367Y733933D01*
X336700Y734267D01*
G01X340800Y738600D02*
Y733600D01*
G01X339633Y736933D02*
X341967D01*
G01X346400D02*
Y733600D01*
G01Y738267D02*
X346233Y738350D01*
Y738517D01*
X346400Y738600D01*
X346567Y738517D01*
Y738350D01*
X346400Y738267D01*
G01X352000Y733600D02*
X351500Y733683D01*
X351000Y734017D01*
X350667Y734600D01*
X350500Y735267D01*
X350667Y735933D01*
X351000Y736517D01*
X351500Y736850D01*
X352000Y736933D01*
X352500Y736850D01*
X353000Y736517D01*
X353333Y735933D01*
X353417Y735267D01*
X353333Y734600D01*
X353000Y734017D01*
X352500Y733683D01*
X352000Y733600D01*
G01X356183D02*
Y736933D01*
G01Y736100D02*
X356517Y736517D01*
X357017Y736850D01*
X357683Y736933D01*
X358267Y736850D01*
X358767Y736517D01*
X359017Y735933D01*
Y733600D01*
G01X361950Y734183D02*
X362367Y733850D01*
X362950Y733600D01*
X363450D01*
X363950Y733767D01*
X364283Y734017D01*
X364450Y734350D01*
X364367Y734850D01*
X364033Y735100D01*
X362533Y735600D01*
X362200Y736183D01*
X362367Y736600D01*
X362700Y736850D01*
X363200Y736933D01*
X363700Y736850D01*
X364200Y736600D01*
G01X71000Y747600D02*
X73000D01*
G01X72000D02*
Y742600D01*
G01X71000D02*
X73000D01*
G01X75933D02*
Y747600D01*
X77933D01*
X78600Y747350D01*
X79100Y746767D01*
X79267Y746100D01*
X79100Y745433D01*
X78683Y744933D01*
X77933Y744683D01*
X75933D01*
G01X85033Y747183D02*
X84533Y747433D01*
X83950Y747600D01*
X83283D01*
X82533Y747350D01*
X81950Y746933D01*
X81533Y746433D01*
X81200Y745600D01*
X81117Y744850D01*
X81283Y744100D01*
X81533Y743600D01*
X82033Y743100D01*
X82617Y742767D01*
X83200Y742600D01*
X83783D01*
X84367Y742767D01*
X84867Y743017D01*
X85283Y743350D01*
G01X87717Y744267D02*
X89883D01*
G01X95400Y742600D02*
Y747600D01*
X92317Y744017D01*
X96483D01*
G01X100000Y742600D02*
Y747600D01*
X99000Y746600D01*
G01Y742600D02*
X101000D01*
G01X105600Y747600D02*
X104933Y747433D01*
X104433Y747017D01*
X104100Y746517D01*
X103850Y745850D01*
X103767Y745100D01*
X103850Y744350D01*
X104100Y743683D01*
X104433Y743183D01*
X104933Y742767D01*
X105600Y742600D01*
X106267Y742767D01*
X106767Y743183D01*
X107100Y743683D01*
X107350Y744350D01*
X107433Y745100D01*
X107350Y745850D01*
X107100Y746517D01*
X106767Y747017D01*
X106267Y747433D01*
X105600Y747600D01*
G01X111200Y742600D02*
Y747600D01*
X110200Y746600D01*
G01Y742600D02*
X112200D01*
G01X120650Y743267D02*
X121317Y742850D01*
X122067Y742600D01*
X122733D01*
X123400Y742850D01*
X123900Y743267D01*
X124150Y743850D01*
X123983Y744433D01*
X123567Y744933D01*
X122817Y745267D01*
X121817Y745433D01*
X121233Y745767D01*
X120983Y746350D01*
X121150Y746933D01*
X121567Y747350D01*
X122150Y747600D01*
X122733D01*
X123317Y747433D01*
X123817Y747017D01*
G01X126500Y740933D02*
Y745933D01*
G01Y745183D02*
X126917Y745600D01*
X127333Y745850D01*
X128000Y745933D01*
X128583Y745850D01*
X129167Y745433D01*
X129417Y744850D01*
X129500Y744267D01*
X129417Y743683D01*
X129167Y743100D01*
X128667Y742767D01*
X128000Y742600D01*
X127417Y742683D01*
X126833Y742933D01*
X126500Y743267D01*
G01X132350Y744850D02*
X135017D01*
X134767Y745433D01*
X134350Y745767D01*
X133767Y745933D01*
X133183Y745850D01*
X132683Y745600D01*
X132350Y745017D01*
X132183Y744517D01*
Y744017D01*
X132350Y743517D01*
X132767Y743017D01*
X133267Y742683D01*
X133850Y742600D01*
X134433Y742767D01*
X135017Y743267D01*
G01X140533Y745517D02*
X139950Y745850D01*
X139450Y745933D01*
X138783Y745767D01*
X138283Y745433D01*
X137950Y744850D01*
X137867Y744267D01*
X137950Y743683D01*
X138283Y743183D01*
X138783Y742767D01*
X139450Y742600D01*
X140033Y742767D01*
X140533Y743100D01*
G01X144800Y745933D02*
Y742600D01*
G01Y747267D02*
X144633Y747350D01*
Y747517D01*
X144800Y747600D01*
X144967Y747517D01*
Y747350D01*
X144800Y747267D01*
G01X149900Y742600D02*
Y746850D01*
X150067Y747267D01*
X150400Y747517D01*
X150900Y747600D01*
X151400Y747433D01*
X151650Y747017D01*
G01X150650Y745600D02*
X148983D01*
G01X156000Y745933D02*
Y742600D01*
G01Y747267D02*
X155833Y747350D01*
Y747517D01*
X156000Y747600D01*
X156167Y747517D01*
Y747350D01*
X156000Y747267D01*
G01X162933Y745517D02*
X162350Y745850D01*
X161850Y745933D01*
X161183Y745767D01*
X160683Y745433D01*
X160350Y744850D01*
X160267Y744267D01*
X160350Y743683D01*
X160683Y743183D01*
X161183Y742767D01*
X161850Y742600D01*
X162433Y742767D01*
X162933Y743100D01*
G01X168700Y742600D02*
Y745933D01*
G01Y745350D02*
X168367Y745683D01*
X167867Y745850D01*
X167283Y745933D01*
X166700Y745767D01*
X166200Y745433D01*
X165867Y744933D01*
X165700Y744267D01*
X165867Y743600D01*
X166200Y743100D01*
X166700Y742767D01*
X167283Y742600D01*
X167867Y742683D01*
X168367Y742933D01*
X168700Y743267D01*
G01X172800Y747600D02*
Y742600D01*
G01X171633Y745933D02*
X173967D01*
G01X178400D02*
Y742600D01*
G01Y747267D02*
X178233Y747350D01*
Y747517D01*
X178400Y747600D01*
X178567Y747517D01*
Y747350D01*
X178400Y747267D01*
G01X184000Y742600D02*
X183500Y742683D01*
X183000Y743017D01*
X182667Y743600D01*
X182500Y744267D01*
X182667Y744933D01*
X183000Y745517D01*
X183500Y745850D01*
X184000Y745933D01*
X184500Y745850D01*
X185000Y745517D01*
X185333Y744933D01*
X185417Y744267D01*
X185333Y743600D01*
X185000Y743017D01*
X184500Y742683D01*
X184000Y742600D01*
G01X188183D02*
Y745933D01*
G01Y745100D02*
X188517Y745517D01*
X189017Y745850D01*
X189683Y745933D01*
X190267Y745850D01*
X190767Y745517D01*
X191017Y744933D01*
Y742600D01*
G01X200300D02*
Y746850D01*
X200467Y747267D01*
X200800Y747517D01*
X201300Y747600D01*
X201800Y747433D01*
X202050Y747017D01*
G01X201050Y745600D02*
X199383D01*
G01X206400Y742600D02*
X205900Y742683D01*
X205400Y743017D01*
X205067Y743600D01*
X204900Y744267D01*
X205067Y744933D01*
X205400Y745517D01*
X205900Y745850D01*
X206400Y745933D01*
X206900Y745850D01*
X207400Y745517D01*
X207733Y744933D01*
X207817Y744267D01*
X207733Y743600D01*
X207400Y743017D01*
X206900Y742683D01*
X206400Y742600D01*
G01X210833D02*
Y745933D01*
G01Y745267D02*
X211250Y745600D01*
X211667Y745850D01*
X212250Y745933D01*
X212667Y745850D01*
X213167Y745600D01*
G01X223867Y745267D02*
X224200Y745517D01*
X224450Y745933D01*
X224617Y746517D01*
X224450Y747017D01*
X224117Y747350D01*
X223533Y747600D01*
X221283D01*
Y742600D01*
X224033D01*
X224617Y742933D01*
X224950Y743433D01*
X225117Y744017D01*
X224950Y744600D01*
X224450Y745100D01*
X223867Y745267D01*
X221283D01*
G01X230300Y742600D02*
Y745933D01*
G01Y745350D02*
X229967Y745683D01*
X229467Y745850D01*
X228883Y745933D01*
X228300Y745767D01*
X227800Y745433D01*
X227467Y744933D01*
X227300Y744267D01*
X227467Y743600D01*
X227800Y743100D01*
X228300Y742767D01*
X228883Y742600D01*
X229467Y742683D01*
X229967Y742933D01*
X230300Y743267D01*
G01X233150Y743183D02*
X233567Y742850D01*
X234150Y742600D01*
X234650D01*
X235150Y742767D01*
X235483Y743017D01*
X235650Y743350D01*
X235567Y743850D01*
X235233Y744100D01*
X233733Y744600D01*
X233400Y745183D01*
X233567Y745600D01*
X233900Y745850D01*
X234400Y745933D01*
X234900Y745850D01*
X235400Y745600D01*
G01X238750Y744850D02*
X241417D01*
X241167Y745433D01*
X240750Y745767D01*
X240167Y745933D01*
X239583Y745850D01*
X239083Y745600D01*
X238750Y745017D01*
X238583Y744517D01*
Y744017D01*
X238750Y743517D01*
X239167Y743017D01*
X239667Y742683D01*
X240250Y742600D01*
X240833Y742767D01*
X241417Y743267D01*
G01X249033Y742600D02*
Y747600D01*
X251200Y743433D01*
X253367Y747600D01*
Y742600D01*
G01X258300D02*
Y745933D01*
G01Y745350D02*
X257967Y745683D01*
X257467Y745850D01*
X256883Y745933D01*
X256300Y745767D01*
X255800Y745433D01*
X255467Y744933D01*
X255300Y744267D01*
X255467Y743600D01*
X255800Y743100D01*
X256300Y742767D01*
X256883Y742600D01*
X257467Y742683D01*
X257967Y742933D01*
X258300Y743267D01*
G01X262400Y747600D02*
Y742600D01*
G01X261233Y745933D02*
X263567D01*
G01X266750Y744850D02*
X269417D01*
X269167Y745433D01*
X268750Y745767D01*
X268167Y745933D01*
X267583Y745850D01*
X267083Y745600D01*
X266750Y745017D01*
X266583Y744517D01*
Y744017D01*
X266750Y743517D01*
X267167Y743017D01*
X267667Y742683D01*
X268250Y742600D01*
X268833Y742767D01*
X269417Y743267D01*
G01X272433Y742600D02*
Y745933D01*
G01Y745267D02*
X272850Y745600D01*
X273267Y745850D01*
X273850Y745933D01*
X274267Y745850D01*
X274767Y745600D01*
G01X279200Y745933D02*
Y742600D01*
G01Y747267D02*
X279033Y747350D01*
Y747517D01*
X279200Y747600D01*
X279367Y747517D01*
Y747350D01*
X279200Y747267D01*
G01X286300Y742600D02*
Y745933D01*
G01Y745350D02*
X285967Y745683D01*
X285467Y745850D01*
X284883Y745933D01*
X284300Y745767D01*
X283800Y745433D01*
X283467Y744933D01*
X283300Y744267D01*
X283467Y743600D01*
X283800Y743100D01*
X284300Y742767D01*
X284883Y742600D01*
X285467Y742683D01*
X285967Y742933D01*
X286300Y743267D01*
G01X290400Y742600D02*
Y747600D01*
G01X294750Y743183D02*
X295167Y742850D01*
X295750Y742600D01*
X296250D01*
X296750Y742767D01*
X297083Y743017D01*
X297250Y743350D01*
X297167Y743850D01*
X296833Y744100D01*
X295333Y744600D01*
X295000Y745183D01*
X295167Y745600D01*
X295500Y745850D01*
X296000Y745933D01*
X296500Y745850D01*
X297000Y745600D01*
G01X306700Y742600D02*
Y746850D01*
X306867Y747267D01*
X307200Y747517D01*
X307700Y747600D01*
X308200Y747433D01*
X308450Y747017D01*
G01X307450Y745600D02*
X305783D01*
G01X312800Y742600D02*
X312300Y742683D01*
X311800Y743017D01*
X311467Y743600D01*
X311300Y744267D01*
X311467Y744933D01*
X311800Y745517D01*
X312300Y745850D01*
X312800Y745933D01*
X313300Y745850D01*
X313800Y745517D01*
X314133Y744933D01*
X314217Y744267D01*
X314133Y743600D01*
X313800Y743017D01*
X313300Y742683D01*
X312800Y742600D01*
G01X317233D02*
Y745933D01*
G01Y745267D02*
X317650Y745600D01*
X318067Y745850D01*
X318650Y745933D01*
X319067Y745850D01*
X319567Y745600D01*
G01X327933Y742600D02*
Y747600D01*
X330017D01*
X330683Y747350D01*
X331100Y747017D01*
X331267Y746350D01*
X331100Y745683D01*
X330600Y745267D01*
X330017Y745017D01*
X327933D01*
G01X330017D02*
X331267Y742600D01*
G01X335200Y745933D02*
Y742600D01*
G01Y747267D02*
X335033Y747350D01*
Y747517D01*
X335200Y747600D01*
X335367Y747517D01*
Y747350D01*
X335200Y747267D01*
G01X339633Y741350D02*
X340217Y741017D01*
X340883Y740933D01*
X341467Y741017D01*
X341967Y741433D01*
X342300Y742017D01*
Y745933D01*
G01Y745267D02*
X341967Y745600D01*
X341467Y745850D01*
X340883Y745933D01*
X340217Y745767D01*
X339800Y745433D01*
X339467Y744850D01*
X339300Y744267D01*
X339383Y743767D01*
X339717Y743183D01*
X340217Y742767D01*
X340883Y742600D01*
X341383Y742683D01*
X341967Y743017D01*
X342300Y743350D01*
G01X346400Y745933D02*
Y742600D01*
G01Y747267D02*
X346233Y747350D01*
Y747517D01*
X346400Y747600D01*
X346567Y747517D01*
Y747350D01*
X346400Y747267D01*
G01X353500Y747600D02*
Y742600D01*
G01Y743350D02*
X353167Y742933D01*
X352667Y742683D01*
X352083Y742600D01*
X351417Y742767D01*
X350917Y743183D01*
X350583Y743683D01*
X350500Y744267D01*
X350583Y744850D01*
X350917Y745350D01*
X351417Y745767D01*
X352083Y745933D01*
X352667Y745850D01*
X353083Y745683D01*
X353500Y745350D01*
G01X364700Y742600D02*
Y745933D01*
G01Y745350D02*
X364367Y745683D01*
X363867Y745850D01*
X363283Y745933D01*
X362700Y745767D01*
X362200Y745433D01*
X361867Y744933D01*
X361700Y744267D01*
X361867Y743600D01*
X362200Y743100D01*
X362700Y742767D01*
X363283Y742600D01*
X363867Y742683D01*
X364367Y742933D01*
X364700Y743267D01*
G01X367383Y742600D02*
Y745933D01*
G01Y745100D02*
X367717Y745517D01*
X368217Y745850D01*
X368883Y745933D01*
X369467Y745850D01*
X369967Y745517D01*
X370217Y744933D01*
Y742600D01*
G01X375900Y747600D02*
Y742600D01*
G01Y743350D02*
X375567Y742933D01*
X375067Y742683D01*
X374483Y742600D01*
X373817Y742767D01*
X373317Y743183D01*
X372983Y743683D01*
X372900Y744267D01*
X372983Y744850D01*
X373317Y745350D01*
X373817Y745767D01*
X374483Y745933D01*
X375067Y745850D01*
X375483Y745683D01*
X375900Y745350D01*
G01X383433Y742600D02*
Y747600D01*
X385600Y743433D01*
X387767Y747600D01*
Y742600D01*
G01X389783Y745933D02*
Y743600D01*
X390117Y743017D01*
X390617Y742683D01*
X391200Y742600D01*
X391783Y742683D01*
X392283Y743017D01*
X392617Y743600D01*
G01Y742600D02*
Y745933D01*
G01X396800Y742600D02*
Y747600D01*
G01X402400D02*
Y742600D01*
G01X401233Y745933D02*
X403567D01*
G01X408000D02*
Y742600D01*
G01Y747267D02*
X407833Y747350D01*
Y747517D01*
X408000Y747600D01*
X408167Y747517D01*
Y747350D01*
X408000Y747267D01*
G01X413600Y742600D02*
Y747600D01*
G01X420700Y742600D02*
Y745933D01*
G01Y745350D02*
X420367Y745683D01*
X419867Y745850D01*
X419283Y745933D01*
X418700Y745767D01*
X418200Y745433D01*
X417867Y744933D01*
X417700Y744267D01*
X417867Y743600D01*
X418200Y743100D01*
X418700Y742767D01*
X419283Y742600D01*
X419867Y742683D01*
X420367Y742933D01*
X420700Y743267D01*
G01X423050Y741100D02*
X423550Y740933D01*
X424217Y741100D01*
X424633Y741433D01*
X424967Y741850D01*
X425467Y743183D01*
X426550Y745933D01*
G01X423883D02*
X425467Y743183D01*
G01X429150Y744850D02*
X431817D01*
X431567Y745433D01*
X431150Y745767D01*
X430567Y745933D01*
X429983Y745850D01*
X429483Y745600D01*
X429150Y745017D01*
X428983Y744517D01*
Y744017D01*
X429150Y743517D01*
X429567Y743017D01*
X430067Y742683D01*
X430650Y742600D01*
X431233Y742767D01*
X431817Y743267D01*
G01X434833Y742600D02*
Y745933D01*
G01Y745267D02*
X435250Y745600D01*
X435667Y745850D01*
X436250Y745933D01*
X436667Y745850D01*
X437167Y745600D01*
G01X445533Y742600D02*
Y747600D01*
X447533D01*
X448200Y747350D01*
X448700Y746767D01*
X448867Y746100D01*
X448700Y745433D01*
X448283Y744933D01*
X447533Y744683D01*
X445533D01*
G01X451633Y742600D02*
Y745933D01*
G01Y745267D02*
X452050Y745600D01*
X452467Y745850D01*
X453050Y745933D01*
X453467Y745850D01*
X453967Y745600D01*
G01X458400Y745933D02*
Y742600D01*
G01Y747267D02*
X458233Y747350D01*
Y747517D01*
X458400Y747600D01*
X458567Y747517D01*
Y747350D01*
X458400Y747267D01*
G01X462583Y742600D02*
Y745933D01*
G01Y745100D02*
X462917Y745517D01*
X463417Y745850D01*
X464083Y745933D01*
X464667Y745850D01*
X465167Y745517D01*
X465417Y744933D01*
Y742600D01*
G01X469600Y747600D02*
Y742600D01*
G01X468433Y745933D02*
X470767D01*
G01X473950Y744850D02*
X476617D01*
X476367Y745433D01*
X475950Y745767D01*
X475367Y745933D01*
X474783Y745850D01*
X474283Y745600D01*
X473950Y745017D01*
X473783Y744517D01*
Y744017D01*
X473950Y743517D01*
X474367Y743017D01*
X474867Y742683D01*
X475450Y742600D01*
X476033Y742767D01*
X476617Y743267D01*
G01X482300Y747600D02*
Y742600D01*
G01Y743350D02*
X481967Y742933D01*
X481467Y742683D01*
X480883Y742600D01*
X480217Y742767D01*
X479717Y743183D01*
X479383Y743683D01*
X479300Y744267D01*
X479383Y744850D01*
X479717Y745350D01*
X480217Y745767D01*
X480883Y745933D01*
X481467Y745850D01*
X481883Y745683D01*
X482300Y745350D01*
G01X492667Y745267D02*
X493000Y745517D01*
X493250Y745933D01*
X493417Y746517D01*
X493250Y747017D01*
X492917Y747350D01*
X492333Y747600D01*
X490083D01*
Y742600D01*
X492833D01*
X493417Y742933D01*
X493750Y743433D01*
X493917Y744017D01*
X493750Y744600D01*
X493250Y745100D01*
X492667Y745267D01*
X490083D01*
G01X497600Y742600D02*
X497100Y742683D01*
X496600Y743017D01*
X496267Y743600D01*
X496100Y744267D01*
X496267Y744933D01*
X496600Y745517D01*
X497100Y745850D01*
X497600Y745933D01*
X498100Y745850D01*
X498600Y745517D01*
X498933Y744933D01*
X499017Y744267D01*
X498933Y743600D01*
X498600Y743017D01*
X498100Y742683D01*
X497600Y742600D01*
G01X504700D02*
Y745933D01*
G01Y745350D02*
X504367Y745683D01*
X503867Y745850D01*
X503283Y745933D01*
X502700Y745767D01*
X502200Y745433D01*
X501867Y744933D01*
X501700Y744267D01*
X501867Y743600D01*
X502200Y743100D01*
X502700Y742767D01*
X503283Y742600D01*
X503867Y742683D01*
X504367Y742933D01*
X504700Y743267D01*
G01X507633Y742600D02*
Y745933D01*
G01Y745267D02*
X508050Y745600D01*
X508467Y745850D01*
X509050Y745933D01*
X509467Y745850D01*
X509967Y745600D01*
G01X515900Y747600D02*
Y742600D01*
G01Y743350D02*
X515567Y742933D01*
X515067Y742683D01*
X514483Y742600D01*
X513817Y742767D01*
X513317Y743183D01*
X512983Y743683D01*
X512900Y744267D01*
X512983Y744850D01*
X513317Y745350D01*
X513817Y745767D01*
X514483Y745933D01*
X515067Y745850D01*
X515483Y745683D01*
X515900Y745350D01*
G01X518750Y743183D02*
X519167Y742850D01*
X519750Y742600D01*
X520250D01*
X520750Y742767D01*
X521083Y743017D01*
X521250Y743350D01*
X521167Y743850D01*
X520833Y744100D01*
X519333Y744600D01*
X519000Y745183D01*
X519167Y745600D01*
X519500Y745850D01*
X520000Y745933D01*
X520500Y745850D01*
X521000Y745600D01*
G01X67000Y734433D02*
X66833Y734517D01*
Y734683D01*
X67000Y734767D01*
X67167Y734683D01*
Y734517D01*
X67000Y734433D01*
G01Y725433D02*
X66833Y725517D01*
Y725683D01*
X67000Y725767D01*
X67167Y725683D01*
Y725517D01*
X67000Y725433D01*
G01Y779433D02*
X66833Y779517D01*
Y779683D01*
X67000Y779767D01*
X67167Y779683D01*
Y779517D01*
X67000Y779433D01*
G01Y770433D02*
X66833Y770517D01*
Y770683D01*
X67000Y770767D01*
X67167Y770683D01*
Y770517D01*
X67000Y770433D01*
G01Y761433D02*
X66833Y761517D01*
Y761683D01*
X67000Y761767D01*
X67167Y761683D01*
Y761517D01*
X67000Y761433D01*
G01Y752433D02*
X66833Y752517D01*
Y752683D01*
X67000Y752767D01*
X67167Y752683D01*
Y752517D01*
X67000Y752433D01*
G01X71000Y756600D02*
X73000D01*
G01X72000D02*
Y751600D01*
G01X71000D02*
X73000D01*
G01X75933D02*
Y756600D01*
X77933D01*
X78600Y756350D01*
X79100Y755767D01*
X79267Y755100D01*
X79100Y754433D01*
X78683Y753933D01*
X77933Y753683D01*
X75933D01*
G01X85033Y756183D02*
X84533Y756433D01*
X83950Y756600D01*
X83283D01*
X82533Y756350D01*
X81950Y755933D01*
X81533Y755433D01*
X81200Y754600D01*
X81117Y753850D01*
X81283Y753100D01*
X81533Y752600D01*
X82033Y752100D01*
X82617Y751767D01*
X83200Y751600D01*
X83783D01*
X84367Y751767D01*
X84867Y752017D01*
X85283Y752350D01*
G01X87717Y753267D02*
X89883D01*
G01X94400Y756600D02*
Y751600D01*
G01X92483Y756600D02*
X96317D01*
G01X97833Y751600D02*
Y756600D01*
X100000Y752433D01*
X102167Y756600D01*
Y751600D01*
G01X104517Y753267D02*
X106683D01*
G01X109617Y753683D02*
X110200Y754267D01*
X110700Y754600D01*
X111367Y754767D01*
X111950Y754600D01*
X112367Y754267D01*
X112700Y753767D01*
X112783Y753183D01*
X112700Y752683D01*
X112367Y752183D01*
X111867Y751767D01*
X111283Y751600D01*
X110617Y751767D01*
X110033Y752267D01*
X109700Y753017D01*
X109617Y753850D01*
X109783Y754933D01*
X110033Y755517D01*
X110450Y756100D01*
X111033Y756517D01*
X111617Y756600D01*
X112200Y756433D01*
X112617Y756017D01*
G01X114967Y752350D02*
X115467Y751933D01*
X116050Y751683D01*
X116800Y751600D01*
X117550Y751767D01*
X118133Y752100D01*
X118550Y752683D01*
X118633Y753350D01*
X118467Y754017D01*
X118050Y754433D01*
X117467Y754767D01*
X116883Y754850D01*
X116300Y754767D01*
X115550Y754433D01*
X115800Y756600D01*
X118050D01*
G01X122400D02*
X121733Y756433D01*
X121233Y756017D01*
X120900Y755517D01*
X120650Y754850D01*
X120567Y754100D01*
X120650Y753350D01*
X120900Y752683D01*
X121233Y752183D01*
X121733Y751767D01*
X122400Y751600D01*
X123067Y751767D01*
X123567Y752183D01*
X123900Y752683D01*
X124150Y753350D01*
X124233Y754100D01*
X124150Y754850D01*
X123900Y755517D01*
X123567Y756017D01*
X123067Y756433D01*
X122400Y756600D01*
G01X133600D02*
Y751600D01*
G01X131683Y756600D02*
X135517D01*
G01X137950Y753850D02*
X140617D01*
X140367Y754433D01*
X139950Y754767D01*
X139367Y754933D01*
X138783Y754850D01*
X138283Y754600D01*
X137950Y754017D01*
X137783Y753517D01*
Y753017D01*
X137950Y752517D01*
X138367Y752017D01*
X138867Y751683D01*
X139450Y751600D01*
X140033Y751767D01*
X140617Y752267D01*
G01X143550Y752183D02*
X143967Y751850D01*
X144550Y751600D01*
X145050D01*
X145550Y751767D01*
X145883Y752017D01*
X146050Y752350D01*
X145967Y752850D01*
X145633Y753100D01*
X144133Y753600D01*
X143800Y754183D01*
X143967Y754600D01*
X144300Y754850D01*
X144800Y754933D01*
X145300Y754850D01*
X145800Y754600D01*
G01X150400Y756600D02*
Y751600D01*
G01X149233Y754933D02*
X151567D01*
G01X159433Y751600D02*
Y756600D01*
X161600Y752433D01*
X163767Y756600D01*
Y751600D01*
G01X165950Y753850D02*
X168617D01*
X168367Y754433D01*
X167950Y754767D01*
X167367Y754933D01*
X166783Y754850D01*
X166283Y754600D01*
X165950Y754017D01*
X165783Y753517D01*
Y753017D01*
X165950Y752517D01*
X166367Y752017D01*
X166867Y751683D01*
X167450Y751600D01*
X168033Y751767D01*
X168617Y752267D01*
G01X172800Y756600D02*
Y751600D01*
G01X171633Y754933D02*
X173967D01*
G01X176983Y751600D02*
Y756600D01*
G01Y754183D02*
X177400Y754600D01*
X177817Y754850D01*
X178483Y754933D01*
X178983Y754850D01*
X179567Y754517D01*
X179817Y754017D01*
Y751600D01*
G01X184000D02*
X183500Y751683D01*
X183000Y752017D01*
X182667Y752600D01*
X182500Y753267D01*
X182667Y753933D01*
X183000Y754517D01*
X183500Y754850D01*
X184000Y754933D01*
X184500Y754850D01*
X185000Y754517D01*
X185333Y753933D01*
X185417Y753267D01*
X185333Y752600D01*
X185000Y752017D01*
X184500Y751683D01*
X184000Y751600D01*
G01X191100Y756600D02*
Y751600D01*
G01Y752350D02*
X190767Y751933D01*
X190267Y751683D01*
X189683Y751600D01*
X189017Y751767D01*
X188517Y752183D01*
X188183Y752683D01*
X188100Y753267D01*
X188183Y753850D01*
X188517Y754350D01*
X189017Y754767D01*
X189683Y754933D01*
X190267Y754850D01*
X190683Y754683D01*
X191100Y754350D01*
G01X193950Y752183D02*
X194367Y751850D01*
X194950Y751600D01*
X195450D01*
X195950Y751767D01*
X196283Y752017D01*
X196450Y752350D01*
X196367Y752850D01*
X196033Y753100D01*
X194533Y753600D01*
X194200Y754183D01*
X194367Y754600D01*
X194700Y754850D01*
X195200Y754933D01*
X195700Y754850D01*
X196200Y754600D01*
G01X204233Y751600D02*
Y756600D01*
X206400Y752433D01*
X208567Y756600D01*
Y751600D01*
G01X213500D02*
Y754933D01*
G01Y754350D02*
X213167Y754683D01*
X212667Y754850D01*
X212083Y754933D01*
X211500Y754767D01*
X211000Y754433D01*
X210667Y753933D01*
X210500Y753267D01*
X210667Y752600D01*
X211000Y752100D01*
X211500Y751767D01*
X212083Y751600D01*
X212667Y751683D01*
X213167Y751933D01*
X213500Y752267D01*
G01X216183Y751600D02*
Y754933D01*
G01Y754100D02*
X216517Y754517D01*
X217017Y754850D01*
X217683Y754933D01*
X218267Y754850D01*
X218767Y754517D01*
X219017Y753933D01*
Y751600D01*
G01X221783Y754933D02*
Y752600D01*
X222117Y752017D01*
X222617Y751683D01*
X223200Y751600D01*
X223783Y751683D01*
X224283Y752017D01*
X224617Y752600D01*
G01Y751600D02*
Y754933D01*
G01X230300Y751600D02*
Y754933D01*
G01Y754350D02*
X229967Y754683D01*
X229467Y754850D01*
X228883Y754933D01*
X228300Y754767D01*
X227800Y754433D01*
X227467Y753933D01*
X227300Y753267D01*
X227467Y752600D01*
X227800Y752100D01*
X228300Y751767D01*
X228883Y751600D01*
X229467Y751683D01*
X229967Y751933D01*
X230300Y752267D01*
G01X234400Y751600D02*
Y756600D01*
G01X71000Y765600D02*
X73000D01*
G01X72000D02*
Y760600D01*
G01X71000D02*
X73000D01*
G01X75933D02*
Y765600D01*
X77933D01*
X78600Y765350D01*
X79100Y764767D01*
X79267Y764100D01*
X79100Y763433D01*
X78683Y762933D01*
X77933Y762683D01*
X75933D01*
G01X85033Y765183D02*
X84533Y765433D01*
X83950Y765600D01*
X83283D01*
X82533Y765350D01*
X81950Y764933D01*
X81533Y764433D01*
X81200Y763600D01*
X81117Y762850D01*
X81283Y762100D01*
X81533Y761600D01*
X82033Y761100D01*
X82617Y760767D01*
X83200Y760600D01*
X83783D01*
X84367Y760767D01*
X84867Y761017D01*
X85283Y761350D01*
G01X87717Y762267D02*
X89883D01*
G01X92817Y762683D02*
X93400Y763267D01*
X93900Y763600D01*
X94567Y763767D01*
X95150Y763600D01*
X95567Y763267D01*
X95900Y762767D01*
X95983Y762183D01*
X95900Y761683D01*
X95567Y761183D01*
X95067Y760767D01*
X94483Y760600D01*
X93817Y760767D01*
X93233Y761267D01*
X92900Y762017D01*
X92817Y762850D01*
X92983Y763933D01*
X93233Y764517D01*
X93650Y765100D01*
X94233Y765517D01*
X94817Y765600D01*
X95400Y765433D01*
X95817Y765017D01*
G01X100000Y765600D02*
X99333Y765433D01*
X98833Y765017D01*
X98500Y764517D01*
X98250Y763850D01*
X98167Y763100D01*
X98250Y762350D01*
X98500Y761683D01*
X98833Y761183D01*
X99333Y760767D01*
X100000Y760600D01*
X100667Y760767D01*
X101167Y761183D01*
X101500Y761683D01*
X101750Y762350D01*
X101833Y763100D01*
X101750Y763850D01*
X101500Y764517D01*
X101167Y765017D01*
X100667Y765433D01*
X100000Y765600D01*
G01X105600Y760600D02*
Y765600D01*
X104600Y764600D01*
G01Y760600D02*
X106600D01*
G01X109617Y762683D02*
X110200Y763267D01*
X110700Y763600D01*
X111367Y763767D01*
X111950Y763600D01*
X112367Y763267D01*
X112700Y762767D01*
X112783Y762183D01*
X112700Y761683D01*
X112367Y761183D01*
X111867Y760767D01*
X111283Y760600D01*
X110617Y760767D01*
X110033Y761267D01*
X109700Y762017D01*
X109617Y762850D01*
X109783Y763933D01*
X110033Y764517D01*
X110450Y765100D01*
X111033Y765517D01*
X111617Y765600D01*
X112200Y765433D01*
X112617Y765017D01*
G01X122400Y760600D02*
X121733Y760683D01*
X121150Y761017D01*
X120650Y761517D01*
X120317Y762100D01*
X120150Y762767D01*
Y763433D01*
X120317Y764100D01*
X120650Y764683D01*
X121150Y765183D01*
X121733Y765517D01*
X122400Y765600D01*
X123067Y765517D01*
X123650Y765183D01*
X124150Y764683D01*
X124483Y764100D01*
X124650Y763433D01*
Y762767D01*
X124483Y762100D01*
X124150Y761517D01*
X123650Y761017D01*
X123067Y760683D01*
X122400Y760600D01*
G01X123067Y761933D02*
X124067Y760600D01*
G01X126583Y763933D02*
Y761600D01*
X126917Y761017D01*
X127417Y760683D01*
X128000Y760600D01*
X128583Y760683D01*
X129083Y761017D01*
X129417Y761600D01*
G01Y760600D02*
Y763933D01*
G01X135100Y760600D02*
Y763933D01*
G01Y763350D02*
X134767Y763683D01*
X134267Y763850D01*
X133683Y763933D01*
X133100Y763767D01*
X132600Y763433D01*
X132267Y762933D01*
X132100Y762267D01*
X132267Y761600D01*
X132600Y761100D01*
X133100Y760767D01*
X133683Y760600D01*
X134267Y760683D01*
X134767Y760933D01*
X135100Y761267D01*
G01X139200Y760600D02*
Y765600D01*
G01X144800Y763933D02*
Y760600D01*
G01Y765267D02*
X144633Y765350D01*
Y765517D01*
X144800Y765600D01*
X144967Y765517D01*
Y765350D01*
X144800Y765267D01*
G01X149900Y760600D02*
Y764850D01*
X150067Y765267D01*
X150400Y765517D01*
X150900Y765600D01*
X151400Y765433D01*
X151650Y765017D01*
G01X150650Y763600D02*
X148983D01*
G01X156000Y763933D02*
Y760600D01*
G01Y765267D02*
X155833Y765350D01*
Y765517D01*
X156000Y765600D01*
X156167Y765517D01*
Y765350D01*
X156000Y765267D01*
G01X162933Y763517D02*
X162350Y763850D01*
X161850Y763933D01*
X161183Y763767D01*
X160683Y763433D01*
X160350Y762850D01*
X160267Y762267D01*
X160350Y761683D01*
X160683Y761183D01*
X161183Y760767D01*
X161850Y760600D01*
X162433Y760767D01*
X162933Y761100D01*
G01X168700Y760600D02*
Y763933D01*
G01Y763350D02*
X168367Y763683D01*
X167867Y763850D01*
X167283Y763933D01*
X166700Y763767D01*
X166200Y763433D01*
X165867Y762933D01*
X165700Y762267D01*
X165867Y761600D01*
X166200Y761100D01*
X166700Y760767D01*
X167283Y760600D01*
X167867Y760683D01*
X168367Y760933D01*
X168700Y761267D01*
G01X172800Y765600D02*
Y760600D01*
G01X171633Y763933D02*
X173967D01*
G01X178400D02*
Y760600D01*
G01Y765267D02*
X178233Y765350D01*
Y765517D01*
X178400Y765600D01*
X178567Y765517D01*
Y765350D01*
X178400Y765267D01*
G01X184000Y760600D02*
X183500Y760683D01*
X183000Y761017D01*
X182667Y761600D01*
X182500Y762267D01*
X182667Y762933D01*
X183000Y763517D01*
X183500Y763850D01*
X184000Y763933D01*
X184500Y763850D01*
X185000Y763517D01*
X185333Y762933D01*
X185417Y762267D01*
X185333Y761600D01*
X185000Y761017D01*
X184500Y760683D01*
X184000Y760600D01*
G01X188183D02*
Y763933D01*
G01Y763100D02*
X188517Y763517D01*
X189017Y763850D01*
X189683Y763933D01*
X190267Y763850D01*
X190767Y763517D01*
X191017Y762933D01*
Y760600D01*
G01X203300Y758933D02*
X199133Y763933D01*
Y764767D01*
X199967Y765600D01*
X200800D01*
X201633Y764767D01*
Y763933D01*
X200800Y763100D01*
X199133Y762267D01*
X198300Y761433D01*
Y759767D01*
X199133Y758933D01*
X201633D01*
X203300Y760600D01*
G01X210333D02*
Y765600D01*
X212333D01*
X213000Y765350D01*
X213500Y764767D01*
X213667Y764100D01*
X213500Y763433D01*
X213083Y762933D01*
X212333Y762683D01*
X210333D01*
G01X216350Y762850D02*
X219017D01*
X218767Y763433D01*
X218350Y763767D01*
X217767Y763933D01*
X217183Y763850D01*
X216683Y763600D01*
X216350Y763017D01*
X216183Y762517D01*
Y762017D01*
X216350Y761517D01*
X216767Y761017D01*
X217267Y760683D01*
X217850Y760600D01*
X218433Y760767D01*
X219017Y761267D01*
G01X222033Y760600D02*
Y763933D01*
G01Y763267D02*
X222450Y763600D01*
X222867Y763850D01*
X223450Y763933D01*
X223867Y763850D01*
X224367Y763600D01*
G01X228300Y760600D02*
Y764850D01*
X228467Y765267D01*
X228800Y765517D01*
X229300Y765600D01*
X229800Y765433D01*
X230050Y765017D01*
G01X229050Y763600D02*
X227383D01*
G01X234400Y760600D02*
X233900Y760683D01*
X233400Y761017D01*
X233067Y761600D01*
X232900Y762267D01*
X233067Y762933D01*
X233400Y763517D01*
X233900Y763850D01*
X234400Y763933D01*
X234900Y763850D01*
X235400Y763517D01*
X235733Y762933D01*
X235817Y762267D01*
X235733Y761600D01*
X235400Y761017D01*
X234900Y760683D01*
X234400Y760600D01*
G01X238833D02*
Y763933D01*
G01Y763267D02*
X239250Y763600D01*
X239667Y763850D01*
X240250Y763933D01*
X240667Y763850D01*
X241167Y763600D01*
G01X243100Y760600D02*
Y763933D01*
G01Y763017D02*
X243350Y763433D01*
X243767Y763767D01*
X244350Y763933D01*
X244933Y763767D01*
X245350Y763433D01*
X245600Y763017D01*
Y760600D01*
G01Y763017D02*
X245850Y763433D01*
X246267Y763767D01*
X246850Y763933D01*
X247433Y763767D01*
X247850Y763433D01*
X248100Y762933D01*
Y760600D01*
G01X252700D02*
Y763933D01*
G01Y763350D02*
X252367Y763683D01*
X251867Y763850D01*
X251283Y763933D01*
X250700Y763767D01*
X250200Y763433D01*
X249867Y762933D01*
X249700Y762267D01*
X249867Y761600D01*
X250200Y761100D01*
X250700Y760767D01*
X251283Y760600D01*
X251867Y760683D01*
X252367Y760933D01*
X252700Y761267D01*
G01X255383Y760600D02*
Y763933D01*
G01Y763100D02*
X255717Y763517D01*
X256217Y763850D01*
X256883Y763933D01*
X257467Y763850D01*
X257967Y763517D01*
X258217Y762933D01*
Y760600D01*
G01X263733Y763517D02*
X263150Y763850D01*
X262650Y763933D01*
X261983Y763767D01*
X261483Y763433D01*
X261150Y762850D01*
X261067Y762267D01*
X261150Y761683D01*
X261483Y761183D01*
X261983Y760767D01*
X262650Y760600D01*
X263233Y760767D01*
X263733Y761100D01*
G01X266750Y762850D02*
X269417D01*
X269167Y763433D01*
X268750Y763767D01*
X268167Y763933D01*
X267583Y763850D01*
X267083Y763600D01*
X266750Y763017D01*
X266583Y762517D01*
Y762017D01*
X266750Y761517D01*
X267167Y761017D01*
X267667Y760683D01*
X268250Y760600D01*
X268833Y760767D01*
X269417Y761267D01*
G01X277450D02*
X278117Y760850D01*
X278867Y760600D01*
X279533D01*
X280200Y760850D01*
X280700Y761267D01*
X280950Y761850D01*
X280783Y762433D01*
X280367Y762933D01*
X279617Y763267D01*
X278617Y763433D01*
X278033Y763767D01*
X277783Y764350D01*
X277950Y764933D01*
X278367Y765350D01*
X278950Y765600D01*
X279533D01*
X280117Y765433D01*
X280617Y765017D01*
G01X283300Y758933D02*
Y763933D01*
G01Y763183D02*
X283717Y763600D01*
X284133Y763850D01*
X284800Y763933D01*
X285383Y763850D01*
X285967Y763433D01*
X286217Y762850D01*
X286300Y762267D01*
X286217Y761683D01*
X285967Y761100D01*
X285467Y760767D01*
X284800Y760600D01*
X284217Y760683D01*
X283633Y760933D01*
X283300Y761267D01*
G01X289150Y762850D02*
X291817D01*
X291567Y763433D01*
X291150Y763767D01*
X290567Y763933D01*
X289983Y763850D01*
X289483Y763600D01*
X289150Y763017D01*
X288983Y762517D01*
Y762017D01*
X289150Y761517D01*
X289567Y761017D01*
X290067Y760683D01*
X290650Y760600D01*
X291233Y760767D01*
X291817Y761267D01*
G01X297333Y763517D02*
X296750Y763850D01*
X296250Y763933D01*
X295583Y763767D01*
X295083Y763433D01*
X294750Y762850D01*
X294667Y762267D01*
X294750Y761683D01*
X295083Y761183D01*
X295583Y760767D01*
X296250Y760600D01*
X296833Y760767D01*
X297333Y761100D01*
G01X301600Y763933D02*
Y760600D01*
G01Y765267D02*
X301433Y765350D01*
Y765517D01*
X301600Y765600D01*
X301767Y765517D01*
Y765350D01*
X301600Y765267D01*
G01X306700Y760600D02*
Y764850D01*
X306867Y765267D01*
X307200Y765517D01*
X307700Y765600D01*
X308200Y765433D01*
X308450Y765017D01*
G01X307450Y763600D02*
X305783D01*
G01X312800Y763933D02*
Y760600D01*
G01Y765267D02*
X312633Y765350D01*
Y765517D01*
X312800Y765600D01*
X312967Y765517D01*
Y765350D01*
X312800Y765267D01*
G01X319733Y763517D02*
X319150Y763850D01*
X318650Y763933D01*
X317983Y763767D01*
X317483Y763433D01*
X317150Y762850D01*
X317067Y762267D01*
X317150Y761683D01*
X317483Y761183D01*
X317983Y760767D01*
X318650Y760600D01*
X319233Y760767D01*
X319733Y761100D01*
G01X325500Y760600D02*
Y763933D01*
G01Y763350D02*
X325167Y763683D01*
X324667Y763850D01*
X324083Y763933D01*
X323500Y763767D01*
X323000Y763433D01*
X322667Y762933D01*
X322500Y762267D01*
X322667Y761600D01*
X323000Y761100D01*
X323500Y760767D01*
X324083Y760600D01*
X324667Y760683D01*
X325167Y760933D01*
X325500Y761267D01*
G01X329600Y765600D02*
Y760600D01*
G01X328433Y763933D02*
X330767D01*
G01X335200D02*
Y760600D01*
G01Y765267D02*
X335033Y765350D01*
Y765517D01*
X335200Y765600D01*
X335367Y765517D01*
Y765350D01*
X335200Y765267D01*
G01X340800Y760600D02*
X340300Y760683D01*
X339800Y761017D01*
X339467Y761600D01*
X339300Y762267D01*
X339467Y762933D01*
X339800Y763517D01*
X340300Y763850D01*
X340800Y763933D01*
X341300Y763850D01*
X341800Y763517D01*
X342133Y762933D01*
X342217Y762267D01*
X342133Y761600D01*
X341800Y761017D01*
X341300Y760683D01*
X340800Y760600D01*
G01X344983D02*
Y763933D01*
G01Y763100D02*
X345317Y763517D01*
X345817Y763850D01*
X346483Y763933D01*
X347067Y763850D01*
X347567Y763517D01*
X347817Y762933D01*
Y760600D01*
G01X357100D02*
Y764850D01*
X357267Y765267D01*
X357600Y765517D01*
X358100Y765600D01*
X358600Y765433D01*
X358850Y765017D01*
G01X357850Y763600D02*
X356183D01*
G01X363200Y760600D02*
X362700Y760683D01*
X362200Y761017D01*
X361867Y761600D01*
X361700Y762267D01*
X361867Y762933D01*
X362200Y763517D01*
X362700Y763850D01*
X363200Y763933D01*
X363700Y763850D01*
X364200Y763517D01*
X364533Y762933D01*
X364617Y762267D01*
X364533Y761600D01*
X364200Y761017D01*
X363700Y760683D01*
X363200Y760600D01*
G01X367633D02*
Y763933D01*
G01Y763267D02*
X368050Y763600D01*
X368467Y763850D01*
X369050Y763933D01*
X369467Y763850D01*
X369967Y763600D01*
G01X378250Y760600D02*
Y765600D01*
G01X381750D02*
Y760600D01*
G01Y763100D02*
X378250D01*
G01X385600Y763933D02*
Y760600D01*
G01Y765267D02*
X385433Y765350D01*
Y765517D01*
X385600Y765600D01*
X385767Y765517D01*
Y765350D01*
X385600Y765267D01*
G01X390033Y759350D02*
X390617Y759017D01*
X391283Y758933D01*
X391867Y759017D01*
X392367Y759433D01*
X392700Y760017D01*
Y763933D01*
G01Y763267D02*
X392367Y763600D01*
X391867Y763850D01*
X391283Y763933D01*
X390617Y763767D01*
X390200Y763433D01*
X389867Y762850D01*
X389700Y762267D01*
X389783Y761767D01*
X390117Y761183D01*
X390617Y760767D01*
X391283Y760600D01*
X391783Y760683D01*
X392367Y761017D01*
X392700Y761350D01*
G01X395383Y760600D02*
Y765600D01*
G01Y763183D02*
X395800Y763600D01*
X396217Y763850D01*
X396883Y763933D01*
X397383Y763850D01*
X397967Y763517D01*
X398217Y763017D01*
Y760600D01*
G01X406167D02*
Y765600D01*
X407833D01*
X408500Y765350D01*
X409000Y765017D01*
X409417Y764517D01*
X409750Y763933D01*
X409833Y763100D01*
X409750Y762267D01*
X409417Y761683D01*
X409000Y761183D01*
X408500Y760850D01*
X407833Y760600D01*
X406167D01*
G01X412350Y762850D02*
X415017D01*
X414767Y763433D01*
X414350Y763767D01*
X413767Y763933D01*
X413183Y763850D01*
X412683Y763600D01*
X412350Y763017D01*
X412183Y762517D01*
Y762017D01*
X412350Y761517D01*
X412767Y761017D01*
X413267Y760683D01*
X413850Y760600D01*
X414433Y760767D01*
X415017Y761267D01*
G01X417783Y760600D02*
Y763933D01*
G01Y763100D02*
X418117Y763517D01*
X418617Y763850D01*
X419283Y763933D01*
X419867Y763850D01*
X420367Y763517D01*
X420617Y762933D01*
Y760600D01*
G01X423550Y761183D02*
X423967Y760850D01*
X424550Y760600D01*
X425050D01*
X425550Y760767D01*
X425883Y761017D01*
X426050Y761350D01*
X425967Y761850D01*
X425633Y762100D01*
X424133Y762600D01*
X423800Y763183D01*
X423967Y763600D01*
X424300Y763850D01*
X424800Y763933D01*
X425300Y763850D01*
X425800Y763600D01*
G01X430400Y763933D02*
Y760600D01*
G01Y765267D02*
X430233Y765350D01*
Y765517D01*
X430400Y765600D01*
X430567Y765517D01*
Y765350D01*
X430400Y765267D01*
G01X436000Y765600D02*
Y760600D01*
G01X434833Y763933D02*
X437167D01*
G01X439850Y759100D02*
X440350Y758933D01*
X441017Y759100D01*
X441433Y759433D01*
X441767Y759850D01*
X442267Y761183D01*
X443350Y763933D01*
G01X440683D02*
X442267Y761183D01*
G01X451800Y765600D02*
X453800D01*
G01X452800D02*
Y760600D01*
G01X451800D02*
X453800D01*
G01X456983D02*
Y763933D01*
G01Y763100D02*
X457317Y763517D01*
X457817Y763850D01*
X458483Y763933D01*
X459067Y763850D01*
X459567Y763517D01*
X459817Y762933D01*
Y760600D01*
G01X464000Y765600D02*
Y760600D01*
G01X462833Y763933D02*
X465167D01*
G01X468350Y762850D02*
X471017D01*
X470767Y763433D01*
X470350Y763767D01*
X469767Y763933D01*
X469183Y763850D01*
X468683Y763600D01*
X468350Y763017D01*
X468183Y762517D01*
Y762017D01*
X468350Y761517D01*
X468767Y761017D01*
X469267Y760683D01*
X469850Y760600D01*
X470433Y760767D01*
X471017Y761267D01*
G01X474033Y760600D02*
Y763933D01*
G01Y763267D02*
X474450Y763600D01*
X474867Y763850D01*
X475450Y763933D01*
X475867Y763850D01*
X476367Y763600D01*
G01X482133Y763517D02*
X481550Y763850D01*
X481050Y763933D01*
X480383Y763767D01*
X479883Y763433D01*
X479550Y762850D01*
X479467Y762267D01*
X479550Y761683D01*
X479883Y761183D01*
X480383Y760767D01*
X481050Y760600D01*
X481633Y760767D01*
X482133Y761100D01*
G01X486400Y760600D02*
X485900Y760683D01*
X485400Y761017D01*
X485067Y761600D01*
X484900Y762267D01*
X485067Y762933D01*
X485400Y763517D01*
X485900Y763850D01*
X486400Y763933D01*
X486900Y763850D01*
X487400Y763517D01*
X487733Y762933D01*
X487817Y762267D01*
X487733Y761600D01*
X487400Y761017D01*
X486900Y760683D01*
X486400Y760600D01*
G01X490583D02*
Y763933D01*
G01Y763100D02*
X490917Y763517D01*
X491417Y763850D01*
X492083Y763933D01*
X492667Y763850D01*
X493167Y763517D01*
X493417Y762933D01*
Y760600D01*
G01X496183D02*
Y763933D01*
G01Y763100D02*
X496517Y763517D01*
X497017Y763850D01*
X497683Y763933D01*
X498267Y763850D01*
X498767Y763517D01*
X499017Y762933D01*
Y760600D01*
G01X501950Y762850D02*
X504617D01*
X504367Y763433D01*
X503950Y763767D01*
X503367Y763933D01*
X502783Y763850D01*
X502283Y763600D01*
X501950Y763017D01*
X501783Y762517D01*
Y762017D01*
X501950Y761517D01*
X502367Y761017D01*
X502867Y760683D01*
X503450Y760600D01*
X504033Y760767D01*
X504617Y761267D01*
G01X510133Y763517D02*
X509550Y763850D01*
X509050Y763933D01*
X508383Y763767D01*
X507883Y763433D01*
X507550Y762850D01*
X507467Y762267D01*
X507550Y761683D01*
X507883Y761183D01*
X508383Y760767D01*
X509050Y760600D01*
X509633Y760767D01*
X510133Y761100D01*
G01X514400Y765600D02*
Y760600D01*
G01X513233Y763933D02*
X515567D01*
G01X519583Y758933D02*
X518750Y759767D01*
X518333Y760600D01*
Y763933D01*
X518750Y764767D01*
X519583Y765600D01*
G01X523850Y760600D02*
Y765600D01*
G01X527350D02*
Y760600D01*
G01Y763100D02*
X523850D01*
G01X529367Y760600D02*
Y765600D01*
X531033D01*
X531700Y765350D01*
X532200Y765017D01*
X532617Y764517D01*
X532950Y763933D01*
X533033Y763100D01*
X532950Y762267D01*
X532617Y761683D01*
X532200Y761183D01*
X531700Y760850D01*
X531033Y760600D01*
X529367D01*
G01X535800Y765600D02*
X537800D01*
G01X536800D02*
Y760600D01*
G01X535800D02*
X537800D01*
G01X542817Y758933D02*
X543650Y759767D01*
X544067Y760600D01*
Y763933D01*
X543650Y764767D01*
X542817Y765600D01*
G01X551933D02*
Y760600D01*
X555267D01*
G01X560700D02*
Y763933D01*
G01Y763350D02*
X560367Y763683D01*
X559867Y763850D01*
X559283Y763933D01*
X558700Y763767D01*
X558200Y763433D01*
X557867Y762933D01*
X557700Y762267D01*
X557867Y761600D01*
X558200Y761100D01*
X558700Y760767D01*
X559283Y760600D01*
X559867Y760683D01*
X560367Y760933D01*
X560700Y761267D01*
G01X563050Y759100D02*
X563550Y758933D01*
X564217Y759100D01*
X564633Y759433D01*
X564967Y759850D01*
X565467Y761183D01*
X566550Y763933D01*
G01X563883D02*
X565467Y761183D01*
G01X569150Y762850D02*
X571817D01*
X571567Y763433D01*
X571150Y763767D01*
X570567Y763933D01*
X569983Y763850D01*
X569483Y763600D01*
X569150Y763017D01*
X568983Y762517D01*
Y762017D01*
X569150Y761517D01*
X569567Y761017D01*
X570067Y760683D01*
X570650Y760600D01*
X571233Y760767D01*
X571817Y761267D01*
G01X574833Y760600D02*
Y763933D01*
G01Y763267D02*
X575250Y763600D01*
X575667Y763850D01*
X576250Y763933D01*
X576667Y763850D01*
X577167Y763600D01*
G01X580350Y761183D02*
X580767Y760850D01*
X581350Y760600D01*
X581850D01*
X582350Y760767D01*
X582683Y761017D01*
X582850Y761350D01*
X582767Y761850D01*
X582433Y762100D01*
X580933Y762600D01*
X580600Y763183D01*
X580767Y763600D01*
X581100Y763850D01*
X581600Y763933D01*
X582100Y763850D01*
X582600Y763600D01*
G01X592800Y760600D02*
X592300Y760683D01*
X591800Y761017D01*
X591467Y761600D01*
X591300Y762267D01*
X591467Y762933D01*
X591800Y763517D01*
X592300Y763850D01*
X592800Y763933D01*
X593300Y763850D01*
X593800Y763517D01*
X594133Y762933D01*
X594217Y762267D01*
X594133Y761600D01*
X593800Y761017D01*
X593300Y760683D01*
X592800Y760600D01*
G01X597233D02*
Y763933D01*
G01Y763267D02*
X597650Y763600D01*
X598067Y763850D01*
X598650Y763933D01*
X599067Y763850D01*
X599567Y763600D01*
G01X610267Y763267D02*
X610600Y763517D01*
X610850Y763933D01*
X611017Y764517D01*
X610850Y765017D01*
X610517Y765350D01*
X609933Y765600D01*
X607683D01*
Y760600D01*
X610433D01*
X611017Y760933D01*
X611350Y761433D01*
X611517Y762017D01*
X611350Y762600D01*
X610850Y763100D01*
X610267Y763267D01*
X607683D01*
G01X615200Y760600D02*
X614700Y760683D01*
X614200Y761017D01*
X613867Y761600D01*
X613700Y762267D01*
X613867Y762933D01*
X614200Y763517D01*
X614700Y763850D01*
X615200Y763933D01*
X615700Y763850D01*
X616200Y763517D01*
X616533Y762933D01*
X616617Y762267D01*
X616533Y761600D01*
X616200Y761017D01*
X615700Y760683D01*
X615200Y760600D01*
G01X622300D02*
Y763933D01*
G01Y763350D02*
X621967Y763683D01*
X621467Y763850D01*
X620883Y763933D01*
X620300Y763767D01*
X619800Y763433D01*
X619467Y762933D01*
X619300Y762267D01*
X619467Y761600D01*
X619800Y761100D01*
X620300Y760767D01*
X620883Y760600D01*
X621467Y760683D01*
X621967Y760933D01*
X622300Y761267D01*
G01X625233Y760600D02*
Y763933D01*
G01Y763267D02*
X625650Y763600D01*
X626067Y763850D01*
X626650Y763933D01*
X627067Y763850D01*
X627567Y763600D01*
G01X633500Y765600D02*
Y760600D01*
G01Y761350D02*
X633167Y760933D01*
X632667Y760683D01*
X632083Y760600D01*
X631417Y760767D01*
X630917Y761183D01*
X630583Y761683D01*
X630500Y762267D01*
X630583Y762850D01*
X630917Y763350D01*
X631417Y763767D01*
X632083Y763933D01*
X632667Y763850D01*
X633083Y763683D01*
X633500Y763350D01*
G01X636350Y761183D02*
X636767Y760850D01*
X637350Y760600D01*
X637850D01*
X638350Y760767D01*
X638683Y761017D01*
X638850Y761350D01*
X638767Y761850D01*
X638433Y762100D01*
X636933Y762600D01*
X636600Y763183D01*
X636767Y763600D01*
X637100Y763850D01*
X637600Y763933D01*
X638100Y763850D01*
X638600Y763600D01*
G01X643617Y758933D02*
X644450Y759767D01*
X644867Y760600D01*
Y763933D01*
X644450Y764767D01*
X643617Y765600D01*
G01X71000Y774600D02*
X73000D01*
G01X72000D02*
Y769600D01*
G01X71000D02*
X73000D01*
G01X75933D02*
Y774600D01*
X77933D01*
X78600Y774350D01*
X79100Y773767D01*
X79267Y773100D01*
X79100Y772433D01*
X78683Y771933D01*
X77933Y771683D01*
X75933D01*
G01X85033Y774183D02*
X84533Y774433D01*
X83950Y774600D01*
X83283D01*
X82533Y774350D01*
X81950Y773933D01*
X81533Y773433D01*
X81200Y772600D01*
X81117Y771850D01*
X81283Y771100D01*
X81533Y770600D01*
X82033Y770100D01*
X82617Y769767D01*
X83200Y769600D01*
X83783D01*
X84367Y769767D01*
X84867Y770017D01*
X85283Y770350D01*
G01X87717Y771267D02*
X89883D01*
G01X92817Y771683D02*
X93400Y772267D01*
X93900Y772600D01*
X94567Y772767D01*
X95150Y772600D01*
X95567Y772267D01*
X95900Y771767D01*
X95983Y771183D01*
X95900Y770683D01*
X95567Y770183D01*
X95067Y769767D01*
X94483Y769600D01*
X93817Y769767D01*
X93233Y770267D01*
X92900Y771017D01*
X92817Y771850D01*
X92983Y772933D01*
X93233Y773517D01*
X93650Y774100D01*
X94233Y774517D01*
X94817Y774600D01*
X95400Y774433D01*
X95817Y774017D01*
G01X100000Y774600D02*
X99333Y774433D01*
X98833Y774017D01*
X98500Y773517D01*
X98250Y772850D01*
X98167Y772100D01*
X98250Y771350D01*
X98500Y770683D01*
X98833Y770183D01*
X99333Y769767D01*
X100000Y769600D01*
X100667Y769767D01*
X101167Y770183D01*
X101500Y770683D01*
X101750Y771350D01*
X101833Y772100D01*
X101750Y772850D01*
X101500Y773517D01*
X101167Y774017D01*
X100667Y774433D01*
X100000Y774600D01*
G01X105600Y769600D02*
Y774600D01*
X104600Y773600D01*
G01Y769600D02*
X106600D01*
G01X109617Y773767D02*
X110117Y774267D01*
X110700Y774517D01*
X111367Y774600D01*
X112200Y774433D01*
X112783Y774017D01*
X112950Y773517D01*
X112867Y773017D01*
X112533Y772600D01*
X110867Y771767D01*
X110117Y771183D01*
X109617Y770350D01*
X109450Y769600D01*
X112950D01*
G01X122400D02*
X121733Y769683D01*
X121150Y770017D01*
X120650Y770517D01*
X120317Y771100D01*
X120150Y771767D01*
Y772433D01*
X120317Y773100D01*
X120650Y773683D01*
X121150Y774183D01*
X121733Y774517D01*
X122400Y774600D01*
X123067Y774517D01*
X123650Y774183D01*
X124150Y773683D01*
X124483Y773100D01*
X124650Y772433D01*
Y771767D01*
X124483Y771100D01*
X124150Y770517D01*
X123650Y770017D01*
X123067Y769683D01*
X122400Y769600D01*
G01X123067Y770933D02*
X124067Y769600D01*
G01X126583Y772933D02*
Y770600D01*
X126917Y770017D01*
X127417Y769683D01*
X128000Y769600D01*
X128583Y769683D01*
X129083Y770017D01*
X129417Y770600D01*
G01Y769600D02*
Y772933D01*
G01X135100Y769600D02*
Y772933D01*
G01Y772350D02*
X134767Y772683D01*
X134267Y772850D01*
X133683Y772933D01*
X133100Y772767D01*
X132600Y772433D01*
X132267Y771933D01*
X132100Y771267D01*
X132267Y770600D01*
X132600Y770100D01*
X133100Y769767D01*
X133683Y769600D01*
X134267Y769683D01*
X134767Y769933D01*
X135100Y770267D01*
G01X139200Y769600D02*
Y774600D01*
G01X144800Y772933D02*
Y769600D01*
G01Y774267D02*
X144633Y774350D01*
Y774517D01*
X144800Y774600D01*
X144967Y774517D01*
Y774350D01*
X144800Y774267D01*
G01X149900Y769600D02*
Y773850D01*
X150067Y774267D01*
X150400Y774517D01*
X150900Y774600D01*
X151400Y774433D01*
X151650Y774017D01*
G01X150650Y772600D02*
X148983D01*
G01X156000Y772933D02*
Y769600D01*
G01Y774267D02*
X155833Y774350D01*
Y774517D01*
X156000Y774600D01*
X156167Y774517D01*
Y774350D01*
X156000Y774267D01*
G01X162933Y772517D02*
X162350Y772850D01*
X161850Y772933D01*
X161183Y772767D01*
X160683Y772433D01*
X160350Y771850D01*
X160267Y771267D01*
X160350Y770683D01*
X160683Y770183D01*
X161183Y769767D01*
X161850Y769600D01*
X162433Y769767D01*
X162933Y770100D01*
G01X168700Y769600D02*
Y772933D01*
G01Y772350D02*
X168367Y772683D01*
X167867Y772850D01*
X167283Y772933D01*
X166700Y772767D01*
X166200Y772433D01*
X165867Y771933D01*
X165700Y771267D01*
X165867Y770600D01*
X166200Y770100D01*
X166700Y769767D01*
X167283Y769600D01*
X167867Y769683D01*
X168367Y769933D01*
X168700Y770267D01*
G01X172800Y774600D02*
Y769600D01*
G01X171633Y772933D02*
X173967D01*
G01X178400D02*
Y769600D01*
G01Y774267D02*
X178233Y774350D01*
Y774517D01*
X178400Y774600D01*
X178567Y774517D01*
Y774350D01*
X178400Y774267D01*
G01X184000Y769600D02*
X183500Y769683D01*
X183000Y770017D01*
X182667Y770600D01*
X182500Y771267D01*
X182667Y771933D01*
X183000Y772517D01*
X183500Y772850D01*
X184000Y772933D01*
X184500Y772850D01*
X185000Y772517D01*
X185333Y771933D01*
X185417Y771267D01*
X185333Y770600D01*
X185000Y770017D01*
X184500Y769683D01*
X184000Y769600D01*
G01X188183D02*
Y772933D01*
G01Y772100D02*
X188517Y772517D01*
X189017Y772850D01*
X189683Y772933D01*
X190267Y772850D01*
X190767Y772517D01*
X191017Y771933D01*
Y769600D01*
G01X202300D02*
Y772933D01*
G01Y772350D02*
X201967Y772683D01*
X201467Y772850D01*
X200883Y772933D01*
X200300Y772767D01*
X199800Y772433D01*
X199467Y771933D01*
X199300Y771267D01*
X199467Y770600D01*
X199800Y770100D01*
X200300Y769767D01*
X200883Y769600D01*
X201467Y769683D01*
X201967Y769933D01*
X202300Y770267D01*
G01X204983Y769600D02*
Y772933D01*
G01Y772100D02*
X205317Y772517D01*
X205817Y772850D01*
X206483Y772933D01*
X207067Y772850D01*
X207567Y772517D01*
X207817Y771933D01*
Y769600D01*
G01X213500Y774600D02*
Y769600D01*
G01Y770350D02*
X213167Y769933D01*
X212667Y769683D01*
X212083Y769600D01*
X211417Y769767D01*
X210917Y770183D01*
X210583Y770683D01*
X210500Y771267D01*
X210583Y771850D01*
X210917Y772350D01*
X211417Y772767D01*
X212083Y772933D01*
X212667Y772850D01*
X213083Y772683D01*
X213500Y772350D01*
G01X221533Y769600D02*
Y774600D01*
X223533D01*
X224200Y774350D01*
X224700Y773767D01*
X224867Y773100D01*
X224700Y772433D01*
X224283Y771933D01*
X223533Y771683D01*
X221533D01*
G01X227550Y771850D02*
X230217D01*
X229967Y772433D01*
X229550Y772767D01*
X228967Y772933D01*
X228383Y772850D01*
X227883Y772600D01*
X227550Y772017D01*
X227383Y771517D01*
Y771017D01*
X227550Y770517D01*
X227967Y770017D01*
X228467Y769683D01*
X229050Y769600D01*
X229633Y769767D01*
X230217Y770267D01*
G01X233233Y769600D02*
Y772933D01*
G01Y772267D02*
X233650Y772600D01*
X234067Y772850D01*
X234650Y772933D01*
X235067Y772850D01*
X235567Y772600D01*
G01X239500Y769600D02*
Y773850D01*
X239667Y774267D01*
X240000Y774517D01*
X240500Y774600D01*
X241000Y774433D01*
X241250Y774017D01*
G01X240250Y772600D02*
X238583D01*
G01X245600Y769600D02*
X245100Y769683D01*
X244600Y770017D01*
X244267Y770600D01*
X244100Y771267D01*
X244267Y771933D01*
X244600Y772517D01*
X245100Y772850D01*
X245600Y772933D01*
X246100Y772850D01*
X246600Y772517D01*
X246933Y771933D01*
X247017Y771267D01*
X246933Y770600D01*
X246600Y770017D01*
X246100Y769683D01*
X245600Y769600D01*
G01X250033D02*
Y772933D01*
G01Y772267D02*
X250450Y772600D01*
X250867Y772850D01*
X251450Y772933D01*
X251867Y772850D01*
X252367Y772600D01*
G01X254300Y769600D02*
Y772933D01*
G01Y772017D02*
X254550Y772433D01*
X254967Y772767D01*
X255550Y772933D01*
X256133Y772767D01*
X256550Y772433D01*
X256800Y772017D01*
Y769600D01*
G01Y772017D02*
X257050Y772433D01*
X257467Y772767D01*
X258050Y772933D01*
X258633Y772767D01*
X259050Y772433D01*
X259300Y771933D01*
Y769600D01*
G01X263900D02*
Y772933D01*
G01Y772350D02*
X263567Y772683D01*
X263067Y772850D01*
X262483Y772933D01*
X261900Y772767D01*
X261400Y772433D01*
X261067Y771933D01*
X260900Y771267D01*
X261067Y770600D01*
X261400Y770100D01*
X261900Y769767D01*
X262483Y769600D01*
X263067Y769683D01*
X263567Y769933D01*
X263900Y770267D01*
G01X266583Y769600D02*
Y772933D01*
G01Y772100D02*
X266917Y772517D01*
X267417Y772850D01*
X268083Y772933D01*
X268667Y772850D01*
X269167Y772517D01*
X269417Y771933D01*
Y769600D01*
G01X274933Y772517D02*
X274350Y772850D01*
X273850Y772933D01*
X273183Y772767D01*
X272683Y772433D01*
X272350Y771850D01*
X272267Y771267D01*
X272350Y770683D01*
X272683Y770183D01*
X273183Y769767D01*
X273850Y769600D01*
X274433Y769767D01*
X274933Y770100D01*
G01X277950Y771850D02*
X280617D01*
X280367Y772433D01*
X279950Y772767D01*
X279367Y772933D01*
X278783Y772850D01*
X278283Y772600D01*
X277950Y772017D01*
X277783Y771517D01*
Y771017D01*
X277950Y770517D01*
X278367Y770017D01*
X278867Y769683D01*
X279450Y769600D01*
X280033Y769767D01*
X280617Y770267D01*
G01X288650D02*
X289317Y769850D01*
X290067Y769600D01*
X290733D01*
X291400Y769850D01*
X291900Y770267D01*
X292150Y770850D01*
X291983Y771433D01*
X291567Y771933D01*
X290817Y772267D01*
X289817Y772433D01*
X289233Y772767D01*
X288983Y773350D01*
X289150Y773933D01*
X289567Y774350D01*
X290150Y774600D01*
X290733D01*
X291317Y774433D01*
X291817Y774017D01*
G01X294500Y767933D02*
Y772933D01*
G01Y772183D02*
X294917Y772600D01*
X295333Y772850D01*
X296000Y772933D01*
X296583Y772850D01*
X297167Y772433D01*
X297417Y771850D01*
X297500Y771267D01*
X297417Y770683D01*
X297167Y770100D01*
X296667Y769767D01*
X296000Y769600D01*
X295417Y769683D01*
X294833Y769933D01*
X294500Y770267D01*
G01X300350Y771850D02*
X303017D01*
X302767Y772433D01*
X302350Y772767D01*
X301767Y772933D01*
X301183Y772850D01*
X300683Y772600D01*
X300350Y772017D01*
X300183Y771517D01*
Y771017D01*
X300350Y770517D01*
X300767Y770017D01*
X301267Y769683D01*
X301850Y769600D01*
X302433Y769767D01*
X303017Y770267D01*
G01X308533Y772517D02*
X307950Y772850D01*
X307450Y772933D01*
X306783Y772767D01*
X306283Y772433D01*
X305950Y771850D01*
X305867Y771267D01*
X305950Y770683D01*
X306283Y770183D01*
X306783Y769767D01*
X307450Y769600D01*
X308033Y769767D01*
X308533Y770100D01*
G01X312800Y772933D02*
Y769600D01*
G01Y774267D02*
X312633Y774350D01*
Y774517D01*
X312800Y774600D01*
X312967Y774517D01*
Y774350D01*
X312800Y774267D01*
G01X317900Y769600D02*
Y773850D01*
X318067Y774267D01*
X318400Y774517D01*
X318900Y774600D01*
X319400Y774433D01*
X319650Y774017D01*
G01X318650Y772600D02*
X316983D01*
G01X324000Y772933D02*
Y769600D01*
G01Y774267D02*
X323833Y774350D01*
Y774517D01*
X324000Y774600D01*
X324167Y774517D01*
Y774350D01*
X324000Y774267D01*
G01X330933Y772517D02*
X330350Y772850D01*
X329850Y772933D01*
X329183Y772767D01*
X328683Y772433D01*
X328350Y771850D01*
X328267Y771267D01*
X328350Y770683D01*
X328683Y770183D01*
X329183Y769767D01*
X329850Y769600D01*
X330433Y769767D01*
X330933Y770100D01*
G01X336700Y769600D02*
Y772933D01*
G01Y772350D02*
X336367Y772683D01*
X335867Y772850D01*
X335283Y772933D01*
X334700Y772767D01*
X334200Y772433D01*
X333867Y771933D01*
X333700Y771267D01*
X333867Y770600D01*
X334200Y770100D01*
X334700Y769767D01*
X335283Y769600D01*
X335867Y769683D01*
X336367Y769933D01*
X336700Y770267D01*
G01X340800Y774600D02*
Y769600D01*
G01X339633Y772933D02*
X341967D01*
G01X346400D02*
Y769600D01*
G01Y774267D02*
X346233Y774350D01*
Y774517D01*
X346400Y774600D01*
X346567Y774517D01*
Y774350D01*
X346400Y774267D01*
G01X352000Y769600D02*
X351500Y769683D01*
X351000Y770017D01*
X350667Y770600D01*
X350500Y771267D01*
X350667Y771933D01*
X351000Y772517D01*
X351500Y772850D01*
X352000Y772933D01*
X352500Y772850D01*
X353000Y772517D01*
X353333Y771933D01*
X353417Y771267D01*
X353333Y770600D01*
X353000Y770017D01*
X352500Y769683D01*
X352000Y769600D01*
G01X356183D02*
Y772933D01*
G01Y772100D02*
X356517Y772517D01*
X357017Y772850D01*
X357683Y772933D01*
X358267Y772850D01*
X358767Y772517D01*
X359017Y771933D01*
Y769600D01*
G01X368300D02*
Y773850D01*
X368467Y774267D01*
X368800Y774517D01*
X369300Y774600D01*
X369800Y774433D01*
X370050Y774017D01*
G01X369050Y772600D02*
X367383D01*
G01X374400Y769600D02*
X373900Y769683D01*
X373400Y770017D01*
X373067Y770600D01*
X372900Y771267D01*
X373067Y771933D01*
X373400Y772517D01*
X373900Y772850D01*
X374400Y772933D01*
X374900Y772850D01*
X375400Y772517D01*
X375733Y771933D01*
X375817Y771267D01*
X375733Y770600D01*
X375400Y770017D01*
X374900Y769683D01*
X374400Y769600D01*
G01X378833D02*
Y772933D01*
G01Y772267D02*
X379250Y772600D01*
X379667Y772850D01*
X380250Y772933D01*
X380667Y772850D01*
X381167Y772600D01*
G01X389533Y769600D02*
Y774600D01*
X391617D01*
X392283Y774350D01*
X392700Y774017D01*
X392867Y773350D01*
X392700Y772683D01*
X392200Y772267D01*
X391617Y772017D01*
X389533D01*
G01X391617D02*
X392867Y769600D01*
G01X396800Y772933D02*
Y769600D01*
G01Y774267D02*
X396633Y774350D01*
Y774517D01*
X396800Y774600D01*
X396967Y774517D01*
Y774350D01*
X396800Y774267D01*
G01X401233Y768350D02*
X401817Y768017D01*
X402483Y767933D01*
X403067Y768017D01*
X403567Y768433D01*
X403900Y769017D01*
Y772933D01*
G01Y772267D02*
X403567Y772600D01*
X403067Y772850D01*
X402483Y772933D01*
X401817Y772767D01*
X401400Y772433D01*
X401067Y771850D01*
X400900Y771267D01*
X400983Y770767D01*
X401317Y770183D01*
X401817Y769767D01*
X402483Y769600D01*
X402983Y769683D01*
X403567Y770017D01*
X403900Y770350D01*
G01X408000Y772933D02*
Y769600D01*
G01Y774267D02*
X407833Y774350D01*
Y774517D01*
X408000Y774600D01*
X408167Y774517D01*
Y774350D01*
X408000Y774267D01*
G01X415100Y774600D02*
Y769600D01*
G01Y770350D02*
X414767Y769933D01*
X414267Y769683D01*
X413683Y769600D01*
X413017Y769767D01*
X412517Y770183D01*
X412183Y770683D01*
X412100Y771267D01*
X412183Y771850D01*
X412517Y772350D01*
X413017Y772767D01*
X413683Y772933D01*
X414267Y772850D01*
X414683Y772683D01*
X415100Y772350D01*
G01X423133Y769600D02*
Y774600D01*
X425133D01*
X425800Y774350D01*
X426300Y773767D01*
X426467Y773100D01*
X426300Y772433D01*
X425883Y771933D01*
X425133Y771683D01*
X423133D01*
G01X429233Y769600D02*
Y772933D01*
G01Y772267D02*
X429650Y772600D01*
X430067Y772850D01*
X430650Y772933D01*
X431067Y772850D01*
X431567Y772600D01*
G01X436000Y772933D02*
Y769600D01*
G01Y774267D02*
X435833Y774350D01*
Y774517D01*
X436000Y774600D01*
X436167Y774517D01*
Y774350D01*
X436000Y774267D01*
G01X440183Y769600D02*
Y772933D01*
G01Y772100D02*
X440517Y772517D01*
X441017Y772850D01*
X441683Y772933D01*
X442267Y772850D01*
X442767Y772517D01*
X443017Y771933D01*
Y769600D01*
G01X447200Y774600D02*
Y769600D01*
G01X446033Y772933D02*
X448367D01*
G01X451550Y771850D02*
X454217D01*
X453967Y772433D01*
X453550Y772767D01*
X452967Y772933D01*
X452383Y772850D01*
X451883Y772600D01*
X451550Y772017D01*
X451383Y771517D01*
Y771017D01*
X451550Y770517D01*
X451967Y770017D01*
X452467Y769683D01*
X453050Y769600D01*
X453633Y769767D01*
X454217Y770267D01*
G01X459900Y774600D02*
Y769600D01*
G01Y770350D02*
X459567Y769933D01*
X459067Y769683D01*
X458483Y769600D01*
X457817Y769767D01*
X457317Y770183D01*
X456983Y770683D01*
X456900Y771267D01*
X456983Y771850D01*
X457317Y772350D01*
X457817Y772767D01*
X458483Y772933D01*
X459067Y772850D01*
X459483Y772683D01*
X459900Y772350D01*
G01X470267Y772267D02*
X470600Y772517D01*
X470850Y772933D01*
X471017Y773517D01*
X470850Y774017D01*
X470517Y774350D01*
X469933Y774600D01*
X467683D01*
Y769600D01*
X470433D01*
X471017Y769933D01*
X471350Y770433D01*
X471517Y771017D01*
X471350Y771600D01*
X470850Y772100D01*
X470267Y772267D01*
X467683D01*
G01X475200Y769600D02*
X474700Y769683D01*
X474200Y770017D01*
X473867Y770600D01*
X473700Y771267D01*
X473867Y771933D01*
X474200Y772517D01*
X474700Y772850D01*
X475200Y772933D01*
X475700Y772850D01*
X476200Y772517D01*
X476533Y771933D01*
X476617Y771267D01*
X476533Y770600D01*
X476200Y770017D01*
X475700Y769683D01*
X475200Y769600D01*
G01X482300D02*
Y772933D01*
G01Y772350D02*
X481967Y772683D01*
X481467Y772850D01*
X480883Y772933D01*
X480300Y772767D01*
X479800Y772433D01*
X479467Y771933D01*
X479300Y771267D01*
X479467Y770600D01*
X479800Y770100D01*
X480300Y769767D01*
X480883Y769600D01*
X481467Y769683D01*
X481967Y769933D01*
X482300Y770267D01*
G01X485233Y769600D02*
Y772933D01*
G01Y772267D02*
X485650Y772600D01*
X486067Y772850D01*
X486650Y772933D01*
X487067Y772850D01*
X487567Y772600D01*
G01X493500Y774600D02*
Y769600D01*
G01Y770350D02*
X493167Y769933D01*
X492667Y769683D01*
X492083Y769600D01*
X491417Y769767D01*
X490917Y770183D01*
X490583Y770683D01*
X490500Y771267D01*
X490583Y771850D01*
X490917Y772350D01*
X491417Y772767D01*
X492083Y772933D01*
X492667Y772850D01*
X493083Y772683D01*
X493500Y772350D01*
G01X496350Y770183D02*
X496767Y769850D01*
X497350Y769600D01*
X497850D01*
X498350Y769767D01*
X498683Y770017D01*
X498850Y770350D01*
X498767Y770850D01*
X498433Y771100D01*
X496933Y771600D01*
X496600Y772183D01*
X496767Y772600D01*
X497100Y772850D01*
X497600Y772933D01*
X498100Y772850D01*
X498600Y772600D01*
G01X71000Y783600D02*
X73000D01*
G01X72000D02*
Y778600D01*
G01X71000D02*
X73000D01*
G01X75933D02*
Y783600D01*
X77933D01*
X78600Y783350D01*
X79100Y782767D01*
X79267Y782100D01*
X79100Y781433D01*
X78683Y780933D01*
X77933Y780683D01*
X75933D01*
G01X85033Y783183D02*
X84533Y783433D01*
X83950Y783600D01*
X83283D01*
X82533Y783350D01*
X81950Y782933D01*
X81533Y782433D01*
X81200Y781600D01*
X81117Y780850D01*
X81283Y780100D01*
X81533Y779600D01*
X82033Y779100D01*
X82617Y778767D01*
X83200Y778600D01*
X83783D01*
X84367Y778767D01*
X84867Y779017D01*
X85283Y779350D01*
G01X87717Y780267D02*
X89883D01*
G01X92817Y780683D02*
X93400Y781267D01*
X93900Y781600D01*
X94567Y781767D01*
X95150Y781600D01*
X95567Y781267D01*
X95900Y780767D01*
X95983Y780183D01*
X95900Y779683D01*
X95567Y779183D01*
X95067Y778767D01*
X94483Y778600D01*
X93817Y778767D01*
X93233Y779267D01*
X92900Y780017D01*
X92817Y780850D01*
X92983Y781933D01*
X93233Y782517D01*
X93650Y783100D01*
X94233Y783517D01*
X94817Y783600D01*
X95400Y783433D01*
X95817Y783017D01*
G01X100000Y783600D02*
X99333Y783433D01*
X98833Y783017D01*
X98500Y782517D01*
X98250Y781850D01*
X98167Y781100D01*
X98250Y780350D01*
X98500Y779683D01*
X98833Y779183D01*
X99333Y778767D01*
X100000Y778600D01*
X100667Y778767D01*
X101167Y779183D01*
X101500Y779683D01*
X101750Y780350D01*
X101833Y781100D01*
X101750Y781850D01*
X101500Y782517D01*
X101167Y783017D01*
X100667Y783433D01*
X100000Y783600D01*
G01X105600Y778600D02*
Y783600D01*
X104600Y782600D01*
G01Y778600D02*
X106600D01*
G01X111200D02*
Y783600D01*
X110200Y782600D01*
G01Y778600D02*
X112200D01*
G01X122900Y781100D02*
X124567D01*
Y779600D01*
X124067Y779100D01*
X123483Y778767D01*
X122650Y778600D01*
X121817Y778767D01*
X121233Y779100D01*
X120733Y779600D01*
X120400Y780183D01*
X120233Y780850D01*
Y781433D01*
X120400Y781933D01*
X120733Y782517D01*
X121233Y783017D01*
X121733Y783350D01*
X122400Y783600D01*
X122983D01*
X123650Y783433D01*
X124150Y783100D01*
G01X126750Y780850D02*
X129417D01*
X129167Y781433D01*
X128750Y781767D01*
X128167Y781933D01*
X127583Y781850D01*
X127083Y781600D01*
X126750Y781017D01*
X126583Y780517D01*
Y780017D01*
X126750Y779517D01*
X127167Y779017D01*
X127667Y778683D01*
X128250Y778600D01*
X128833Y778767D01*
X129417Y779267D01*
G01X132183Y778600D02*
Y781933D01*
G01Y781100D02*
X132517Y781517D01*
X133017Y781850D01*
X133683Y781933D01*
X134267Y781850D01*
X134767Y781517D01*
X135017Y780933D01*
Y778600D01*
G01X137950Y780850D02*
X140617D01*
X140367Y781433D01*
X139950Y781767D01*
X139367Y781933D01*
X138783Y781850D01*
X138283Y781600D01*
X137950Y781017D01*
X137783Y780517D01*
Y780017D01*
X137950Y779517D01*
X138367Y779017D01*
X138867Y778683D01*
X139450Y778600D01*
X140033Y778767D01*
X140617Y779267D01*
G01X143633Y778600D02*
Y781933D01*
G01Y781267D02*
X144050Y781600D01*
X144467Y781850D01*
X145050Y781933D01*
X145467Y781850D01*
X145967Y781600D01*
G01X150400Y781933D02*
Y778600D01*
G01Y783267D02*
X150233Y783350D01*
Y783517D01*
X150400Y783600D01*
X150567Y783517D01*
Y783350D01*
X150400Y783267D01*
G01X157333Y781517D02*
X156750Y781850D01*
X156250Y781933D01*
X155583Y781767D01*
X155083Y781433D01*
X154750Y780850D01*
X154667Y780267D01*
X154750Y779683D01*
X155083Y779183D01*
X155583Y778767D01*
X156250Y778600D01*
X156833Y778767D01*
X157333Y779100D01*
G01X165533Y778600D02*
Y783600D01*
X167533D01*
X168200Y783350D01*
X168700Y782767D01*
X168867Y782100D01*
X168700Y781433D01*
X168283Y780933D01*
X167533Y780683D01*
X165533D01*
G01X171550Y780850D02*
X174217D01*
X173967Y781433D01*
X173550Y781767D01*
X172967Y781933D01*
X172383Y781850D01*
X171883Y781600D01*
X171550Y781017D01*
X171383Y780517D01*
Y780017D01*
X171550Y779517D01*
X171967Y779017D01*
X172467Y778683D01*
X173050Y778600D01*
X173633Y778767D01*
X174217Y779267D01*
G01X177233Y778600D02*
Y781933D01*
G01Y781267D02*
X177650Y781600D01*
X178067Y781850D01*
X178650Y781933D01*
X179067Y781850D01*
X179567Y781600D01*
G01X183500Y778600D02*
Y782850D01*
X183667Y783267D01*
X184000Y783517D01*
X184500Y783600D01*
X185000Y783433D01*
X185250Y783017D01*
G01X184250Y781600D02*
X182583D01*
G01X189600Y778600D02*
X189100Y778683D01*
X188600Y779017D01*
X188267Y779600D01*
X188100Y780267D01*
X188267Y780933D01*
X188600Y781517D01*
X189100Y781850D01*
X189600Y781933D01*
X190100Y781850D01*
X190600Y781517D01*
X190933Y780933D01*
X191017Y780267D01*
X190933Y779600D01*
X190600Y779017D01*
X190100Y778683D01*
X189600Y778600D01*
G01X194033D02*
Y781933D01*
G01Y781267D02*
X194450Y781600D01*
X194867Y781850D01*
X195450Y781933D01*
X195867Y781850D01*
X196367Y781600D01*
G01X198300Y778600D02*
Y781933D01*
G01Y781017D02*
X198550Y781433D01*
X198967Y781767D01*
X199550Y781933D01*
X200133Y781767D01*
X200550Y781433D01*
X200800Y781017D01*
Y778600D01*
G01Y781017D02*
X201050Y781433D01*
X201467Y781767D01*
X202050Y781933D01*
X202633Y781767D01*
X203050Y781433D01*
X203300Y780933D01*
Y778600D01*
G01X207900D02*
Y781933D01*
G01Y781350D02*
X207567Y781683D01*
X207067Y781850D01*
X206483Y781933D01*
X205900Y781767D01*
X205400Y781433D01*
X205067Y780933D01*
X204900Y780267D01*
X205067Y779600D01*
X205400Y779100D01*
X205900Y778767D01*
X206483Y778600D01*
X207067Y778683D01*
X207567Y778933D01*
X207900Y779267D01*
G01X210583Y778600D02*
Y781933D01*
G01Y781100D02*
X210917Y781517D01*
X211417Y781850D01*
X212083Y781933D01*
X212667Y781850D01*
X213167Y781517D01*
X213417Y780933D01*
Y778600D01*
G01X218933Y781517D02*
X218350Y781850D01*
X217850Y781933D01*
X217183Y781767D01*
X216683Y781433D01*
X216350Y780850D01*
X216267Y780267D01*
X216350Y779683D01*
X216683Y779183D01*
X217183Y778767D01*
X217850Y778600D01*
X218433Y778767D01*
X218933Y779100D01*
G01X221950Y780850D02*
X224617D01*
X224367Y781433D01*
X223950Y781767D01*
X223367Y781933D01*
X222783Y781850D01*
X222283Y781600D01*
X221950Y781017D01*
X221783Y780517D01*
Y780017D01*
X221950Y779517D01*
X222367Y779017D01*
X222867Y778683D01*
X223450Y778600D01*
X224033Y778767D01*
X224617Y779267D01*
G01X232650D02*
X233317Y778850D01*
X234067Y778600D01*
X234733D01*
X235400Y778850D01*
X235900Y779267D01*
X236150Y779850D01*
X235983Y780433D01*
X235567Y780933D01*
X234817Y781267D01*
X233817Y781433D01*
X233233Y781767D01*
X232983Y782350D01*
X233150Y782933D01*
X233567Y783350D01*
X234150Y783600D01*
X234733D01*
X235317Y783433D01*
X235817Y783017D01*
G01X238500Y776933D02*
Y781933D01*
G01Y781183D02*
X238917Y781600D01*
X239333Y781850D01*
X240000Y781933D01*
X240583Y781850D01*
X241167Y781433D01*
X241417Y780850D01*
X241500Y780267D01*
X241417Y779683D01*
X241167Y779100D01*
X240667Y778767D01*
X240000Y778600D01*
X239417Y778683D01*
X238833Y778933D01*
X238500Y779267D01*
G01X244350Y780850D02*
X247017D01*
X246767Y781433D01*
X246350Y781767D01*
X245767Y781933D01*
X245183Y781850D01*
X244683Y781600D01*
X244350Y781017D01*
X244183Y780517D01*
Y780017D01*
X244350Y779517D01*
X244767Y779017D01*
X245267Y778683D01*
X245850Y778600D01*
X246433Y778767D01*
X247017Y779267D01*
G01X252533Y781517D02*
X251950Y781850D01*
X251450Y781933D01*
X250783Y781767D01*
X250283Y781433D01*
X249950Y780850D01*
X249867Y780267D01*
X249950Y779683D01*
X250283Y779183D01*
X250783Y778767D01*
X251450Y778600D01*
X252033Y778767D01*
X252533Y779100D01*
G01X256800Y781933D02*
Y778600D01*
G01Y783267D02*
X256633Y783350D01*
Y783517D01*
X256800Y783600D01*
X256967Y783517D01*
Y783350D01*
X256800Y783267D01*
G01X261900Y778600D02*
Y782850D01*
X262067Y783267D01*
X262400Y783517D01*
X262900Y783600D01*
X263400Y783433D01*
X263650Y783017D01*
G01X262650Y781600D02*
X260983D01*
G01X268000Y781933D02*
Y778600D01*
G01Y783267D02*
X267833Y783350D01*
Y783517D01*
X268000Y783600D01*
X268167Y783517D01*
Y783350D01*
X268000Y783267D01*
G01X274933Y781517D02*
X274350Y781850D01*
X273850Y781933D01*
X273183Y781767D01*
X272683Y781433D01*
X272350Y780850D01*
X272267Y780267D01*
X272350Y779683D01*
X272683Y779183D01*
X273183Y778767D01*
X273850Y778600D01*
X274433Y778767D01*
X274933Y779100D01*
G01X280700Y778600D02*
Y781933D01*
G01Y781350D02*
X280367Y781683D01*
X279867Y781850D01*
X279283Y781933D01*
X278700Y781767D01*
X278200Y781433D01*
X277867Y780933D01*
X277700Y780267D01*
X277867Y779600D01*
X278200Y779100D01*
X278700Y778767D01*
X279283Y778600D01*
X279867Y778683D01*
X280367Y778933D01*
X280700Y779267D01*
G01X284800Y783600D02*
Y778600D01*
G01X283633Y781933D02*
X285967D01*
G01X290400D02*
Y778600D01*
G01Y783267D02*
X290233Y783350D01*
Y783517D01*
X290400Y783600D01*
X290567Y783517D01*
Y783350D01*
X290400Y783267D01*
G01X296000Y778600D02*
X295500Y778683D01*
X295000Y779017D01*
X294667Y779600D01*
X294500Y780267D01*
X294667Y780933D01*
X295000Y781517D01*
X295500Y781850D01*
X296000Y781933D01*
X296500Y781850D01*
X297000Y781517D01*
X297333Y780933D01*
X297417Y780267D01*
X297333Y779600D01*
X297000Y779017D01*
X296500Y778683D01*
X296000Y778600D01*
G01X300183D02*
Y781933D01*
G01Y781100D02*
X300517Y781517D01*
X301017Y781850D01*
X301683Y781933D01*
X302267Y781850D01*
X302767Y781517D01*
X303017Y780933D01*
Y778600D01*
G01X312300D02*
Y782850D01*
X312467Y783267D01*
X312800Y783517D01*
X313300Y783600D01*
X313800Y783433D01*
X314050Y783017D01*
G01X313050Y781600D02*
X311383D01*
G01X318400Y778600D02*
X317900Y778683D01*
X317400Y779017D01*
X317067Y779600D01*
X316900Y780267D01*
X317067Y780933D01*
X317400Y781517D01*
X317900Y781850D01*
X318400Y781933D01*
X318900Y781850D01*
X319400Y781517D01*
X319733Y780933D01*
X319817Y780267D01*
X319733Y779600D01*
X319400Y779017D01*
X318900Y778683D01*
X318400Y778600D01*
G01X322833D02*
Y781933D01*
G01Y781267D02*
X323250Y781600D01*
X323667Y781850D01*
X324250Y781933D01*
X324667Y781850D01*
X325167Y781600D01*
G01X333533Y778600D02*
Y783600D01*
X335533D01*
X336200Y783350D01*
X336700Y782767D01*
X336867Y782100D01*
X336700Y781433D01*
X336283Y780933D01*
X335533Y780683D01*
X333533D01*
G01X339633Y778600D02*
Y781933D01*
G01Y781267D02*
X340050Y781600D01*
X340467Y781850D01*
X341050Y781933D01*
X341467Y781850D01*
X341967Y781600D01*
G01X346400Y781933D02*
Y778600D01*
G01Y783267D02*
X346233Y783350D01*
Y783517D01*
X346400Y783600D01*
X346567Y783517D01*
Y783350D01*
X346400Y783267D01*
G01X350583Y778600D02*
Y781933D01*
G01Y781100D02*
X350917Y781517D01*
X351417Y781850D01*
X352083Y781933D01*
X352667Y781850D01*
X353167Y781517D01*
X353417Y780933D01*
Y778600D01*
G01X357600Y783600D02*
Y778600D01*
G01X356433Y781933D02*
X358767D01*
G01X361950Y780850D02*
X364617D01*
X364367Y781433D01*
X363950Y781767D01*
X363367Y781933D01*
X362783Y781850D01*
X362283Y781600D01*
X361950Y781017D01*
X361783Y780517D01*
Y780017D01*
X361950Y779517D01*
X362367Y779017D01*
X362867Y778683D01*
X363450Y778600D01*
X364033Y778767D01*
X364617Y779267D01*
G01X370300Y783600D02*
Y778600D01*
G01Y779350D02*
X369967Y778933D01*
X369467Y778683D01*
X368883Y778600D01*
X368217Y778767D01*
X367717Y779183D01*
X367383Y779683D01*
X367300Y780267D01*
X367383Y780850D01*
X367717Y781350D01*
X368217Y781767D01*
X368883Y781933D01*
X369467Y781850D01*
X369883Y781683D01*
X370300Y781350D01*
G01X380667Y781267D02*
X381000Y781517D01*
X381250Y781933D01*
X381417Y782517D01*
X381250Y783017D01*
X380917Y783350D01*
X380333Y783600D01*
X378083D01*
Y778600D01*
X380833D01*
X381417Y778933D01*
X381750Y779433D01*
X381917Y780017D01*
X381750Y780600D01*
X381250Y781100D01*
X380667Y781267D01*
X378083D01*
G01X385600Y778600D02*
X385100Y778683D01*
X384600Y779017D01*
X384267Y779600D01*
X384100Y780267D01*
X384267Y780933D01*
X384600Y781517D01*
X385100Y781850D01*
X385600Y781933D01*
X386100Y781850D01*
X386600Y781517D01*
X386933Y780933D01*
X387017Y780267D01*
X386933Y779600D01*
X386600Y779017D01*
X386100Y778683D01*
X385600Y778600D01*
G01X392700D02*
Y781933D01*
G01Y781350D02*
X392367Y781683D01*
X391867Y781850D01*
X391283Y781933D01*
X390700Y781767D01*
X390200Y781433D01*
X389867Y780933D01*
X389700Y780267D01*
X389867Y779600D01*
X390200Y779100D01*
X390700Y778767D01*
X391283Y778600D01*
X391867Y778683D01*
X392367Y778933D01*
X392700Y779267D01*
G01X395633Y778600D02*
Y781933D01*
G01Y781267D02*
X396050Y781600D01*
X396467Y781850D01*
X397050Y781933D01*
X397467Y781850D01*
X397967Y781600D01*
G01X403900Y783600D02*
Y778600D01*
G01Y779350D02*
X403567Y778933D01*
X403067Y778683D01*
X402483Y778600D01*
X401817Y778767D01*
X401317Y779183D01*
X400983Y779683D01*
X400900Y780267D01*
X400983Y780850D01*
X401317Y781350D01*
X401817Y781767D01*
X402483Y781933D01*
X403067Y781850D01*
X403483Y781683D01*
X403900Y781350D01*
G01X406750Y779183D02*
X407167Y778850D01*
X407750Y778600D01*
X408250D01*
X408750Y778767D01*
X409083Y779017D01*
X409250Y779350D01*
X409167Y779850D01*
X408833Y780100D01*
X407333Y780600D01*
X407000Y781183D01*
X407167Y781600D01*
X407500Y781850D01*
X408000Y781933D01*
X408500Y781850D01*
X409000Y781600D01*
G01X67000Y786333D02*
X66833Y786417D01*
Y786583D01*
X67000Y786667D01*
X67167Y786583D01*
Y786417D01*
X67000Y786333D01*
G01X71000Y791500D02*
X73000D01*
G01X72000D02*
Y786500D01*
G01X71000D02*
X73000D01*
G01X75933D02*
Y791500D01*
X77933D01*
X78600Y791250D01*
X79100Y790667D01*
X79267Y790000D01*
X79100Y789333D01*
X78683Y788833D01*
X77933Y788583D01*
X75933D01*
G01X85033Y791083D02*
X84533Y791333D01*
X83950Y791500D01*
X83283D01*
X82533Y791250D01*
X81950Y790833D01*
X81533Y790333D01*
X81200Y789500D01*
X81117Y788750D01*
X81283Y788000D01*
X81533Y787500D01*
X82033Y787000D01*
X82617Y786667D01*
X83200Y786500D01*
X83783D01*
X84367Y786667D01*
X84867Y786917D01*
X85283Y787250D01*
G01X87717Y788167D02*
X89883D01*
G01X92317Y786500D02*
X94400Y791500D01*
X96483Y786500D01*
G01X95733Y788250D02*
X93067D01*
G01X98917Y788167D02*
X101083D01*
G01X104017Y788583D02*
X104600Y789167D01*
X105100Y789500D01*
X105767Y789667D01*
X106350Y789500D01*
X106767Y789167D01*
X107100Y788667D01*
X107183Y788083D01*
X107100Y787583D01*
X106767Y787083D01*
X106267Y786667D01*
X105683Y786500D01*
X105017Y786667D01*
X104433Y787167D01*
X104100Y787917D01*
X104017Y788750D01*
X104183Y789833D01*
X104433Y790417D01*
X104850Y791000D01*
X105433Y791417D01*
X106017Y791500D01*
X106600Y791333D01*
X107017Y790917D01*
G01X111200Y791500D02*
X110533Y791333D01*
X110033Y790917D01*
X109700Y790417D01*
X109450Y789750D01*
X109367Y789000D01*
X109450Y788250D01*
X109700Y787583D01*
X110033Y787083D01*
X110533Y786667D01*
X111200Y786500D01*
X111867Y786667D01*
X112367Y787083D01*
X112700Y787583D01*
X112950Y788250D01*
X113033Y789000D01*
X112950Y789750D01*
X112700Y790417D01*
X112367Y790917D01*
X111867Y791333D01*
X111200Y791500D01*
G01X116800D02*
X116133Y791333D01*
X115633Y790917D01*
X115300Y790417D01*
X115050Y789750D01*
X114967Y789000D01*
X115050Y788250D01*
X115300Y787583D01*
X115633Y787083D01*
X116133Y786667D01*
X116800Y786500D01*
X117467Y786667D01*
X117967Y787083D01*
X118300Y787583D01*
X118550Y788250D01*
X118633Y789000D01*
X118550Y789750D01*
X118300Y790417D01*
X117967Y790917D01*
X117467Y791333D01*
X116800Y791500D01*
G01X125917Y786500D02*
X128000Y791500D01*
X130083Y786500D01*
G01X129333Y788250D02*
X126667D01*
G01X134933Y789417D02*
X134350Y789750D01*
X133850Y789833D01*
X133183Y789667D01*
X132683Y789333D01*
X132350Y788750D01*
X132267Y788167D01*
X132350Y787583D01*
X132683Y787083D01*
X133183Y786667D01*
X133850Y786500D01*
X134433Y786667D01*
X134933Y787000D01*
G01X140533Y789417D02*
X139950Y789750D01*
X139450Y789833D01*
X138783Y789667D01*
X138283Y789333D01*
X137950Y788750D01*
X137867Y788167D01*
X137950Y787583D01*
X138283Y787083D01*
X138783Y786667D01*
X139450Y786500D01*
X140033Y786667D01*
X140533Y787000D01*
G01X143550Y788750D02*
X146217D01*
X145967Y789333D01*
X145550Y789667D01*
X144967Y789833D01*
X144383Y789750D01*
X143883Y789500D01*
X143550Y788917D01*
X143383Y788417D01*
Y787917D01*
X143550Y787417D01*
X143967Y786917D01*
X144467Y786583D01*
X145050Y786500D01*
X145633Y786667D01*
X146217Y787167D01*
G01X148900Y784833D02*
Y789833D01*
G01Y789083D02*
X149317Y789500D01*
X149733Y789750D01*
X150400Y789833D01*
X150983Y789750D01*
X151567Y789333D01*
X151817Y788750D01*
X151900Y788167D01*
X151817Y787583D01*
X151567Y787000D01*
X151067Y786667D01*
X150400Y786500D01*
X149817Y786583D01*
X149233Y786833D01*
X148900Y787167D01*
G01X156000Y791500D02*
Y786500D01*
G01X154833Y789833D02*
X157167D01*
G01X163100Y786500D02*
Y789833D01*
G01Y789250D02*
X162767Y789583D01*
X162267Y789750D01*
X161683Y789833D01*
X161100Y789667D01*
X160600Y789333D01*
X160267Y788833D01*
X160100Y788167D01*
X160267Y787500D01*
X160600Y787000D01*
X161100Y786667D01*
X161683Y786500D01*
X162267Y786583D01*
X162767Y786833D01*
X163100Y787167D01*
G01X165700Y786500D02*
Y791500D01*
G01Y789000D02*
X166117Y789500D01*
X166617Y789750D01*
X167117Y789833D01*
X167867Y789667D01*
X168367Y789333D01*
X168700Y788750D01*
Y788083D01*
X168533Y787417D01*
X168200Y786917D01*
X167617Y786583D01*
X167117Y786500D01*
X166617Y786583D01*
X166117Y786833D01*
X165700Y787250D01*
G01X172800Y789833D02*
Y786500D01*
G01Y791167D02*
X172633Y791250D01*
Y791417D01*
X172800Y791500D01*
X172967Y791417D01*
Y791250D01*
X172800Y791167D01*
G01X178400Y786500D02*
Y791500D01*
G01X184000Y789833D02*
Y786500D01*
G01Y791167D02*
X183833Y791250D01*
Y791417D01*
X184000Y791500D01*
X184167Y791417D01*
Y791250D01*
X184000Y791167D01*
G01X189600Y791500D02*
Y786500D01*
G01X188433Y789833D02*
X190767D01*
G01X193450Y785000D02*
X193950Y784833D01*
X194617Y785000D01*
X195033Y785333D01*
X195367Y785750D01*
X195867Y787083D01*
X196950Y789833D01*
G01X194283D02*
X195867Y787083D01*
G01X206400Y786500D02*
X205900Y786583D01*
X205400Y786917D01*
X205067Y787500D01*
X204900Y788167D01*
X205067Y788833D01*
X205400Y789417D01*
X205900Y789750D01*
X206400Y789833D01*
X206900Y789750D01*
X207400Y789417D01*
X207733Y788833D01*
X207817Y788167D01*
X207733Y787500D01*
X207400Y786917D01*
X206900Y786583D01*
X206400Y786500D01*
G01X211500D02*
Y790750D01*
X211667Y791167D01*
X212000Y791417D01*
X212500Y791500D01*
X213000Y791333D01*
X213250Y790917D01*
G01X212250Y789500D02*
X210583D01*
G01X221533Y786500D02*
Y791500D01*
X223533D01*
X224200Y791250D01*
X224700Y790667D01*
X224867Y790000D01*
X224700Y789333D01*
X224283Y788833D01*
X223533Y788583D01*
X221533D01*
G01X227633Y786500D02*
Y789833D01*
G01Y789167D02*
X228050Y789500D01*
X228467Y789750D01*
X229050Y789833D01*
X229467Y789750D01*
X229967Y789500D01*
G01X234400Y789833D02*
Y786500D01*
G01Y791167D02*
X234233Y791250D01*
Y791417D01*
X234400Y791500D01*
X234567Y791417D01*
Y791250D01*
X234400Y791167D01*
G01X238583Y786500D02*
Y789833D01*
G01Y789000D02*
X238917Y789417D01*
X239417Y789750D01*
X240083Y789833D01*
X240667Y789750D01*
X241167Y789417D01*
X241417Y788833D01*
Y786500D01*
G01X245600Y791500D02*
Y786500D01*
G01X244433Y789833D02*
X246767D01*
G01X249950Y788750D02*
X252617D01*
X252367Y789333D01*
X251950Y789667D01*
X251367Y789833D01*
X250783Y789750D01*
X250283Y789500D01*
X249950Y788917D01*
X249783Y788417D01*
Y787917D01*
X249950Y787417D01*
X250367Y786917D01*
X250867Y786583D01*
X251450Y786500D01*
X252033Y786667D01*
X252617Y787167D01*
G01X258300Y791500D02*
Y786500D01*
G01Y787250D02*
X257967Y786833D01*
X257467Y786583D01*
X256883Y786500D01*
X256217Y786667D01*
X255717Y787083D01*
X255383Y787583D01*
X255300Y788167D01*
X255383Y788750D01*
X255717Y789250D01*
X256217Y789667D01*
X256883Y789833D01*
X257467Y789750D01*
X257883Y789583D01*
X258300Y789250D01*
G01X268667Y789167D02*
X269000Y789417D01*
X269250Y789833D01*
X269417Y790417D01*
X269250Y790917D01*
X268917Y791250D01*
X268333Y791500D01*
X266083D01*
Y786500D01*
X268833D01*
X269417Y786833D01*
X269750Y787333D01*
X269917Y787917D01*
X269750Y788500D01*
X269250Y789000D01*
X268667Y789167D01*
X266083D01*
G01X273600Y786500D02*
X273100Y786583D01*
X272600Y786917D01*
X272267Y787500D01*
X272100Y788167D01*
X272267Y788833D01*
X272600Y789417D01*
X273100Y789750D01*
X273600Y789833D01*
X274100Y789750D01*
X274600Y789417D01*
X274933Y788833D01*
X275017Y788167D01*
X274933Y787500D01*
X274600Y786917D01*
X274100Y786583D01*
X273600Y786500D01*
G01X280700D02*
Y789833D01*
G01Y789250D02*
X280367Y789583D01*
X279867Y789750D01*
X279283Y789833D01*
X278700Y789667D01*
X278200Y789333D01*
X277867Y788833D01*
X277700Y788167D01*
X277867Y787500D01*
X278200Y787000D01*
X278700Y786667D01*
X279283Y786500D01*
X279867Y786583D01*
X280367Y786833D01*
X280700Y787167D01*
G01X283633Y786500D02*
Y789833D01*
G01Y789167D02*
X284050Y789500D01*
X284467Y789750D01*
X285050Y789833D01*
X285467Y789750D01*
X285967Y789500D01*
G01X291900Y791500D02*
Y786500D01*
G01Y787250D02*
X291567Y786833D01*
X291067Y786583D01*
X290483Y786500D01*
X289817Y786667D01*
X289317Y787083D01*
X288983Y787583D01*
X288900Y788167D01*
X288983Y788750D01*
X289317Y789250D01*
X289817Y789667D01*
X290483Y789833D01*
X291067Y789750D01*
X291483Y789583D01*
X291900Y789250D01*
G01X294750Y787083D02*
X295167Y786750D01*
X295750Y786500D01*
X296250D01*
X296750Y786667D01*
X297083Y786917D01*
X297250Y787250D01*
X297167Y787750D01*
X296833Y788000D01*
X295333Y788500D01*
X295000Y789083D01*
X295167Y789500D01*
X295500Y789750D01*
X296000Y789833D01*
X296500Y789750D01*
X297000Y789500D01*
G01X112333Y-60000D02*
Y-65000D01*
X115667D01*
G01X119600D02*
X119100Y-64917D01*
X118600Y-64583D01*
X118267Y-64000D01*
X118100Y-63333D01*
X118267Y-62667D01*
X118600Y-62083D01*
X119100Y-61750D01*
X119600Y-61667D01*
X120100Y-61750D01*
X120600Y-62083D01*
X120933Y-62667D01*
X121017Y-63333D01*
X120933Y-64000D01*
X120600Y-64583D01*
X120100Y-64917D01*
X119600Y-65000D01*
G01X124033Y-66250D02*
X124617Y-66583D01*
X125283Y-66667D01*
X125867Y-66583D01*
X126367Y-66167D01*
X126700Y-65583D01*
Y-61667D01*
G01Y-62333D02*
X126367Y-62000D01*
X125867Y-61750D01*
X125283Y-61667D01*
X124617Y-61833D01*
X124200Y-62167D01*
X123867Y-62750D01*
X123700Y-63333D01*
X123783Y-63833D01*
X124117Y-64417D01*
X124617Y-64833D01*
X125283Y-65000D01*
X125783Y-64917D01*
X126367Y-64583D01*
X126700Y-64250D01*
G01X130800Y-65000D02*
X130300Y-64917D01*
X129800Y-64583D01*
X129467Y-64000D01*
X129300Y-63333D01*
X129467Y-62667D01*
X129800Y-62083D01*
X130300Y-61750D01*
X130800Y-61667D01*
X131300Y-61750D01*
X131800Y-62083D01*
X132133Y-62667D01*
X132217Y-63333D01*
X132133Y-64000D01*
X131800Y-64583D01*
X131300Y-64917D01*
X130800Y-65000D01*
G01X103500Y679000D02*
Y-69500D01*
G01X114000Y-36000D02*
Y-41000D01*
G01X112833Y-37667D02*
X115167D01*
G01X118183Y-41000D02*
Y-36000D01*
G01Y-38417D02*
X118600Y-38000D01*
X119017Y-37750D01*
X119683Y-37667D01*
X120183Y-37750D01*
X120767Y-38083D01*
X121017Y-38583D01*
Y-41000D01*
G01X125200Y-37667D02*
Y-41000D01*
G01Y-36333D02*
X125033Y-36250D01*
Y-36083D01*
X125200Y-36000D01*
X125367Y-36083D01*
Y-36250D01*
X125200Y-36333D01*
G01X132133Y-38083D02*
X131550Y-37750D01*
X131050Y-37667D01*
X130383Y-37833D01*
X129883Y-38167D01*
X129550Y-38750D01*
X129467Y-39333D01*
X129550Y-39917D01*
X129883Y-40417D01*
X130383Y-40833D01*
X131050Y-41000D01*
X131633Y-40833D01*
X132133Y-40500D01*
G01X134983Y-41000D02*
Y-36000D01*
G01X137650Y-37667D02*
X134983Y-39583D01*
G01X136067Y-38833D02*
X137817Y-41000D01*
G01X140583D02*
Y-37667D01*
G01Y-38500D02*
X140917Y-38083D01*
X141417Y-37750D01*
X142083Y-37667D01*
X142667Y-37750D01*
X143167Y-38083D01*
X143417Y-38667D01*
Y-41000D01*
G01X146350Y-38750D02*
X149017D01*
X148767Y-38167D01*
X148350Y-37833D01*
X147767Y-37667D01*
X147183Y-37750D01*
X146683Y-38000D01*
X146350Y-38583D01*
X146183Y-39083D01*
Y-39583D01*
X146350Y-40083D01*
X146767Y-40583D01*
X147267Y-40917D01*
X147850Y-41000D01*
X148433Y-40833D01*
X149017Y-40333D01*
G01X151950Y-40417D02*
X152367Y-40750D01*
X152950Y-41000D01*
X153450D01*
X153950Y-40833D01*
X154283Y-40583D01*
X154450Y-40250D01*
X154367Y-39750D01*
X154033Y-39500D01*
X152533Y-39000D01*
X152200Y-38417D01*
X152367Y-38000D01*
X152700Y-37750D01*
X153200Y-37667D01*
X153700Y-37750D01*
X154200Y-38000D01*
G01X157550Y-40417D02*
X157967Y-40750D01*
X158550Y-41000D01*
X159050D01*
X159550Y-40833D01*
X159883Y-40583D01*
X160050Y-40250D01*
X159967Y-39750D01*
X159633Y-39500D01*
X158133Y-39000D01*
X157800Y-38417D01*
X157967Y-38000D01*
X158300Y-37750D01*
X158800Y-37667D01*
X159300Y-37750D01*
X159800Y-38000D01*
G01X103500Y-54500D02*
X694500D01*
G01X114000Y-15000D02*
Y-20000D01*
G01X112833Y-16667D02*
X115167D01*
G01X118183Y-20000D02*
Y-15000D01*
G01Y-17417D02*
X118600Y-17000D01*
X119017Y-16750D01*
X119683Y-16667D01*
X120183Y-16750D01*
X120767Y-17083D01*
X121017Y-17583D01*
Y-20000D01*
G01X125200Y-16667D02*
Y-20000D01*
G01Y-15333D02*
X125033Y-15250D01*
Y-15083D01*
X125200Y-15000D01*
X125367Y-15083D01*
Y-15250D01*
X125200Y-15333D01*
G01X132133Y-17083D02*
X131550Y-16750D01*
X131050Y-16667D01*
X130383Y-16833D01*
X129883Y-17167D01*
X129550Y-17750D01*
X129467Y-18333D01*
X129550Y-18917D01*
X129883Y-19417D01*
X130383Y-19833D01*
X131050Y-20000D01*
X131633Y-19833D01*
X132133Y-19500D01*
G01X134983Y-20000D02*
Y-15000D01*
G01X137650Y-16667D02*
X134983Y-18583D01*
G01X136067Y-17833D02*
X137817Y-20000D01*
G01X140583D02*
Y-16667D01*
G01Y-17500D02*
X140917Y-17083D01*
X141417Y-16750D01*
X142083Y-16667D01*
X142667Y-16750D01*
X143167Y-17083D01*
X143417Y-17667D01*
Y-20000D01*
G01X146350Y-17750D02*
X149017D01*
X148767Y-17167D01*
X148350Y-16833D01*
X147767Y-16667D01*
X147183Y-16750D01*
X146683Y-17000D01*
X146350Y-17583D01*
X146183Y-18083D01*
Y-18583D01*
X146350Y-19083D01*
X146767Y-19583D01*
X147267Y-19917D01*
X147850Y-20000D01*
X148433Y-19833D01*
X149017Y-19333D01*
G01X151950Y-19417D02*
X152367Y-19750D01*
X152950Y-20000D01*
X153450D01*
X153950Y-19833D01*
X154283Y-19583D01*
X154450Y-19250D01*
X154367Y-18750D01*
X154033Y-18500D01*
X152533Y-18000D01*
X152200Y-17417D01*
X152367Y-17000D01*
X152700Y-16750D01*
X153200Y-16667D01*
X153700Y-16750D01*
X154200Y-17000D01*
G01X157550Y-19417D02*
X157967Y-19750D01*
X158550Y-20000D01*
X159050D01*
X159550Y-19833D01*
X159883Y-19583D01*
X160050Y-19250D01*
X159967Y-18750D01*
X159633Y-18500D01*
X158133Y-18000D01*
X157800Y-17417D01*
X157967Y-17000D01*
X158300Y-16750D01*
X158800Y-16667D01*
X159300Y-16750D01*
X159800Y-17000D01*
G01X119183Y-2167D02*
X118350Y-1333D01*
X117933Y-500D01*
Y2833D01*
X118350Y3667D01*
X119183Y4500D01*
G01X123450Y167D02*
X124117Y-250D01*
X124867Y-500D01*
X125533D01*
X126200Y-250D01*
X126700Y167D01*
X126950Y750D01*
X126783Y1333D01*
X126367Y1833D01*
X125617Y2167D01*
X124617Y2333D01*
X124033Y2667D01*
X123783Y3250D01*
X123950Y3833D01*
X124367Y4250D01*
X124950Y4500D01*
X125533D01*
X126117Y4333D01*
X126617Y3917D01*
G01X128633Y-500D02*
Y4500D01*
X130800Y333D01*
X132967Y4500D01*
Y-500D01*
G01X134567D02*
Y4500D01*
X136233D01*
X136900Y4250D01*
X137400Y3917D01*
X137817Y3417D01*
X138150Y2833D01*
X138233Y2000D01*
X138150Y1167D01*
X137817Y583D01*
X137400Y83D01*
X136900Y-250D01*
X136233Y-500D01*
X134567D01*
G01X142417Y-2167D02*
X143250Y-1333D01*
X143667Y-500D01*
Y2833D01*
X143250Y3667D01*
X142417Y4500D01*
G01X103500Y-9500D02*
X694500D01*
G01X112483Y24700D02*
Y29700D01*
X114650Y25533D01*
X116817Y29700D01*
Y24700D01*
G01X121750D02*
Y28033D01*
G01Y27450D02*
X121417Y27783D01*
X120917Y27950D01*
X120333Y28033D01*
X119750Y27867D01*
X119250Y27533D01*
X118917Y27033D01*
X118750Y26367D01*
X118917Y25700D01*
X119250Y25200D01*
X119750Y24867D01*
X120333Y24700D01*
X120917Y24783D01*
X121417Y25033D01*
X121750Y25367D01*
G01X124683Y24700D02*
Y28033D01*
G01Y27367D02*
X125100Y27700D01*
X125517Y27950D01*
X126100Y28033D01*
X126517Y27950D01*
X127017Y27700D01*
G01X130033Y24700D02*
Y29700D01*
G01X132700Y28033D02*
X130033Y26117D01*
G01X131117Y26867D02*
X132867Y24700D01*
G01X137467Y23033D02*
X138300Y23867D01*
X138717Y24700D01*
Y28033D01*
X138300Y28867D01*
X137467Y29700D01*
G01X113070Y36130D02*
X114737D01*
Y34630D01*
X114237Y34130D01*
X113653Y33797D01*
X112820Y33630D01*
X111987Y33797D01*
X111403Y34130D01*
X110903Y34630D01*
X110570Y35213D01*
X110403Y35880D01*
Y36463D01*
X110570Y36963D01*
X110903Y37547D01*
X111403Y38047D01*
X111903Y38380D01*
X112570Y38630D01*
X113153D01*
X113820Y38463D01*
X114320Y38130D01*
G01X118170Y33630D02*
X117670Y33713D01*
X117170Y34047D01*
X116837Y34630D01*
X116670Y35297D01*
X116837Y35963D01*
X117170Y36547D01*
X117670Y36880D01*
X118170Y36963D01*
X118670Y36880D01*
X119170Y36547D01*
X119503Y35963D01*
X119587Y35297D01*
X119503Y34630D01*
X119170Y34047D01*
X118670Y33713D01*
X118170Y33630D01*
G01X123770D02*
Y38630D01*
G01X130870D02*
Y33630D01*
G01Y34380D02*
X130537Y33963D01*
X130037Y33713D01*
X129453Y33630D01*
X128787Y33797D01*
X128287Y34213D01*
X127953Y34713D01*
X127870Y35297D01*
X127953Y35880D01*
X128287Y36380D01*
X128787Y36797D01*
X129453Y36963D01*
X130037Y36880D01*
X130453Y36713D01*
X130870Y36380D01*
G01X133720Y35880D02*
X136387D01*
X136137Y36463D01*
X135720Y36797D01*
X135137Y36963D01*
X134553Y36880D01*
X134053Y36630D01*
X133720Y36047D01*
X133553Y35547D01*
Y35047D01*
X133720Y34547D01*
X134137Y34047D01*
X134637Y33713D01*
X135220Y33630D01*
X135803Y33797D01*
X136387Y34297D01*
G01X139153Y33630D02*
Y36963D01*
G01Y36130D02*
X139487Y36547D01*
X139987Y36880D01*
X140653Y36963D01*
X141237Y36880D01*
X141737Y36547D01*
X141987Y35963D01*
Y33630D01*
G01X151270D02*
Y37880D01*
X151437Y38297D01*
X151770Y38547D01*
X152270Y38630D01*
X152770Y38463D01*
X153020Y38047D01*
G01X152020Y36630D02*
X150353D01*
G01X157370Y36963D02*
Y33630D01*
G01Y38297D02*
X157203Y38380D01*
Y38547D01*
X157370Y38630D01*
X157537Y38547D01*
Y38380D01*
X157370Y38297D01*
G01X161553Y33630D02*
Y36963D01*
G01Y36130D02*
X161887Y36547D01*
X162387Y36880D01*
X163053Y36963D01*
X163637Y36880D01*
X164137Y36547D01*
X164387Y35963D01*
Y33630D01*
G01X167403Y32380D02*
X167987Y32047D01*
X168653Y31963D01*
X169237Y32047D01*
X169737Y32463D01*
X170070Y33047D01*
Y36963D01*
G01Y36297D02*
X169737Y36630D01*
X169237Y36880D01*
X168653Y36963D01*
X167987Y36797D01*
X167570Y36463D01*
X167237Y35880D01*
X167070Y35297D01*
X167153Y34797D01*
X167487Y34213D01*
X167987Y33797D01*
X168653Y33630D01*
X169153Y33713D01*
X169737Y34047D01*
X170070Y34380D01*
G01X172920Y35880D02*
X175587D01*
X175337Y36463D01*
X174920Y36797D01*
X174337Y36963D01*
X173753Y36880D01*
X173253Y36630D01*
X172920Y36047D01*
X172753Y35547D01*
Y35047D01*
X172920Y34547D01*
X173337Y34047D01*
X173837Y33713D01*
X174420Y33630D01*
X175003Y33797D01*
X175587Y34297D01*
G01X178603Y33630D02*
Y36963D01*
G01Y36297D02*
X179020Y36630D01*
X179437Y36880D01*
X180020Y36963D01*
X180437Y36880D01*
X180937Y36630D01*
G01X189303Y33630D02*
Y38630D01*
X191303D01*
X191970Y38380D01*
X192470Y37797D01*
X192637Y37130D01*
X192470Y36463D01*
X192053Y35963D01*
X191303Y35713D01*
X189303D01*
G01X194487Y33630D02*
X196570Y38630D01*
X198653Y33630D01*
G01X197903Y35380D02*
X195237D01*
G01X200337Y33630D02*
Y38630D01*
X202003D01*
X202670Y38380D01*
X203170Y38047D01*
X203587Y37547D01*
X203920Y36963D01*
X204003Y36130D01*
X203920Y35297D01*
X203587Y34713D01*
X203170Y34213D01*
X202670Y33880D01*
X202003Y33630D01*
X200337D01*
G01X211870Y33463D02*
X214870Y38630D01*
G01X217387Y33630D02*
Y38630D01*
X220553D01*
G01X219387Y36213D02*
X217387D01*
G01X224570Y36963D02*
Y33630D01*
G01Y38297D02*
X224403Y38380D01*
Y38547D01*
X224570Y38630D01*
X224737Y38547D01*
Y38380D01*
X224570Y38297D01*
G01X231670Y38630D02*
Y33630D01*
G01Y34380D02*
X231337Y33963D01*
X230837Y33713D01*
X230253Y33630D01*
X229587Y33797D01*
X229087Y34213D01*
X228753Y34713D01*
X228670Y35297D01*
X228753Y35880D01*
X229087Y36380D01*
X229587Y36797D01*
X230253Y36963D01*
X230837Y36880D01*
X231253Y36713D01*
X231670Y36380D01*
G01X234353Y36963D02*
Y34630D01*
X234687Y34047D01*
X235187Y33713D01*
X235770Y33630D01*
X236353Y33713D01*
X236853Y34047D01*
X237187Y34630D01*
G01Y33630D02*
Y36963D01*
G01X242703Y36547D02*
X242120Y36880D01*
X241620Y36963D01*
X240953Y36797D01*
X240453Y36463D01*
X240120Y35880D01*
X240037Y35297D01*
X240120Y34713D01*
X240453Y34213D01*
X240953Y33797D01*
X241620Y33630D01*
X242203Y33797D01*
X242703Y34130D01*
G01X246970Y36963D02*
Y33630D01*
G01Y38297D02*
X246803Y38380D01*
Y38547D01*
X246970Y38630D01*
X247137Y38547D01*
Y38380D01*
X246970Y38297D01*
G01X254070Y33630D02*
Y36963D01*
G01Y36380D02*
X253737Y36713D01*
X253237Y36880D01*
X252653Y36963D01*
X252070Y36797D01*
X251570Y36463D01*
X251237Y35963D01*
X251070Y35297D01*
X251237Y34630D01*
X251570Y34130D01*
X252070Y33797D01*
X252653Y33630D01*
X253237Y33713D01*
X253737Y33963D01*
X254070Y34297D01*
G01X258170Y33630D02*
Y38630D01*
G01X112250Y12167D02*
X112917Y11750D01*
X113667Y11500D01*
X114333D01*
X115000Y11750D01*
X115500Y12167D01*
X115750Y12750D01*
X115583Y13333D01*
X115167Y13833D01*
X114417Y14167D01*
X113417Y14333D01*
X112833Y14667D01*
X112583Y15250D01*
X112750Y15833D01*
X113167Y16250D01*
X113750Y16500D01*
X114333D01*
X114917Y16333D01*
X115417Y15917D01*
G01X119600Y11500D02*
X119100Y11583D01*
X118600Y11917D01*
X118267Y12500D01*
X118100Y13167D01*
X118267Y13833D01*
X118600Y14417D01*
X119100Y14750D01*
X119600Y14833D01*
X120100Y14750D01*
X120600Y14417D01*
X120933Y13833D01*
X121017Y13167D01*
X120933Y12500D01*
X120600Y11917D01*
X120100Y11583D01*
X119600Y11500D01*
G01X125200D02*
Y16500D01*
G01X132300D02*
Y11500D01*
G01Y12250D02*
X131967Y11833D01*
X131467Y11583D01*
X130883Y11500D01*
X130217Y11667D01*
X129717Y12083D01*
X129383Y12583D01*
X129300Y13167D01*
X129383Y13750D01*
X129717Y14250D01*
X130217Y14667D01*
X130883Y14833D01*
X131467Y14750D01*
X131883Y14583D01*
X132300Y14250D01*
G01X135150Y13750D02*
X137817D01*
X137567Y14333D01*
X137150Y14667D01*
X136567Y14833D01*
X135983Y14750D01*
X135483Y14500D01*
X135150Y13917D01*
X134983Y13417D01*
Y12917D01*
X135150Y12417D01*
X135567Y11917D01*
X136067Y11583D01*
X136650Y11500D01*
X137233Y11667D01*
X137817Y12167D01*
G01X140833Y11500D02*
Y14833D01*
G01Y14167D02*
X141250Y14500D01*
X141667Y14750D01*
X142250Y14833D01*
X142667Y14750D01*
X143167Y14500D01*
G01X150700Y11500D02*
Y14833D01*
G01Y13917D02*
X150950Y14333D01*
X151367Y14667D01*
X151950Y14833D01*
X152533Y14667D01*
X152950Y14333D01*
X153200Y13917D01*
Y11500D01*
G01Y13917D02*
X153450Y14333D01*
X153867Y14667D01*
X154450Y14833D01*
X155033Y14667D01*
X155450Y14333D01*
X155700Y13833D01*
Y11500D01*
G01X160300D02*
Y14833D01*
G01Y14250D02*
X159967Y14583D01*
X159467Y14750D01*
X158883Y14833D01*
X158300Y14667D01*
X157800Y14333D01*
X157467Y13833D01*
X157300Y13167D01*
X157467Y12500D01*
X157800Y12000D01*
X158300Y11667D01*
X158883Y11500D01*
X159467Y11583D01*
X159967Y11833D01*
X160300Y12167D01*
G01X163150Y12083D02*
X163567Y11750D01*
X164150Y11500D01*
X164650D01*
X165150Y11667D01*
X165483Y11917D01*
X165650Y12250D01*
X165567Y12750D01*
X165233Y13000D01*
X163733Y13500D01*
X163400Y14083D01*
X163567Y14500D01*
X163900Y14750D01*
X164400Y14833D01*
X164900Y14750D01*
X165400Y14500D01*
G01X168583Y11500D02*
Y16500D01*
G01X171250Y14833D02*
X168583Y12917D01*
G01X169667Y13667D02*
X171417Y11500D01*
G01X182700Y16500D02*
Y11500D01*
G01Y12250D02*
X182367Y11833D01*
X181867Y11583D01*
X181283Y11500D01*
X180617Y11667D01*
X180117Y12083D01*
X179783Y12583D01*
X179700Y13167D01*
X179783Y13750D01*
X180117Y14250D01*
X180617Y14667D01*
X181283Y14833D01*
X181867Y14750D01*
X182283Y14583D01*
X182700Y14250D01*
G01X185550Y13750D02*
X188217D01*
X187967Y14333D01*
X187550Y14667D01*
X186967Y14833D01*
X186383Y14750D01*
X185883Y14500D01*
X185550Y13917D01*
X185383Y13417D01*
Y12917D01*
X185550Y12417D01*
X185967Y11917D01*
X186467Y11583D01*
X187050Y11500D01*
X187633Y11667D01*
X188217Y12167D01*
G01X191900Y11500D02*
Y15750D01*
X192067Y16167D01*
X192400Y16417D01*
X192900Y16500D01*
X193400Y16333D01*
X193650Y15917D01*
G01X192650Y14500D02*
X190983D01*
G01X198000Y14833D02*
Y11500D01*
G01Y16167D02*
X197833Y16250D01*
Y16417D01*
X198000Y16500D01*
X198167Y16417D01*
Y16250D01*
X198000Y16167D01*
G01X202183Y11500D02*
Y14833D01*
G01Y14000D02*
X202517Y14417D01*
X203017Y14750D01*
X203683Y14833D01*
X204267Y14750D01*
X204767Y14417D01*
X205017Y13833D01*
Y11500D01*
G01X207950Y13750D02*
X210617D01*
X210367Y14333D01*
X209950Y14667D01*
X209367Y14833D01*
X208783Y14750D01*
X208283Y14500D01*
X207950Y13917D01*
X207783Y13417D01*
Y12917D01*
X207950Y12417D01*
X208367Y11917D01*
X208867Y11583D01*
X209450Y11500D01*
X210033Y11667D01*
X210617Y12167D01*
G01X218900Y9833D02*
Y14833D01*
G01Y14083D02*
X219317Y14500D01*
X219733Y14750D01*
X220400Y14833D01*
X220983Y14750D01*
X221567Y14333D01*
X221817Y13750D01*
X221900Y13167D01*
X221817Y12583D01*
X221567Y12000D01*
X221067Y11667D01*
X220400Y11500D01*
X219817Y11583D01*
X219233Y11833D01*
X218900Y12167D01*
G01X227500Y11500D02*
Y14833D01*
G01Y14250D02*
X227167Y14583D01*
X226667Y14750D01*
X226083Y14833D01*
X225500Y14667D01*
X225000Y14333D01*
X224667Y13833D01*
X224500Y13167D01*
X224667Y12500D01*
X225000Y12000D01*
X225500Y11667D01*
X226083Y11500D01*
X226667Y11583D01*
X227167Y11833D01*
X227500Y12167D01*
G01X233100Y16500D02*
Y11500D01*
G01Y12250D02*
X232767Y11833D01*
X232267Y11583D01*
X231683Y11500D01*
X231017Y11667D01*
X230517Y12083D01*
X230183Y12583D01*
X230100Y13167D01*
X230183Y13750D01*
X230517Y14250D01*
X231017Y14667D01*
X231683Y14833D01*
X232267Y14750D01*
X232683Y14583D01*
X233100Y14250D01*
G01X112743Y42673D02*
X111910Y43507D01*
X111493Y44340D01*
Y47673D01*
X111910Y48507D01*
X112743Y49340D01*
G01X116260Y44340D02*
Y47673D01*
G01Y46757D02*
X116510Y47173D01*
X116927Y47507D01*
X117510Y47673D01*
X118093Y47507D01*
X118510Y47173D01*
X118760Y46757D01*
Y44340D01*
G01Y46757D02*
X119010Y47173D01*
X119427Y47507D01*
X120010Y47673D01*
X120593Y47507D01*
X121010Y47173D01*
X121260Y46673D01*
Y44340D01*
G01X123110Y46590D02*
X125777D01*
X125527Y47173D01*
X125110Y47507D01*
X124527Y47673D01*
X123943Y47590D01*
X123443Y47340D01*
X123110Y46757D01*
X122943Y46257D01*
Y45757D01*
X123110Y45257D01*
X123527Y44757D01*
X124027Y44423D01*
X124610Y44340D01*
X125193Y44507D01*
X125777Y45007D01*
G01X131460Y44340D02*
Y47673D01*
G01Y47090D02*
X131127Y47423D01*
X130627Y47590D01*
X130043Y47673D01*
X129460Y47507D01*
X128960Y47173D01*
X128627Y46673D01*
X128460Y46007D01*
X128627Y45340D01*
X128960Y44840D01*
X129460Y44507D01*
X130043Y44340D01*
X130627Y44423D01*
X131127Y44673D01*
X131460Y45007D01*
G01X134310Y44923D02*
X134727Y44590D01*
X135310Y44340D01*
X135810D01*
X136310Y44507D01*
X136643Y44757D01*
X136810Y45090D01*
X136727Y45590D01*
X136393Y45840D01*
X134893Y46340D01*
X134560Y46923D01*
X134727Y47340D01*
X135060Y47590D01*
X135560Y47673D01*
X136060Y47590D01*
X136560Y47340D01*
G01X139743Y47673D02*
Y45340D01*
X140077Y44757D01*
X140577Y44423D01*
X141160Y44340D01*
X141743Y44423D01*
X142243Y44757D01*
X142577Y45340D01*
G01Y44340D02*
Y47673D01*
G01X145593Y44340D02*
Y47673D01*
G01Y47007D02*
X146010Y47340D01*
X146427Y47590D01*
X147010Y47673D01*
X147427Y47590D01*
X147927Y47340D01*
G01X151110Y46590D02*
X153777D01*
X153527Y47173D01*
X153110Y47507D01*
X152527Y47673D01*
X151943Y47590D01*
X151443Y47340D01*
X151110Y46757D01*
X150943Y46257D01*
Y45757D01*
X151110Y45257D01*
X151527Y44757D01*
X152027Y44423D01*
X152610Y44340D01*
X153193Y44507D01*
X153777Y45007D01*
G01X163560Y49340D02*
Y44340D01*
G01X162393Y47673D02*
X164727D01*
G01X169160Y44340D02*
X168660Y44423D01*
X168160Y44757D01*
X167827Y45340D01*
X167660Y46007D01*
X167827Y46673D01*
X168160Y47257D01*
X168660Y47590D01*
X169160Y47673D01*
X169660Y47590D01*
X170160Y47257D01*
X170493Y46673D01*
X170577Y46007D01*
X170493Y45340D01*
X170160Y44757D01*
X169660Y44423D01*
X169160Y44340D01*
G01X173260Y42673D02*
Y47673D01*
G01Y46923D02*
X173677Y47340D01*
X174093Y47590D01*
X174760Y47673D01*
X175343Y47590D01*
X175927Y47173D01*
X176177Y46590D01*
X176260Y46007D01*
X176177Y45423D01*
X175927Y44840D01*
X175427Y44507D01*
X174760Y44340D01*
X174177Y44423D01*
X173593Y44673D01*
X173260Y45007D01*
G01X184710Y44923D02*
X185127Y44590D01*
X185710Y44340D01*
X186210D01*
X186710Y44507D01*
X187043Y44757D01*
X187210Y45090D01*
X187127Y45590D01*
X186793Y45840D01*
X185293Y46340D01*
X184960Y46923D01*
X185127Y47340D01*
X185460Y47590D01*
X185960Y47673D01*
X186460Y47590D01*
X186960Y47340D01*
G01X191560Y47673D02*
Y44340D01*
G01Y49007D02*
X191393Y49090D01*
Y49257D01*
X191560Y49340D01*
X191727Y49257D01*
Y49090D01*
X191560Y49007D01*
G01X195910Y47673D02*
X198410D01*
X195910Y44340D01*
X198410D01*
G01X201510Y46590D02*
X204177D01*
X203927Y47173D01*
X203510Y47507D01*
X202927Y47673D01*
X202343Y47590D01*
X201843Y47340D01*
X201510Y46757D01*
X201343Y46257D01*
Y45757D01*
X201510Y45257D01*
X201927Y44757D01*
X202427Y44423D01*
X203010Y44340D01*
X203593Y44507D01*
X204177Y45007D01*
G01X213960Y44340D02*
X213460Y44423D01*
X212960Y44757D01*
X212627Y45340D01*
X212460Y46007D01*
X212627Y46673D01*
X212960Y47257D01*
X213460Y47590D01*
X213960Y47673D01*
X214460Y47590D01*
X214960Y47257D01*
X215293Y46673D01*
X215377Y46007D01*
X215293Y45340D01*
X214960Y44757D01*
X214460Y44423D01*
X213960Y44340D01*
G01X219060D02*
Y48590D01*
X219227Y49007D01*
X219560Y49257D01*
X220060Y49340D01*
X220560Y49173D01*
X220810Y48757D01*
G01X219810Y47340D02*
X218143D01*
G01X229093Y44340D02*
Y49340D01*
X231093D01*
X231760Y49090D01*
X232260Y48507D01*
X232427Y47840D01*
X232260Y47173D01*
X231843Y46673D01*
X231093Y46423D01*
X229093D01*
G01X234277Y44340D02*
X236360Y49340D01*
X238443Y44340D01*
G01X237693Y46090D02*
X235027D01*
G01X240127Y44340D02*
Y49340D01*
X241793D01*
X242460Y49090D01*
X242960Y48757D01*
X243377Y48257D01*
X243710Y47673D01*
X243793Y46840D01*
X243710Y46007D01*
X243377Y45423D01*
X242960Y44923D01*
X242460Y44590D01*
X241793Y44340D01*
X240127D01*
G01X251660Y44173D02*
X254660Y49340D01*
G01X112333Y51500D02*
Y56500D01*
X114333D01*
X115000Y56250D01*
X115500Y55667D01*
X115667Y55000D01*
X115500Y54333D01*
X115083Y53833D01*
X114333Y53583D01*
X112333D01*
G01X117517Y51500D02*
X119600Y56500D01*
X121683Y51500D01*
G01X120933Y53250D02*
X118267D01*
G01X123367Y51500D02*
Y56500D01*
X125033D01*
X125700Y56250D01*
X126200Y55917D01*
X126617Y55417D01*
X126950Y54833D01*
X127033Y54000D01*
X126950Y53167D01*
X126617Y52583D01*
X126200Y52083D01*
X125700Y51750D01*
X125033Y51500D01*
X123367D01*
G01X135150Y52083D02*
X135567Y51750D01*
X136150Y51500D01*
X136650D01*
X137150Y51667D01*
X137483Y51917D01*
X137650Y52250D01*
X137567Y52750D01*
X137233Y53000D01*
X135733Y53500D01*
X135400Y54083D01*
X135567Y54500D01*
X135900Y54750D01*
X136400Y54833D01*
X136900Y54750D01*
X137400Y54500D01*
G01X142000Y54833D02*
Y51500D01*
G01Y56167D02*
X141833Y56250D01*
Y56417D01*
X142000Y56500D01*
X142167Y56417D01*
Y56250D01*
X142000Y56167D01*
G01X146350Y54833D02*
X148850D01*
X146350Y51500D01*
X148850D01*
G01X151950Y53750D02*
X154617D01*
X154367Y54333D01*
X153950Y54667D01*
X153367Y54833D01*
X152783Y54750D01*
X152283Y54500D01*
X151950Y53917D01*
X151783Y53417D01*
Y52917D01*
X151950Y52417D01*
X152367Y51917D01*
X152867Y51583D01*
X153450Y51500D01*
X154033Y51667D01*
X154617Y52167D01*
G01X103500Y60500D02*
X694500D01*
G01X114000Y85000D02*
Y80000D01*
G01X112083Y85000D02*
X115917D01*
G01X118433Y80000D02*
Y83333D01*
G01Y82667D02*
X118850Y83000D01*
X119267Y83250D01*
X119850Y83333D01*
X120267Y83250D01*
X120767Y83000D01*
G01X126700Y80000D02*
Y83333D01*
G01Y82750D02*
X126367Y83083D01*
X125867Y83250D01*
X125283Y83333D01*
X124700Y83167D01*
X124200Y82833D01*
X123867Y82333D01*
X123700Y81667D01*
X123867Y81000D01*
X124200Y80500D01*
X124700Y80167D01*
X125283Y80000D01*
X125867Y80083D01*
X126367Y80333D01*
X126700Y80667D01*
G01X132133Y82917D02*
X131550Y83250D01*
X131050Y83333D01*
X130383Y83167D01*
X129883Y82833D01*
X129550Y82250D01*
X129467Y81667D01*
X129550Y81083D01*
X129883Y80583D01*
X130383Y80167D01*
X131050Y80000D01*
X131633Y80167D01*
X132133Y80500D01*
G01X135150Y82250D02*
X137817D01*
X137567Y82833D01*
X137150Y83167D01*
X136567Y83333D01*
X135983Y83250D01*
X135483Y83000D01*
X135150Y82417D01*
X134983Y81917D01*
Y81417D01*
X135150Y80917D01*
X135567Y80417D01*
X136067Y80083D01*
X136650Y80000D01*
X137233Y80167D01*
X137817Y80667D01*
G01X145517Y83333D02*
X146517Y80000D01*
X147600Y83333D01*
X148683Y80000D01*
X149683Y83333D01*
G01X153200D02*
Y80000D01*
G01Y84667D02*
X153033Y84750D01*
Y84917D01*
X153200Y85000D01*
X153367Y84917D01*
Y84750D01*
X153200Y84667D01*
G01X160300Y85000D02*
Y80000D01*
G01Y80750D02*
X159967Y80333D01*
X159467Y80083D01*
X158883Y80000D01*
X158217Y80167D01*
X157717Y80583D01*
X157383Y81083D01*
X157300Y81667D01*
X157383Y82250D01*
X157717Y82750D01*
X158217Y83167D01*
X158883Y83333D01*
X159467Y83250D01*
X159883Y83083D01*
X160300Y82750D01*
G01X164400Y85000D02*
Y80000D01*
G01X163233Y83333D02*
X165567D01*
G01X168583Y80000D02*
Y85000D01*
G01Y82583D02*
X169000Y83000D01*
X169417Y83250D01*
X170083Y83333D01*
X170583Y83250D01*
X171167Y82917D01*
X171417Y82417D01*
Y80000D01*
G01X112333Y111500D02*
Y116500D01*
X114417D01*
X115083Y116250D01*
X115500Y115917D01*
X115667Y115250D01*
X115500Y114583D01*
X115000Y114167D01*
X114417Y113917D01*
X112333D01*
G01X114417D02*
X115667Y111500D01*
G01X118350Y113750D02*
X121017D01*
X120767Y114333D01*
X120350Y114667D01*
X119767Y114833D01*
X119183Y114750D01*
X118683Y114500D01*
X118350Y113917D01*
X118183Y113417D01*
Y112917D01*
X118350Y112417D01*
X118767Y111917D01*
X119267Y111583D01*
X119850Y111500D01*
X120433Y111667D01*
X121017Y112167D01*
G01X125200Y111500D02*
Y116500D01*
G01X132300Y111500D02*
Y114833D01*
G01Y114250D02*
X131967Y114583D01*
X131467Y114750D01*
X130883Y114833D01*
X130300Y114667D01*
X129800Y114333D01*
X129467Y113833D01*
X129300Y113167D01*
X129467Y112500D01*
X129800Y112000D01*
X130300Y111667D01*
X130883Y111500D01*
X131467Y111583D01*
X131967Y111833D01*
X132300Y112167D01*
G01X136400Y116500D02*
Y111500D01*
G01X135233Y114833D02*
X137567D01*
G01X142000D02*
Y111500D01*
G01Y116167D02*
X141833Y116250D01*
Y116417D01*
X142000Y116500D01*
X142167Y116417D01*
Y116250D01*
X142000Y116167D01*
G01X146100Y114833D02*
X147600Y111500D01*
X149100Y114833D01*
G01X151950Y113750D02*
X154617D01*
X154367Y114333D01*
X153950Y114667D01*
X153367Y114833D01*
X152783Y114750D01*
X152283Y114500D01*
X151950Y113917D01*
X151783Y113417D01*
Y112917D01*
X151950Y112417D01*
X152367Y111917D01*
X152867Y111583D01*
X153450Y111500D01*
X154033Y111667D01*
X154617Y112167D01*
G01X162900Y109833D02*
Y114833D01*
G01Y114083D02*
X163317Y114500D01*
X163733Y114750D01*
X164400Y114833D01*
X164983Y114750D01*
X165567Y114333D01*
X165817Y113750D01*
X165900Y113167D01*
X165817Y112583D01*
X165567Y112000D01*
X165067Y111667D01*
X164400Y111500D01*
X163817Y111583D01*
X163233Y111833D01*
X162900Y112167D01*
G01X170000Y111500D02*
X169500Y111583D01*
X169000Y111917D01*
X168667Y112500D01*
X168500Y113167D01*
X168667Y113833D01*
X169000Y114417D01*
X169500Y114750D01*
X170000Y114833D01*
X170500Y114750D01*
X171000Y114417D01*
X171333Y113833D01*
X171417Y113167D01*
X171333Y112500D01*
X171000Y111917D01*
X170500Y111583D01*
X170000Y111500D01*
G01X174350Y112083D02*
X174767Y111750D01*
X175350Y111500D01*
X175850D01*
X176350Y111667D01*
X176683Y111917D01*
X176850Y112250D01*
X176767Y112750D01*
X176433Y113000D01*
X174933Y113500D01*
X174600Y114083D01*
X174767Y114500D01*
X175100Y114750D01*
X175600Y114833D01*
X176100Y114750D01*
X176600Y114500D01*
G01X181200Y114833D02*
Y111500D01*
G01Y116167D02*
X181033Y116250D01*
Y116417D01*
X181200Y116500D01*
X181367Y116417D01*
Y116250D01*
X181200Y116167D01*
G01X186800Y116500D02*
Y111500D01*
G01X185633Y114833D02*
X187967D01*
G01X192400D02*
Y111500D01*
G01Y116167D02*
X192233Y116250D01*
Y116417D01*
X192400Y116500D01*
X192567Y116417D01*
Y116250D01*
X192400Y116167D01*
G01X198000Y111500D02*
X197500Y111583D01*
X197000Y111917D01*
X196667Y112500D01*
X196500Y113167D01*
X196667Y113833D01*
X197000Y114417D01*
X197500Y114750D01*
X198000Y114833D01*
X198500Y114750D01*
X199000Y114417D01*
X199333Y113833D01*
X199417Y113167D01*
X199333Y112500D01*
X199000Y111917D01*
X198500Y111583D01*
X198000Y111500D01*
G01X202183D02*
Y114833D01*
G01Y114000D02*
X202517Y114417D01*
X203017Y114750D01*
X203683Y114833D01*
X204267Y114750D01*
X204767Y114417D01*
X205017Y113833D01*
Y111500D01*
G01X114000Y143500D02*
Y138500D01*
G01X112833Y141833D02*
X115167D01*
G01X118183Y138500D02*
Y143500D01*
G01Y141083D02*
X118600Y141500D01*
X119017Y141750D01*
X119683Y141833D01*
X120183Y141750D01*
X120767Y141417D01*
X121017Y140917D01*
Y138500D01*
G01X125200Y141833D02*
Y138500D01*
G01Y143167D02*
X125033Y143250D01*
Y143417D01*
X125200Y143500D01*
X125367Y143417D01*
Y143250D01*
X125200Y143167D01*
G01X132133Y141417D02*
X131550Y141750D01*
X131050Y141833D01*
X130383Y141667D01*
X129883Y141333D01*
X129550Y140750D01*
X129467Y140167D01*
X129550Y139583D01*
X129883Y139083D01*
X130383Y138667D01*
X131050Y138500D01*
X131633Y138667D01*
X132133Y139000D01*
G01X134983Y138500D02*
Y143500D01*
G01X137650Y141833D02*
X134983Y139917D01*
G01X136067Y140667D02*
X137817Y138500D01*
G01X140583D02*
Y141833D01*
G01Y141000D02*
X140917Y141417D01*
X141417Y141750D01*
X142083Y141833D01*
X142667Y141750D01*
X143167Y141417D01*
X143417Y140833D01*
Y138500D01*
G01X146350Y140750D02*
X149017D01*
X148767Y141333D01*
X148350Y141667D01*
X147767Y141833D01*
X147183Y141750D01*
X146683Y141500D01*
X146350Y140917D01*
X146183Y140417D01*
Y139917D01*
X146350Y139417D01*
X146767Y138917D01*
X147267Y138583D01*
X147850Y138500D01*
X148433Y138667D01*
X149017Y139167D01*
G01X151950Y139083D02*
X152367Y138750D01*
X152950Y138500D01*
X153450D01*
X153950Y138667D01*
X154283Y138917D01*
X154450Y139250D01*
X154367Y139750D01*
X154033Y140000D01*
X152533Y140500D01*
X152200Y141083D01*
X152367Y141500D01*
X152700Y141750D01*
X153200Y141833D01*
X153700Y141750D01*
X154200Y141500D01*
G01X157550Y139083D02*
X157967Y138750D01*
X158550Y138500D01*
X159050D01*
X159550Y138667D01*
X159883Y138917D01*
X160050Y139250D01*
X159967Y139750D01*
X159633Y140000D01*
X158133Y140500D01*
X157800Y141083D01*
X157967Y141500D01*
X158300Y141750D01*
X158800Y141833D01*
X159300Y141750D01*
X159800Y141500D01*
G01X171500Y138500D02*
Y141833D01*
G01Y141250D02*
X171167Y141583D01*
X170667Y141750D01*
X170083Y141833D01*
X169500Y141667D01*
X169000Y141333D01*
X168667Y140833D01*
X168500Y140167D01*
X168667Y139500D01*
X169000Y139000D01*
X169500Y138667D01*
X170083Y138500D01*
X170667Y138583D01*
X171167Y138833D01*
X171500Y139167D01*
G01X175100Y138500D02*
Y142750D01*
X175267Y143167D01*
X175600Y143417D01*
X176100Y143500D01*
X176600Y143333D01*
X176850Y142917D01*
G01X175850Y141500D02*
X174183D01*
G01X181200Y143500D02*
Y138500D01*
G01X180033Y141833D02*
X182367D01*
G01X185550Y140750D02*
X188217D01*
X187967Y141333D01*
X187550Y141667D01*
X186967Y141833D01*
X186383Y141750D01*
X185883Y141500D01*
X185550Y140917D01*
X185383Y140417D01*
Y139917D01*
X185550Y139417D01*
X185967Y138917D01*
X186467Y138583D01*
X187050Y138500D01*
X187633Y138667D01*
X188217Y139167D01*
G01X191233Y138500D02*
Y141833D01*
G01Y141167D02*
X191650Y141500D01*
X192067Y141750D01*
X192650Y141833D01*
X193067Y141750D01*
X193567Y141500D01*
G01X202100Y136833D02*
Y141833D01*
G01Y141083D02*
X202517Y141500D01*
X202933Y141750D01*
X203600Y141833D01*
X204183Y141750D01*
X204767Y141333D01*
X205017Y140750D01*
X205100Y140167D01*
X205017Y139583D01*
X204767Y139000D01*
X204267Y138667D01*
X203600Y138500D01*
X203017Y138583D01*
X202433Y138833D01*
X202100Y139167D01*
G01X209200Y138500D02*
Y143500D01*
G01X216300Y138500D02*
Y141833D01*
G01Y141250D02*
X215967Y141583D01*
X215467Y141750D01*
X214883Y141833D01*
X214300Y141667D01*
X213800Y141333D01*
X213467Y140833D01*
X213300Y140167D01*
X213467Y139500D01*
X213800Y139000D01*
X214300Y138667D01*
X214883Y138500D01*
X215467Y138583D01*
X215967Y138833D01*
X216300Y139167D01*
G01X220400Y143500D02*
Y138500D01*
G01X219233Y141833D02*
X221567D01*
G01X226000D02*
Y138500D01*
G01Y143167D02*
X225833Y143250D01*
Y143417D01*
X226000Y143500D01*
X226167Y143417D01*
Y143250D01*
X226000Y143167D01*
G01X230183Y138500D02*
Y141833D01*
G01Y141000D02*
X230517Y141417D01*
X231017Y141750D01*
X231683Y141833D01*
X232267Y141750D01*
X232767Y141417D01*
X233017Y140833D01*
Y138500D01*
G01X236033Y137250D02*
X236617Y136917D01*
X237283Y136833D01*
X237867Y136917D01*
X238367Y137333D01*
X238700Y137917D01*
Y141833D01*
G01Y141167D02*
X238367Y141500D01*
X237867Y141750D01*
X237283Y141833D01*
X236617Y141667D01*
X236200Y141333D01*
X235867Y140750D01*
X235700Y140167D01*
X235783Y139667D01*
X236117Y139083D01*
X236617Y138667D01*
X237283Y138500D01*
X237783Y138583D01*
X238367Y138917D01*
X238700Y139250D01*
G01X115667Y148500D02*
X112333D01*
Y153500D01*
X115667D01*
G01X114333Y151083D02*
X112333D01*
G01X118350Y151833D02*
X120850Y148500D01*
G01Y151833D02*
X118350Y148500D01*
G01X125200Y153500D02*
Y148500D01*
G01X124033Y151833D02*
X126367D01*
G01X129550Y150750D02*
X132217D01*
X131967Y151333D01*
X131550Y151667D01*
X130967Y151833D01*
X130383Y151750D01*
X129883Y151500D01*
X129550Y150917D01*
X129383Y150417D01*
Y149917D01*
X129550Y149417D01*
X129967Y148917D01*
X130467Y148583D01*
X131050Y148500D01*
X131633Y148667D01*
X132217Y149167D01*
G01X135233Y148500D02*
Y151833D01*
G01Y151167D02*
X135650Y151500D01*
X136067Y151750D01*
X136650Y151833D01*
X137067Y151750D01*
X137567Y151500D01*
G01X140583Y148500D02*
Y151833D01*
G01Y151000D02*
X140917Y151417D01*
X141417Y151750D01*
X142083Y151833D01*
X142667Y151750D01*
X143167Y151417D01*
X143417Y150833D01*
Y148500D01*
G01X149100D02*
Y151833D01*
G01Y151250D02*
X148767Y151583D01*
X148267Y151750D01*
X147683Y151833D01*
X147100Y151667D01*
X146600Y151333D01*
X146267Y150833D01*
X146100Y150167D01*
X146267Y149500D01*
X146600Y149000D01*
X147100Y148667D01*
X147683Y148500D01*
X148267Y148583D01*
X148767Y148833D01*
X149100Y149167D01*
G01X153200Y148500D02*
Y153500D01*
G01X165733Y151417D02*
X165150Y151750D01*
X164650Y151833D01*
X163983Y151667D01*
X163483Y151333D01*
X163150Y150750D01*
X163067Y150167D01*
X163150Y149583D01*
X163483Y149083D01*
X163983Y148667D01*
X164650Y148500D01*
X165233Y148667D01*
X165733Y149000D01*
G01X170000Y148500D02*
X169500Y148583D01*
X169000Y148917D01*
X168667Y149500D01*
X168500Y150167D01*
X168667Y150833D01*
X169000Y151417D01*
X169500Y151750D01*
X170000Y151833D01*
X170500Y151750D01*
X171000Y151417D01*
X171333Y150833D01*
X171417Y150167D01*
X171333Y149500D01*
X171000Y148917D01*
X170500Y148583D01*
X170000Y148500D01*
G01X174183D02*
Y151833D01*
G01Y151000D02*
X174517Y151417D01*
X175017Y151750D01*
X175683Y151833D01*
X176267Y151750D01*
X176767Y151417D01*
X177017Y150833D01*
Y148500D01*
G01X182700Y153500D02*
Y148500D01*
G01Y149250D02*
X182367Y148833D01*
X181867Y148583D01*
X181283Y148500D01*
X180617Y148667D01*
X180117Y149083D01*
X179783Y149583D01*
X179700Y150167D01*
X179783Y150750D01*
X180117Y151250D01*
X180617Y151667D01*
X181283Y151833D01*
X181867Y151750D01*
X182283Y151583D01*
X182700Y151250D01*
G01X185383Y151833D02*
Y149500D01*
X185717Y148917D01*
X186217Y148583D01*
X186800Y148500D01*
X187383Y148583D01*
X187883Y148917D01*
X188217Y149500D01*
G01Y148500D02*
Y151833D01*
G01X193733Y151417D02*
X193150Y151750D01*
X192650Y151833D01*
X191983Y151667D01*
X191483Y151333D01*
X191150Y150750D01*
X191067Y150167D01*
X191150Y149583D01*
X191483Y149083D01*
X191983Y148667D01*
X192650Y148500D01*
X193233Y148667D01*
X193733Y149000D01*
G01X198000Y153500D02*
Y148500D01*
G01X196833Y151833D02*
X199167D01*
G01X203600Y148500D02*
X203100Y148583D01*
X202600Y148917D01*
X202267Y149500D01*
X202100Y150167D01*
X202267Y150833D01*
X202600Y151417D01*
X203100Y151750D01*
X203600Y151833D01*
X204100Y151750D01*
X204600Y151417D01*
X204933Y150833D01*
X205017Y150167D01*
X204933Y149500D01*
X204600Y148917D01*
X204100Y148583D01*
X203600Y148500D01*
G01X208033D02*
Y151833D01*
G01Y151167D02*
X208450Y151500D01*
X208867Y151750D01*
X209450Y151833D01*
X209867Y151750D01*
X210367Y151500D01*
G01X112333Y356500D02*
Y351500D01*
X115667D01*
G01X121100D02*
Y354833D01*
G01Y354250D02*
X120767Y354583D01*
X120267Y354750D01*
X119683Y354833D01*
X119100Y354667D01*
X118600Y354333D01*
X118267Y353833D01*
X118100Y353167D01*
X118267Y352500D01*
X118600Y352000D01*
X119100Y351667D01*
X119683Y351500D01*
X120267Y351583D01*
X120767Y351833D01*
X121100Y352167D01*
G01X123950Y352083D02*
X124367Y351750D01*
X124950Y351500D01*
X125450D01*
X125950Y351667D01*
X126283Y351917D01*
X126450Y352250D01*
X126367Y352750D01*
X126033Y353000D01*
X124533Y353500D01*
X124200Y354083D01*
X124367Y354500D01*
X124700Y354750D01*
X125200Y354833D01*
X125700Y354750D01*
X126200Y354500D01*
G01X129550Y353750D02*
X132217D01*
X131967Y354333D01*
X131550Y354667D01*
X130967Y354833D01*
X130383Y354750D01*
X129883Y354500D01*
X129550Y353917D01*
X129383Y353417D01*
Y352917D01*
X129550Y352417D01*
X129967Y351917D01*
X130467Y351583D01*
X131050Y351500D01*
X131633Y351667D01*
X132217Y352167D01*
G01X135233Y351500D02*
Y354833D01*
G01Y354167D02*
X135650Y354500D01*
X136067Y354750D01*
X136650Y354833D01*
X137067Y354750D01*
X137567Y354500D01*
G01X146100Y354833D02*
X147600Y351500D01*
X149100Y354833D01*
G01X153200D02*
Y351500D01*
G01Y356167D02*
X153033Y356250D01*
Y356417D01*
X153200Y356500D01*
X153367Y356417D01*
Y356250D01*
X153200Y356167D01*
G01X160300Y351500D02*
Y354833D01*
G01Y354250D02*
X159967Y354583D01*
X159467Y354750D01*
X158883Y354833D01*
X158300Y354667D01*
X157800Y354333D01*
X157467Y353833D01*
X157300Y353167D01*
X157467Y352500D01*
X157800Y352000D01*
X158300Y351667D01*
X158883Y351500D01*
X159467Y351583D01*
X159967Y351833D01*
X160300Y352167D01*
G01X168167Y351333D02*
X171833Y355000D01*
G01X170000Y355667D02*
Y350667D01*
G01X171833Y351333D02*
X168167Y355000D01*
G01X167500Y353167D02*
X172500D01*
G01X175183Y349833D02*
X174350Y350667D01*
X173933Y351500D01*
Y354833D01*
X174350Y355667D01*
X175183Y356500D01*
G01X179367Y352250D02*
X179867Y351833D01*
X180450Y351583D01*
X181200Y351500D01*
X181950Y351667D01*
X182533Y352000D01*
X182950Y352583D01*
X183033Y353250D01*
X182867Y353917D01*
X182450Y354333D01*
X181867Y354667D01*
X181283Y354750D01*
X180700Y354667D01*
X179950Y354333D01*
X180200Y356500D01*
X182450D01*
G01X186800Y351333D02*
X186633Y351417D01*
Y351583D01*
X186800Y351667D01*
X186967Y351583D01*
Y351417D01*
X186800Y351333D01*
G01X192400Y351500D02*
Y356500D01*
X191400Y355500D01*
G01Y351500D02*
X193400D01*
G01X198417Y349833D02*
X199250Y350667D01*
X199667Y351500D01*
Y354833D01*
X199250Y355667D01*
X198417Y356500D01*
G01X105000Y364500D02*
X694500D01*
G01X112333Y406500D02*
Y411500D01*
X114333D01*
X115000Y411250D01*
X115500Y410667D01*
X115667Y410000D01*
X115500Y409333D01*
X115083Y408833D01*
X114333Y408583D01*
X112333D01*
G01X119600Y411500D02*
Y406500D01*
G01X117683Y411500D02*
X121517D01*
G01X123450Y406500D02*
Y411500D01*
G01X126950D02*
Y406500D01*
G01Y409000D02*
X123450D01*
G01X135233Y406500D02*
Y409833D01*
G01Y409167D02*
X135650Y409500D01*
X136067Y409750D01*
X136650Y409833D01*
X137067Y409750D01*
X137567Y409500D01*
G01X140750Y408750D02*
X143417D01*
X143167Y409333D01*
X142750Y409667D01*
X142167Y409833D01*
X141583Y409750D01*
X141083Y409500D01*
X140750Y408917D01*
X140583Y408417D01*
Y407917D01*
X140750Y407417D01*
X141167Y406917D01*
X141667Y406583D01*
X142250Y406500D01*
X142833Y406667D01*
X143417Y407167D01*
G01X146433Y405250D02*
X147017Y404917D01*
X147683Y404833D01*
X148267Y404917D01*
X148767Y405333D01*
X149100Y405917D01*
Y409833D01*
G01Y409167D02*
X148767Y409500D01*
X148267Y409750D01*
X147683Y409833D01*
X147017Y409667D01*
X146600Y409333D01*
X146267Y408750D01*
X146100Y408167D01*
X146183Y407667D01*
X146517Y407083D01*
X147017Y406667D01*
X147683Y406500D01*
X148183Y406583D01*
X148767Y406917D01*
X149100Y407250D01*
G01X153200Y409833D02*
Y406500D01*
G01Y411167D02*
X153033Y411250D01*
Y411417D01*
X153200Y411500D01*
X153367Y411417D01*
Y411250D01*
X153200Y411167D01*
G01X157550Y407083D02*
X157967Y406750D01*
X158550Y406500D01*
X159050D01*
X159550Y406667D01*
X159883Y406917D01*
X160050Y407250D01*
X159967Y407750D01*
X159633Y408000D01*
X158133Y408500D01*
X157800Y409083D01*
X157967Y409500D01*
X158300Y409750D01*
X158800Y409833D01*
X159300Y409750D01*
X159800Y409500D01*
G01X164400Y411500D02*
Y406500D01*
G01X163233Y409833D02*
X165567D01*
G01X168833Y406500D02*
Y409833D01*
G01Y409167D02*
X169250Y409500D01*
X169667Y409750D01*
X170250Y409833D01*
X170667Y409750D01*
X171167Y409500D01*
G01X177100Y406500D02*
Y409833D01*
G01Y409250D02*
X176767Y409583D01*
X176267Y409750D01*
X175683Y409833D01*
X175100Y409667D01*
X174600Y409333D01*
X174267Y408833D01*
X174100Y408167D01*
X174267Y407500D01*
X174600Y407000D01*
X175100Y406667D01*
X175683Y406500D01*
X176267Y406583D01*
X176767Y406833D01*
X177100Y407167D01*
G01X181200Y411500D02*
Y406500D01*
G01X180033Y409833D02*
X182367D01*
G01X186800D02*
Y406500D01*
G01Y411167D02*
X186633Y411250D01*
Y411417D01*
X186800Y411500D01*
X186967Y411417D01*
Y411250D01*
X186800Y411167D01*
G01X192400Y406500D02*
X191900Y406583D01*
X191400Y406917D01*
X191067Y407500D01*
X190900Y408167D01*
X191067Y408833D01*
X191400Y409417D01*
X191900Y409750D01*
X192400Y409833D01*
X192900Y409750D01*
X193400Y409417D01*
X193733Y408833D01*
X193817Y408167D01*
X193733Y407500D01*
X193400Y406917D01*
X192900Y406583D01*
X192400Y406500D01*
G01X196583D02*
Y409833D01*
G01Y409000D02*
X196917Y409417D01*
X197417Y409750D01*
X198083Y409833D01*
X198667Y409750D01*
X199167Y409417D01*
X199417Y408833D01*
Y406500D01*
G01X112167Y433000D02*
Y438000D01*
X113833D01*
X114500Y437750D01*
X115000Y437417D01*
X115417Y436917D01*
X115750Y436333D01*
X115833Y435500D01*
X115750Y434667D01*
X115417Y434083D01*
X115000Y433583D01*
X114500Y433250D01*
X113833Y433000D01*
X112167D01*
G01X118350Y435250D02*
X121017D01*
X120767Y435833D01*
X120350Y436167D01*
X119767Y436333D01*
X119183Y436250D01*
X118683Y436000D01*
X118350Y435417D01*
X118183Y434917D01*
Y434417D01*
X118350Y433917D01*
X118767Y433417D01*
X119267Y433083D01*
X119850Y433000D01*
X120433Y433167D01*
X121017Y433667D01*
G01X123700Y431333D02*
Y436333D01*
G01Y435583D02*
X124117Y436000D01*
X124533Y436250D01*
X125200Y436333D01*
X125783Y436250D01*
X126367Y435833D01*
X126617Y435250D01*
X126700Y434667D01*
X126617Y434083D01*
X126367Y433500D01*
X125867Y433167D01*
X125200Y433000D01*
X124617Y433083D01*
X124033Y433333D01*
X123700Y433667D01*
G01X130800Y438000D02*
Y433000D01*
G01X129633Y436333D02*
X131967D01*
G01X134983Y433000D02*
Y438000D01*
G01Y435583D02*
X135400Y436000D01*
X135817Y436250D01*
X136483Y436333D01*
X136983Y436250D01*
X137567Y435917D01*
X137817Y435417D01*
Y433000D01*
G01X148933Y435917D02*
X148350Y436250D01*
X147850Y436333D01*
X147183Y436167D01*
X146683Y435833D01*
X146350Y435250D01*
X146267Y434667D01*
X146350Y434083D01*
X146683Y433583D01*
X147183Y433167D01*
X147850Y433000D01*
X148433Y433167D01*
X148933Y433500D01*
G01X153200Y433000D02*
X152700Y433083D01*
X152200Y433417D01*
X151867Y434000D01*
X151700Y434667D01*
X151867Y435333D01*
X152200Y435917D01*
X152700Y436250D01*
X153200Y436333D01*
X153700Y436250D01*
X154200Y435917D01*
X154533Y435333D01*
X154617Y434667D01*
X154533Y434000D01*
X154200Y433417D01*
X153700Y433083D01*
X153200Y433000D01*
G01X157383D02*
Y436333D01*
G01Y435500D02*
X157717Y435917D01*
X158217Y436250D01*
X158883Y436333D01*
X159467Y436250D01*
X159967Y435917D01*
X160217Y435333D01*
Y433000D01*
G01X164400Y438000D02*
Y433000D01*
G01X163233Y436333D02*
X165567D01*
G01X168833Y433000D02*
Y436333D01*
G01Y435667D02*
X169250Y436000D01*
X169667Y436250D01*
X170250Y436333D01*
X170667Y436250D01*
X171167Y436000D01*
G01X175600Y433000D02*
X175100Y433083D01*
X174600Y433417D01*
X174267Y434000D01*
X174100Y434667D01*
X174267Y435333D01*
X174600Y435917D01*
X175100Y436250D01*
X175600Y436333D01*
X176100Y436250D01*
X176600Y435917D01*
X176933Y435333D01*
X177017Y434667D01*
X176933Y434000D01*
X176600Y433417D01*
X176100Y433083D01*
X175600Y433000D01*
G01X181200D02*
Y438000D01*
G01X190983Y433000D02*
Y438000D01*
G01Y435583D02*
X191400Y436000D01*
X191817Y436250D01*
X192483Y436333D01*
X192983Y436250D01*
X193567Y435917D01*
X193817Y435417D01*
Y433000D01*
G01X198000D02*
X197500Y433083D01*
X197000Y433417D01*
X196667Y434000D01*
X196500Y434667D01*
X196667Y435333D01*
X197000Y435917D01*
X197500Y436250D01*
X198000Y436333D01*
X198500Y436250D01*
X199000Y435917D01*
X199333Y435333D01*
X199417Y434667D01*
X199333Y434000D01*
X199000Y433417D01*
X198500Y433083D01*
X198000Y433000D01*
G01X203600D02*
Y438000D01*
G01X207950Y435250D02*
X210617D01*
X210367Y435833D01*
X209950Y436167D01*
X209367Y436333D01*
X208783Y436250D01*
X208283Y436000D01*
X207950Y435417D01*
X207783Y434917D01*
Y434417D01*
X207950Y433917D01*
X208367Y433417D01*
X208867Y433083D01*
X209450Y433000D01*
X210033Y433167D01*
X210617Y433667D01*
G01X103500Y424000D02*
X694500D01*
G01X112333Y455000D02*
Y460000D01*
X114417D01*
X115083Y459750D01*
X115500Y459417D01*
X115667Y458750D01*
X115500Y458083D01*
X115000Y457667D01*
X114417Y457417D01*
X112333D01*
G01X114417D02*
X115667Y455000D01*
G01X119600D02*
X119100Y455083D01*
X118600Y455417D01*
X118267Y456000D01*
X118100Y456667D01*
X118267Y457333D01*
X118600Y457917D01*
X119100Y458250D01*
X119600Y458333D01*
X120100Y458250D01*
X120600Y457917D01*
X120933Y457333D01*
X121017Y456667D01*
X120933Y456000D01*
X120600Y455417D01*
X120100Y455083D01*
X119600Y455000D01*
G01X123783Y458333D02*
Y456000D01*
X124117Y455417D01*
X124617Y455083D01*
X125200Y455000D01*
X125783Y455083D01*
X126283Y455417D01*
X126617Y456000D01*
G01Y455000D02*
Y458333D01*
G01X129633Y453750D02*
X130217Y453417D01*
X130883Y453333D01*
X131467Y453417D01*
X131967Y453833D01*
X132300Y454417D01*
Y458333D01*
G01Y457667D02*
X131967Y458000D01*
X131467Y458250D01*
X130883Y458333D01*
X130217Y458167D01*
X129800Y457833D01*
X129467Y457250D01*
X129300Y456667D01*
X129383Y456167D01*
X129717Y455583D01*
X130217Y455167D01*
X130883Y455000D01*
X131383Y455083D01*
X131967Y455417D01*
X132300Y455750D01*
G01X134983Y455000D02*
Y460000D01*
G01Y457583D02*
X135400Y458000D01*
X135817Y458250D01*
X136483Y458333D01*
X136983Y458250D01*
X137567Y457917D01*
X137817Y457417D01*
Y455000D01*
G01X140583D02*
Y458333D01*
G01Y457500D02*
X140917Y457917D01*
X141417Y458250D01*
X142083Y458333D01*
X142667Y458250D01*
X143167Y457917D01*
X143417Y457333D01*
Y455000D01*
G01X146350Y457250D02*
X149017D01*
X148767Y457833D01*
X148350Y458167D01*
X147767Y458333D01*
X147183Y458250D01*
X146683Y458000D01*
X146350Y457417D01*
X146183Y456917D01*
Y456417D01*
X146350Y455917D01*
X146767Y455417D01*
X147267Y455083D01*
X147850Y455000D01*
X148433Y455167D01*
X149017Y455667D01*
G01X151950Y455583D02*
X152367Y455250D01*
X152950Y455000D01*
X153450D01*
X153950Y455167D01*
X154283Y455417D01*
X154450Y455750D01*
X154367Y456250D01*
X154033Y456500D01*
X152533Y457000D01*
X152200Y457583D01*
X152367Y458000D01*
X152700Y458250D01*
X153200Y458333D01*
X153700Y458250D01*
X154200Y458000D01*
G01X157550Y455583D02*
X157967Y455250D01*
X158550Y455000D01*
X159050D01*
X159550Y455167D01*
X159883Y455417D01*
X160050Y455750D01*
X159967Y456250D01*
X159633Y456500D01*
X158133Y457000D01*
X157800Y457583D01*
X157967Y458000D01*
X158300Y458250D01*
X158800Y458333D01*
X159300Y458250D01*
X159800Y458000D01*
G01X103500Y449000D02*
X694500D01*
G01X104000Y464000D02*
X694500D01*
G01X112250Y513500D02*
Y518500D01*
G01X115750D02*
Y513500D01*
G01Y516000D02*
X112250D01*
G01X119600Y513500D02*
X119100Y513583D01*
X118600Y513917D01*
X118267Y514500D01*
X118100Y515167D01*
X118267Y515833D01*
X118600Y516417D01*
X119100Y516750D01*
X119600Y516833D01*
X120100Y516750D01*
X120600Y516417D01*
X120933Y515833D01*
X121017Y515167D01*
X120933Y514500D01*
X120600Y513917D01*
X120100Y513583D01*
X119600Y513500D01*
G01X125200D02*
Y518500D01*
G01X129550Y515750D02*
X132217D01*
X131967Y516333D01*
X131550Y516667D01*
X130967Y516833D01*
X130383Y516750D01*
X129883Y516500D01*
X129550Y515917D01*
X129383Y515417D01*
Y514917D01*
X129550Y514417D01*
X129967Y513917D01*
X130467Y513583D01*
X131050Y513500D01*
X131633Y513667D01*
X132217Y514167D01*
G01X140750Y514083D02*
X141167Y513750D01*
X141750Y513500D01*
X142250D01*
X142750Y513667D01*
X143083Y513917D01*
X143250Y514250D01*
X143167Y514750D01*
X142833Y515000D01*
X141333Y515500D01*
X141000Y516083D01*
X141167Y516500D01*
X141500Y516750D01*
X142000Y516833D01*
X142500Y516750D01*
X143000Y516500D01*
G01X147600Y516833D02*
Y513500D01*
G01Y518167D02*
X147433Y518250D01*
Y518417D01*
X147600Y518500D01*
X147767Y518417D01*
Y518250D01*
X147600Y518167D01*
G01X151950Y516833D02*
X154450D01*
X151950Y513500D01*
X154450D01*
G01X157550Y515750D02*
X160217D01*
X159967Y516333D01*
X159550Y516667D01*
X158967Y516833D01*
X158383Y516750D01*
X157883Y516500D01*
X157550Y515917D01*
X157383Y515417D01*
Y514917D01*
X157550Y514417D01*
X157967Y513917D01*
X158467Y513583D01*
X159050Y513500D01*
X159633Y513667D01*
X160217Y514167D01*
G01X111917Y610000D02*
X114000Y605000D01*
X116083Y610000D01*
G01X119600Y608333D02*
Y605000D01*
G01Y609667D02*
X119433Y609750D01*
Y609917D01*
X119600Y610000D01*
X119767Y609917D01*
Y609750D01*
X119600Y609667D01*
G01X126700Y605000D02*
Y608333D01*
G01Y607750D02*
X126367Y608083D01*
X125867Y608250D01*
X125283Y608333D01*
X124700Y608167D01*
X124200Y607833D01*
X123867Y607333D01*
X123700Y606667D01*
X123867Y606000D01*
X124200Y605500D01*
X124700Y605167D01*
X125283Y605000D01*
X125867Y605083D01*
X126367Y605333D01*
X126700Y605667D01*
G01X134983Y605000D02*
Y610000D01*
G01Y607583D02*
X135400Y608000D01*
X135817Y608250D01*
X136483Y608333D01*
X136983Y608250D01*
X137567Y607917D01*
X137817Y607417D01*
Y605000D01*
G01X142000D02*
X141500Y605083D01*
X141000Y605417D01*
X140667Y606000D01*
X140500Y606667D01*
X140667Y607333D01*
X141000Y607917D01*
X141500Y608250D01*
X142000Y608333D01*
X142500Y608250D01*
X143000Y607917D01*
X143333Y607333D01*
X143417Y606667D01*
X143333Y606000D01*
X143000Y605417D01*
X142500Y605083D01*
X142000Y605000D01*
G01X147600D02*
Y610000D01*
G01X151950Y607250D02*
X154617D01*
X154367Y607833D01*
X153950Y608167D01*
X153367Y608333D01*
X152783Y608250D01*
X152283Y608000D01*
X151950Y607417D01*
X151783Y606917D01*
Y606417D01*
X151950Y605917D01*
X152367Y605417D01*
X152867Y605083D01*
X153450Y605000D01*
X154033Y605167D01*
X154617Y605667D01*
G01X164400Y610000D02*
Y605000D01*
G01X163233Y608333D02*
X165567D01*
G01X168583Y605000D02*
Y610000D01*
G01Y607583D02*
X169000Y608000D01*
X169417Y608250D01*
X170083Y608333D01*
X170583Y608250D01*
X171167Y607917D01*
X171417Y607417D01*
Y605000D01*
G01X174350Y607250D02*
X177017D01*
X176767Y607833D01*
X176350Y608167D01*
X175767Y608333D01*
X175183Y608250D01*
X174683Y608000D01*
X174350Y607417D01*
X174183Y606917D01*
Y606417D01*
X174350Y605917D01*
X174767Y605417D01*
X175267Y605083D01*
X175850Y605000D01*
X176433Y605167D01*
X177017Y605667D01*
G01X180033Y605000D02*
Y608333D01*
G01Y607667D02*
X180450Y608000D01*
X180867Y608250D01*
X181450Y608333D01*
X181867Y608250D01*
X182367Y608000D01*
G01X184300Y605000D02*
Y608333D01*
G01Y607417D02*
X184550Y607833D01*
X184967Y608167D01*
X185550Y608333D01*
X186133Y608167D01*
X186550Y607833D01*
X186800Y607417D01*
Y605000D01*
G01Y607417D02*
X187050Y607833D01*
X187467Y608167D01*
X188050Y608333D01*
X188633Y608167D01*
X189050Y607833D01*
X189300Y607333D01*
Y605000D01*
G01X193900D02*
Y608333D01*
G01Y607750D02*
X193567Y608083D01*
X193067Y608250D01*
X192483Y608333D01*
X191900Y608167D01*
X191400Y607833D01*
X191067Y607333D01*
X190900Y606667D01*
X191067Y606000D01*
X191400Y605500D01*
X191900Y605167D01*
X192483Y605000D01*
X193067Y605083D01*
X193567Y605333D01*
X193900Y605667D01*
G01X198000Y605000D02*
Y610000D01*
G01X207700Y603333D02*
Y608333D01*
G01Y607583D02*
X208117Y608000D01*
X208533Y608250D01*
X209200Y608333D01*
X209783Y608250D01*
X210367Y607833D01*
X210617Y607250D01*
X210700Y606667D01*
X210617Y606083D01*
X210367Y605500D01*
X209867Y605167D01*
X209200Y605000D01*
X208617Y605083D01*
X208033Y605333D01*
X207700Y605667D01*
G01X216300Y605000D02*
Y608333D01*
G01Y607750D02*
X215967Y608083D01*
X215467Y608250D01*
X214883Y608333D01*
X214300Y608167D01*
X213800Y607833D01*
X213467Y607333D01*
X213300Y606667D01*
X213467Y606000D01*
X213800Y605500D01*
X214300Y605167D01*
X214883Y605000D01*
X215467Y605083D01*
X215967Y605333D01*
X216300Y605667D01*
G01X221900Y610000D02*
Y605000D01*
G01Y605750D02*
X221567Y605333D01*
X221067Y605083D01*
X220483Y605000D01*
X219817Y605167D01*
X219317Y605583D01*
X218983Y606083D01*
X218900Y606667D01*
X218983Y607250D01*
X219317Y607750D01*
X219817Y608167D01*
X220483Y608333D01*
X221067Y608250D01*
X221483Y608083D01*
X221900Y607750D01*
G01X112250Y588500D02*
Y593500D01*
G01X115750D02*
Y588500D01*
G01Y591000D02*
X112250D01*
G01X119600Y588500D02*
X119100Y588583D01*
X118600Y588917D01*
X118267Y589500D01*
X118100Y590167D01*
X118267Y590833D01*
X118600Y591417D01*
X119100Y591750D01*
X119600Y591833D01*
X120100Y591750D01*
X120600Y591417D01*
X120933Y590833D01*
X121017Y590167D01*
X120933Y589500D01*
X120600Y588917D01*
X120100Y588583D01*
X119600Y588500D01*
G01X125200D02*
Y593500D01*
G01X129550Y590750D02*
X132217D01*
X131967Y591333D01*
X131550Y591667D01*
X130967Y591833D01*
X130383Y591750D01*
X129883Y591500D01*
X129550Y590917D01*
X129383Y590417D01*
Y589917D01*
X129550Y589417D01*
X129967Y588917D01*
X130467Y588583D01*
X131050Y588500D01*
X131633Y588667D01*
X132217Y589167D01*
G01X140500Y586833D02*
Y591833D01*
G01Y591083D02*
X140917Y591500D01*
X141333Y591750D01*
X142000Y591833D01*
X142583Y591750D01*
X143167Y591333D01*
X143417Y590750D01*
X143500Y590167D01*
X143417Y589583D01*
X143167Y589000D01*
X142667Y588667D01*
X142000Y588500D01*
X141417Y588583D01*
X140833Y588833D01*
X140500Y589167D01*
G01X147600Y588500D02*
X147100Y588583D01*
X146600Y588917D01*
X146267Y589500D01*
X146100Y590167D01*
X146267Y590833D01*
X146600Y591417D01*
X147100Y591750D01*
X147600Y591833D01*
X148100Y591750D01*
X148600Y591417D01*
X148933Y590833D01*
X149017Y590167D01*
X148933Y589500D01*
X148600Y588917D01*
X148100Y588583D01*
X147600Y588500D01*
G01X151950Y589083D02*
X152367Y588750D01*
X152950Y588500D01*
X153450D01*
X153950Y588667D01*
X154283Y588917D01*
X154450Y589250D01*
X154367Y589750D01*
X154033Y590000D01*
X152533Y590500D01*
X152200Y591083D01*
X152367Y591500D01*
X152700Y591750D01*
X153200Y591833D01*
X153700Y591750D01*
X154200Y591500D01*
G01X158800Y591833D02*
Y588500D01*
G01Y593167D02*
X158633Y593250D01*
Y593417D01*
X158800Y593500D01*
X158967Y593417D01*
Y593250D01*
X158800Y593167D01*
G01X164400Y593500D02*
Y588500D01*
G01X163233Y591833D02*
X165567D01*
G01X170000D02*
Y588500D01*
G01Y593167D02*
X169833Y593250D01*
Y593417D01*
X170000Y593500D01*
X170167Y593417D01*
Y593250D01*
X170000Y593167D01*
G01X175600Y588500D02*
X175100Y588583D01*
X174600Y588917D01*
X174267Y589500D01*
X174100Y590167D01*
X174267Y590833D01*
X174600Y591417D01*
X175100Y591750D01*
X175600Y591833D01*
X176100Y591750D01*
X176600Y591417D01*
X176933Y590833D01*
X177017Y590167D01*
X176933Y589500D01*
X176600Y588917D01*
X176100Y588583D01*
X175600Y588500D01*
G01X179783D02*
Y591833D01*
G01Y591000D02*
X180117Y591417D01*
X180617Y591750D01*
X181283Y591833D01*
X181867Y591750D01*
X182367Y591417D01*
X182617Y590833D01*
Y588500D01*
G01X192400Y593500D02*
Y588500D01*
G01X191233Y591833D02*
X193567D01*
G01X198000Y588500D02*
X197500Y588583D01*
X197000Y588917D01*
X196667Y589500D01*
X196500Y590167D01*
X196667Y590833D01*
X197000Y591417D01*
X197500Y591750D01*
X198000Y591833D01*
X198500Y591750D01*
X199000Y591417D01*
X199333Y590833D01*
X199417Y590167D01*
X199333Y589500D01*
X199000Y588917D01*
X198500Y588583D01*
X198000Y588500D01*
G01X203600D02*
Y593500D01*
G01X207950Y590750D02*
X210617D01*
X210367Y591333D01*
X209950Y591667D01*
X209367Y591833D01*
X208783Y591750D01*
X208283Y591500D01*
X207950Y590917D01*
X207783Y590417D01*
Y589917D01*
X207950Y589417D01*
X208367Y588917D01*
X208867Y588583D01*
X209450Y588500D01*
X210033Y588667D01*
X210617Y589167D01*
G01X213633Y588500D02*
Y591833D01*
G01Y591167D02*
X214050Y591500D01*
X214467Y591750D01*
X215050Y591833D01*
X215467Y591750D01*
X215967Y591500D01*
G01X221900Y588500D02*
Y591833D01*
G01Y591250D02*
X221567Y591583D01*
X221067Y591750D01*
X220483Y591833D01*
X219900Y591667D01*
X219400Y591333D01*
X219067Y590833D01*
X218900Y590167D01*
X219067Y589500D01*
X219400Y589000D01*
X219900Y588667D01*
X220483Y588500D01*
X221067Y588583D01*
X221567Y588833D01*
X221900Y589167D01*
G01X224583Y588500D02*
Y591833D01*
G01Y591000D02*
X224917Y591417D01*
X225417Y591750D01*
X226083Y591833D01*
X226667Y591750D01*
X227167Y591417D01*
X227417Y590833D01*
Y588500D01*
G01X232933Y591417D02*
X232350Y591750D01*
X231850Y591833D01*
X231183Y591667D01*
X230683Y591333D01*
X230350Y590750D01*
X230267Y590167D01*
X230350Y589583D01*
X230683Y589083D01*
X231183Y588667D01*
X231850Y588500D01*
X232433Y588667D01*
X232933Y589000D01*
G01X235950Y590750D02*
X238617D01*
X238367Y591333D01*
X237950Y591667D01*
X237367Y591833D01*
X236783Y591750D01*
X236283Y591500D01*
X235950Y590917D01*
X235783Y590417D01*
Y589917D01*
X235950Y589417D01*
X236367Y588917D01*
X236867Y588583D01*
X237450Y588500D01*
X238033Y588667D01*
X238617Y589167D01*
G01X103500Y614000D02*
X694500D01*
G01X103500Y584000D02*
X694500D01*
G01X111917Y620000D02*
X114000Y625000D01*
X116083Y620000D01*
G01X115333Y621750D02*
X112667D01*
G01X118183Y620000D02*
Y623333D01*
G01Y622500D02*
X118517Y622917D01*
X119017Y623250D01*
X119683Y623333D01*
X120267Y623250D01*
X120767Y622917D01*
X121017Y622333D01*
Y620000D01*
G01X125200Y625000D02*
Y620000D01*
G01X124033Y623333D02*
X126367D01*
G01X130800D02*
Y620000D01*
G01Y624667D02*
X130633Y624750D01*
Y624917D01*
X130800Y625000D01*
X130967Y624917D01*
Y624750D01*
X130800Y624667D01*
G01X135317Y621667D02*
X137483D01*
G01X146100Y618333D02*
Y623333D01*
G01Y622583D02*
X146517Y623000D01*
X146933Y623250D01*
X147600Y623333D01*
X148183Y623250D01*
X148767Y622833D01*
X149017Y622250D01*
X149100Y621667D01*
X149017Y621083D01*
X148767Y620500D01*
X148267Y620167D01*
X147600Y620000D01*
X147017Y620083D01*
X146433Y620333D01*
X146100Y620667D01*
G01X154700Y620000D02*
Y623333D01*
G01Y622750D02*
X154367Y623083D01*
X153867Y623250D01*
X153283Y623333D01*
X152700Y623167D01*
X152200Y622833D01*
X151867Y622333D01*
X151700Y621667D01*
X151867Y621000D01*
X152200Y620500D01*
X152700Y620167D01*
X153283Y620000D01*
X153867Y620083D01*
X154367Y620333D01*
X154700Y620667D01*
G01X160300Y625000D02*
Y620000D01*
G01Y620750D02*
X159967Y620333D01*
X159467Y620083D01*
X158883Y620000D01*
X158217Y620167D01*
X157717Y620583D01*
X157383Y621083D01*
X157300Y621667D01*
X157383Y622250D01*
X157717Y622750D01*
X158217Y623167D01*
X158883Y623333D01*
X159467Y623250D01*
X159883Y623083D01*
X160300Y622750D01*
G01X111843Y639590D02*
Y644590D01*
X115677Y639590D01*
Y644590D01*
G01X119360Y639590D02*
X118860Y639673D01*
X118360Y640007D01*
X118027Y640590D01*
X117860Y641257D01*
X118027Y641923D01*
X118360Y642507D01*
X118860Y642840D01*
X119360Y642923D01*
X119860Y642840D01*
X120360Y642507D01*
X120693Y641923D01*
X120777Y641257D01*
X120693Y640590D01*
X120360Y640007D01*
X119860Y639673D01*
X119360Y639590D01*
G01X123543D02*
Y642923D01*
G01Y642090D02*
X123877Y642507D01*
X124377Y642840D01*
X125043Y642923D01*
X125627Y642840D01*
X126127Y642507D01*
X126377Y641923D01*
Y639590D01*
G01X129477Y641257D02*
X131643D01*
G01X135660Y639590D02*
Y643840D01*
X135827Y644257D01*
X136160Y644507D01*
X136660Y644590D01*
X137160Y644423D01*
X137410Y644007D01*
G01X136410Y642590D02*
X134743D01*
G01X140343Y642923D02*
Y640590D01*
X140677Y640007D01*
X141177Y639673D01*
X141760Y639590D01*
X142343Y639673D01*
X142843Y640007D01*
X143177Y640590D01*
G01Y639590D02*
Y642923D01*
G01X145943Y639590D02*
Y642923D01*
G01Y642090D02*
X146277Y642507D01*
X146777Y642840D01*
X147443Y642923D01*
X148027Y642840D01*
X148527Y642507D01*
X148777Y641923D01*
Y639590D01*
G01X154293Y642507D02*
X153710Y642840D01*
X153210Y642923D01*
X152543Y642757D01*
X152043Y642423D01*
X151710Y641840D01*
X151627Y641257D01*
X151710Y640673D01*
X152043Y640173D01*
X152543Y639757D01*
X153210Y639590D01*
X153793Y639757D01*
X154293Y640090D01*
G01X158560Y644590D02*
Y639590D01*
G01X157393Y642923D02*
X159727D01*
G01X164160D02*
Y639590D01*
G01Y644257D02*
X163993Y644340D01*
Y644507D01*
X164160Y644590D01*
X164327Y644507D01*
Y644340D01*
X164160Y644257D01*
G01X169760Y639590D02*
X169260Y639673D01*
X168760Y640007D01*
X168427Y640590D01*
X168260Y641257D01*
X168427Y641923D01*
X168760Y642507D01*
X169260Y642840D01*
X169760Y642923D01*
X170260Y642840D01*
X170760Y642507D01*
X171093Y641923D01*
X171177Y641257D01*
X171093Y640590D01*
X170760Y640007D01*
X170260Y639673D01*
X169760Y639590D01*
G01X173943D02*
Y642923D01*
G01Y642090D02*
X174277Y642507D01*
X174777Y642840D01*
X175443Y642923D01*
X176027Y642840D01*
X176527Y642507D01*
X176777Y641923D01*
Y639590D01*
G01X182460D02*
Y642923D01*
G01Y642340D02*
X182127Y642673D01*
X181627Y642840D01*
X181043Y642923D01*
X180460Y642757D01*
X179960Y642423D01*
X179627Y641923D01*
X179460Y641257D01*
X179627Y640590D01*
X179960Y640090D01*
X180460Y639757D01*
X181043Y639590D01*
X181627Y639673D01*
X182127Y639923D01*
X182460Y640257D01*
G01X186560Y639590D02*
Y644590D01*
G01X196260Y637923D02*
Y642923D01*
G01Y642173D02*
X196677Y642590D01*
X197093Y642840D01*
X197760Y642923D01*
X198343Y642840D01*
X198927Y642423D01*
X199177Y641840D01*
X199260Y641257D01*
X199177Y640673D01*
X198927Y640090D01*
X198427Y639757D01*
X197760Y639590D01*
X197177Y639673D01*
X196593Y639923D01*
X196260Y640257D01*
G01X204860Y639590D02*
Y642923D01*
G01Y642340D02*
X204527Y642673D01*
X204027Y642840D01*
X203443Y642923D01*
X202860Y642757D01*
X202360Y642423D01*
X202027Y641923D01*
X201860Y641257D01*
X202027Y640590D01*
X202360Y640090D01*
X202860Y639757D01*
X203443Y639590D01*
X204027Y639673D01*
X204527Y639923D01*
X204860Y640257D01*
G01X210460Y644590D02*
Y639590D01*
G01Y640340D02*
X210127Y639923D01*
X209627Y639673D01*
X209043Y639590D01*
X208377Y639757D01*
X207877Y640173D01*
X207543Y640673D01*
X207460Y641257D01*
X207543Y641840D01*
X207877Y642340D01*
X208377Y642757D01*
X209043Y642923D01*
X209627Y642840D01*
X210043Y642673D01*
X210460Y642340D01*
G01X103500Y629000D02*
X694500D01*
G01X160333Y668083D02*
X159833Y668333D01*
X159250Y668500D01*
X158583D01*
X157833Y668250D01*
X157250Y667833D01*
X156833Y667333D01*
X156500Y666500D01*
X156417Y665750D01*
X156583Y665000D01*
X156833Y664500D01*
X157333Y664000D01*
X157917Y663667D01*
X158500Y663500D01*
X159083D01*
X159667Y663667D01*
X160167Y663917D01*
X160583Y664250D01*
G01X164100Y663500D02*
Y668500D01*
G01X171200Y663500D02*
Y666833D01*
G01Y666250D02*
X170867Y666583D01*
X170367Y666750D01*
X169783Y666833D01*
X169200Y666667D01*
X168700Y666333D01*
X168367Y665833D01*
X168200Y665167D01*
X168367Y664500D01*
X168700Y664000D01*
X169200Y663667D01*
X169783Y663500D01*
X170367Y663583D01*
X170867Y663833D01*
X171200Y664167D01*
G01X174050Y664083D02*
X174467Y663750D01*
X175050Y663500D01*
X175550D01*
X176050Y663667D01*
X176383Y663917D01*
X176550Y664250D01*
X176467Y664750D01*
X176133Y665000D01*
X174633Y665500D01*
X174300Y666083D01*
X174467Y666500D01*
X174800Y666750D01*
X175300Y666833D01*
X175800Y666750D01*
X176300Y666500D01*
G01X179650Y664083D02*
X180067Y663750D01*
X180650Y663500D01*
X181150D01*
X181650Y663667D01*
X181983Y663917D01*
X182150Y664250D01*
X182067Y664750D01*
X181733Y665000D01*
X180233Y665500D01*
X179900Y666083D01*
X180067Y666500D01*
X180400Y666750D01*
X180900Y666833D01*
X181400Y666750D01*
X181900Y666500D01*
G01X186500Y666833D02*
Y663500D01*
G01Y668167D02*
X186333Y668250D01*
Y668417D01*
X186500Y668500D01*
X186667Y668417D01*
Y668250D01*
X186500Y668167D01*
G01X191600Y663500D02*
Y667750D01*
X191767Y668167D01*
X192100Y668417D01*
X192600Y668500D01*
X193100Y668333D01*
X193350Y667917D01*
G01X192350Y666500D02*
X190683D01*
G01X195950Y662000D02*
X196450Y661833D01*
X197117Y662000D01*
X197533Y662333D01*
X197867Y662750D01*
X198367Y664083D01*
X199450Y666833D01*
G01X196783D02*
X198367Y664083D01*
G01X262500Y-69500D02*
Y439000D01*
G01X264000Y-39500D02*
X694500D01*
G01X264000Y5500D02*
X694500D01*
G01X264000Y40500D02*
X694500D01*
G01X264000Y75500D02*
X694500D01*
G01X264000Y90500D02*
X694500D01*
G01X264000Y135500D02*
X694500D01*
G01X264000Y160500D02*
X694500D01*
G01X262500Y237500D02*
X694500D01*
G01X262500Y290500D02*
X694500D01*
G01X262500Y397000D02*
Y679000D01*
G01Y479000D02*
X694500D01*
G01X262500Y494000D02*
X694500D01*
G01X262500Y509000D02*
X694500D01*
G01X262500Y524000D02*
X694500D01*
G01X262500Y539000D02*
X694500D01*
G01X262500Y554000D02*
X694500D01*
G01X262500Y569000D02*
X694500D01*
G01X274000Y-63500D02*
Y-60167D01*
G01Y-60750D02*
X273667Y-60417D01*
X273167Y-60250D01*
X272583Y-60167D01*
X272000Y-60333D01*
X271500Y-60667D01*
X271167Y-61167D01*
X271000Y-61833D01*
X271167Y-62500D01*
X271500Y-63000D01*
X272000Y-63333D01*
X272583Y-63500D01*
X273167Y-63417D01*
X273667Y-63167D01*
X274000Y-62833D01*
G01X279600Y-58500D02*
Y-63500D01*
G01Y-62750D02*
X279267Y-63167D01*
X278767Y-63417D01*
X278183Y-63500D01*
X277517Y-63333D01*
X277017Y-62917D01*
X276683Y-62417D01*
X276600Y-61833D01*
X276683Y-61250D01*
X277017Y-60750D01*
X277517Y-60333D01*
X278183Y-60167D01*
X278767Y-60250D01*
X279183Y-60417D01*
X279600Y-60750D01*
G01X285200Y-58500D02*
Y-63500D01*
G01Y-62750D02*
X284867Y-63167D01*
X284367Y-63417D01*
X283783Y-63500D01*
X283117Y-63333D01*
X282617Y-62917D01*
X282283Y-62417D01*
X282200Y-61833D01*
X282283Y-61250D01*
X282617Y-60750D01*
X283117Y-60333D01*
X283783Y-60167D01*
X284367Y-60250D01*
X284783Y-60417D01*
X285200Y-60750D01*
G01X293650Y-62917D02*
X294067Y-63250D01*
X294650Y-63500D01*
X295150D01*
X295650Y-63333D01*
X295983Y-63083D01*
X296150Y-62750D01*
X296067Y-62250D01*
X295733Y-62000D01*
X294233Y-61500D01*
X293900Y-60917D01*
X294067Y-60500D01*
X294400Y-60250D01*
X294900Y-60167D01*
X295400Y-60250D01*
X295900Y-60500D01*
G01X299083Y-60167D02*
Y-62500D01*
X299417Y-63083D01*
X299917Y-63417D01*
X300500Y-63500D01*
X301083Y-63417D01*
X301583Y-63083D01*
X301917Y-62500D01*
G01Y-63500D02*
Y-60167D01*
G01X304600Y-65167D02*
Y-60167D01*
G01Y-60917D02*
X305017Y-60500D01*
X305433Y-60250D01*
X306100Y-60167D01*
X306683Y-60250D01*
X307267Y-60667D01*
X307517Y-61250D01*
X307600Y-61833D01*
X307517Y-62417D01*
X307267Y-63000D01*
X306767Y-63333D01*
X306100Y-63500D01*
X305517Y-63417D01*
X304933Y-63167D01*
X304600Y-62833D01*
G01X310200Y-65167D02*
Y-60167D01*
G01Y-60917D02*
X310617Y-60500D01*
X311033Y-60250D01*
X311700Y-60167D01*
X312283Y-60250D01*
X312867Y-60667D01*
X313117Y-61250D01*
X313200Y-61833D01*
X313117Y-62417D01*
X312867Y-63000D01*
X312367Y-63333D01*
X311700Y-63500D01*
X311117Y-63417D01*
X310533Y-63167D01*
X310200Y-62833D01*
G01X317300Y-63500D02*
Y-58500D01*
G01X322900Y-60167D02*
Y-63500D01*
G01Y-58833D02*
X322733Y-58750D01*
Y-58583D01*
X322900Y-58500D01*
X323067Y-58583D01*
Y-58750D01*
X322900Y-58833D01*
G01X327250Y-61250D02*
X329917D01*
X329667Y-60667D01*
X329250Y-60333D01*
X328667Y-60167D01*
X328083Y-60250D01*
X327583Y-60500D01*
X327250Y-61083D01*
X327083Y-61583D01*
Y-62083D01*
X327250Y-62583D01*
X327667Y-63083D01*
X328167Y-63417D01*
X328750Y-63500D01*
X329333Y-63333D01*
X329917Y-62833D01*
G01X332933Y-63500D02*
Y-60167D01*
G01Y-60833D02*
X333350Y-60500D01*
X333767Y-60250D01*
X334350Y-60167D01*
X334767Y-60250D01*
X335267Y-60500D01*
G01X339700Y-60167D02*
X340533Y-59125D01*
Y-58500D01*
X339908D01*
Y-59125D01*
X340533D01*
G01X344050Y-62917D02*
X344467Y-63250D01*
X345050Y-63500D01*
X345550D01*
X346050Y-63333D01*
X346383Y-63083D01*
X346550Y-62750D01*
X346467Y-62250D01*
X346133Y-62000D01*
X344633Y-61500D01*
X344300Y-60917D01*
X344467Y-60500D01*
X344800Y-60250D01*
X345300Y-60167D01*
X345800Y-60250D01*
X346300Y-60500D01*
G01X354833Y-58500D02*
Y-63500D01*
X358167D01*
G01X362100D02*
X361600Y-63417D01*
X361100Y-63083D01*
X360767Y-62500D01*
X360600Y-61833D01*
X360767Y-61167D01*
X361100Y-60583D01*
X361600Y-60250D01*
X362100Y-60167D01*
X362600Y-60250D01*
X363100Y-60583D01*
X363433Y-61167D01*
X363517Y-61833D01*
X363433Y-62500D01*
X363100Y-63083D01*
X362600Y-63417D01*
X362100Y-63500D01*
G01X366533Y-64750D02*
X367117Y-65083D01*
X367783Y-65167D01*
X368367Y-65083D01*
X368867Y-64667D01*
X369200Y-64083D01*
Y-60167D01*
G01Y-60833D02*
X368867Y-60500D01*
X368367Y-60250D01*
X367783Y-60167D01*
X367117Y-60333D01*
X366700Y-60667D01*
X366367Y-61250D01*
X366200Y-61833D01*
X366283Y-62333D01*
X366617Y-62917D01*
X367117Y-63333D01*
X367783Y-63500D01*
X368283Y-63417D01*
X368867Y-63083D01*
X369200Y-62750D01*
G01X373300Y-63500D02*
X372800Y-63417D01*
X372300Y-63083D01*
X371967Y-62500D01*
X371800Y-61833D01*
X371967Y-61167D01*
X372300Y-60583D01*
X372800Y-60250D01*
X373300Y-60167D01*
X373800Y-60250D01*
X374300Y-60583D01*
X374633Y-61167D01*
X374717Y-61833D01*
X374633Y-62500D01*
X374300Y-63083D01*
X373800Y-63417D01*
X373300Y-63500D01*
G01X386000D02*
Y-60167D01*
G01Y-60750D02*
X385667Y-60417D01*
X385167Y-60250D01*
X384583Y-60167D01*
X384000Y-60333D01*
X383500Y-60667D01*
X383167Y-61167D01*
X383000Y-61833D01*
X383167Y-62500D01*
X383500Y-63000D01*
X384000Y-63333D01*
X384583Y-63500D01*
X385167Y-63417D01*
X385667Y-63167D01*
X386000Y-62833D01*
G01X388683Y-63500D02*
Y-60167D01*
G01Y-61000D02*
X389017Y-60583D01*
X389517Y-60250D01*
X390183Y-60167D01*
X390767Y-60250D01*
X391267Y-60583D01*
X391517Y-61167D01*
Y-63500D01*
G01X397200Y-58500D02*
Y-63500D01*
G01Y-62750D02*
X396867Y-63167D01*
X396367Y-63417D01*
X395783Y-63500D01*
X395117Y-63333D01*
X394617Y-62917D01*
X394283Y-62417D01*
X394200Y-61833D01*
X394283Y-61250D01*
X394617Y-60750D01*
X395117Y-60333D01*
X395783Y-60167D01*
X396367Y-60250D01*
X396783Y-60417D01*
X397200Y-60750D01*
G01X405067Y-58500D02*
Y-62083D01*
X405400Y-62833D01*
X406067Y-63333D01*
X406900Y-63500D01*
X407733Y-63333D01*
X408400Y-62833D01*
X408733Y-62083D01*
Y-58500D01*
G01X410833D02*
Y-63500D01*
X414167D01*
G01X423200D02*
Y-59250D01*
X423367Y-58833D01*
X423700Y-58583D01*
X424200Y-58500D01*
X424700Y-58667D01*
X424950Y-59083D01*
G01X423950Y-60500D02*
X422283D01*
G01X429300Y-60167D02*
Y-63500D01*
G01Y-58833D02*
X429133Y-58750D01*
Y-58583D01*
X429300Y-58500D01*
X429467Y-58583D01*
Y-58750D01*
X429300Y-58833D01*
G01X434900Y-63500D02*
Y-58500D01*
G01X439250Y-61250D02*
X441917D01*
X441667Y-60667D01*
X441250Y-60333D01*
X440667Y-60167D01*
X440083Y-60250D01*
X439583Y-60500D01*
X439250Y-61083D01*
X439083Y-61583D01*
Y-62083D01*
X439250Y-62583D01*
X439667Y-63083D01*
X440167Y-63417D01*
X440750Y-63500D01*
X441333Y-63333D01*
X441917Y-62833D01*
G01X449783Y-63500D02*
Y-58500D01*
X453617Y-63500D01*
Y-58500D01*
G01X455883Y-60167D02*
Y-62500D01*
X456217Y-63083D01*
X456717Y-63417D01*
X457300Y-63500D01*
X457883Y-63417D01*
X458383Y-63083D01*
X458717Y-62500D01*
G01Y-63500D02*
Y-60167D01*
G01X460400Y-63500D02*
Y-60167D01*
G01Y-61083D02*
X460650Y-60667D01*
X461067Y-60333D01*
X461650Y-60167D01*
X462233Y-60333D01*
X462650Y-60667D01*
X462900Y-61083D01*
Y-63500D01*
G01Y-61083D02*
X463150Y-60667D01*
X463567Y-60333D01*
X464150Y-60167D01*
X464733Y-60333D01*
X465150Y-60667D01*
X465400Y-61167D01*
Y-63500D01*
G01X467000D02*
Y-58500D01*
G01Y-61000D02*
X467417Y-60500D01*
X467917Y-60250D01*
X468417Y-60167D01*
X469167Y-60333D01*
X469667Y-60667D01*
X470000Y-61250D01*
Y-61917D01*
X469833Y-62583D01*
X469500Y-63083D01*
X468917Y-63417D01*
X468417Y-63500D01*
X467917Y-63417D01*
X467417Y-63167D01*
X467000Y-62750D01*
G01X472850Y-61250D02*
X475517D01*
X475267Y-60667D01*
X474850Y-60333D01*
X474267Y-60167D01*
X473683Y-60250D01*
X473183Y-60500D01*
X472850Y-61083D01*
X472683Y-61583D01*
Y-62083D01*
X472850Y-62583D01*
X473267Y-63083D01*
X473767Y-63417D01*
X474350Y-63500D01*
X474933Y-63333D01*
X475517Y-62833D01*
G01X478533Y-63500D02*
Y-60167D01*
G01Y-60833D02*
X478950Y-60500D01*
X479367Y-60250D01*
X479950Y-60167D01*
X480367Y-60250D01*
X480867Y-60500D01*
G01X490900Y-60167D02*
Y-63500D01*
G01Y-58833D02*
X490733Y-58750D01*
Y-58583D01*
X490900Y-58500D01*
X491067Y-58583D01*
Y-58750D01*
X490900Y-58833D01*
G01X495083Y-63500D02*
Y-60167D01*
G01Y-61000D02*
X495417Y-60583D01*
X495917Y-60250D01*
X496583Y-60167D01*
X497167Y-60250D01*
X497667Y-60583D01*
X497917Y-61167D01*
Y-63500D01*
G01X506450Y-62917D02*
X506867Y-63250D01*
X507450Y-63500D01*
X507950D01*
X508450Y-63333D01*
X508783Y-63083D01*
X508950Y-62750D01*
X508867Y-62250D01*
X508533Y-62000D01*
X507033Y-61500D01*
X506700Y-60917D01*
X506867Y-60500D01*
X507200Y-60250D01*
X507700Y-60167D01*
X508200Y-60250D01*
X508700Y-60500D01*
G01X513300Y-60167D02*
Y-63500D01*
G01Y-58833D02*
X513133Y-58750D01*
Y-58583D01*
X513300Y-58500D01*
X513467Y-58583D01*
Y-58750D01*
X513300Y-58833D01*
G01X518900Y-63500D02*
Y-58500D01*
G01X523083Y-63500D02*
Y-58500D01*
G01X525750Y-60167D02*
X523083Y-62083D01*
G01X524167Y-61333D02*
X525917Y-63500D01*
G01X528850Y-62917D02*
X529267Y-63250D01*
X529850Y-63500D01*
X530350D01*
X530850Y-63333D01*
X531183Y-63083D01*
X531350Y-62750D01*
X531267Y-62250D01*
X530933Y-62000D01*
X529433Y-61500D01*
X529100Y-60917D01*
X529267Y-60500D01*
X529600Y-60250D01*
X530100Y-60167D01*
X530600Y-60250D01*
X531100Y-60500D01*
G01X537033Y-60583D02*
X536450Y-60250D01*
X535950Y-60167D01*
X535283Y-60333D01*
X534783Y-60667D01*
X534450Y-61250D01*
X534367Y-61833D01*
X534450Y-62417D01*
X534783Y-62917D01*
X535283Y-63333D01*
X535950Y-63500D01*
X536533Y-63333D01*
X537033Y-63000D01*
G01X540133Y-63500D02*
Y-60167D01*
G01Y-60833D02*
X540550Y-60500D01*
X540967Y-60250D01*
X541550Y-60167D01*
X541967Y-60250D01*
X542467Y-60500D01*
G01X545650Y-61250D02*
X548317D01*
X548067Y-60667D01*
X547650Y-60333D01*
X547067Y-60167D01*
X546483Y-60250D01*
X545983Y-60500D01*
X545650Y-61083D01*
X545483Y-61583D01*
Y-62083D01*
X545650Y-62583D01*
X546067Y-63083D01*
X546567Y-63417D01*
X547150Y-63500D01*
X547733Y-63333D01*
X548317Y-62833D01*
G01X551250Y-61250D02*
X553917D01*
X553667Y-60667D01*
X553250Y-60333D01*
X552667Y-60167D01*
X552083Y-60250D01*
X551583Y-60500D01*
X551250Y-61083D01*
X551083Y-61583D01*
Y-62083D01*
X551250Y-62583D01*
X551667Y-63083D01*
X552167Y-63417D01*
X552750Y-63500D01*
X553333Y-63333D01*
X553917Y-62833D01*
G01X556683Y-63500D02*
Y-60167D01*
G01Y-61000D02*
X557017Y-60583D01*
X557517Y-60250D01*
X558183Y-60167D01*
X558767Y-60250D01*
X559267Y-60583D01*
X559517Y-61167D01*
Y-63500D01*
G01X270750Y-47833D02*
X271417Y-48250D01*
X272167Y-48500D01*
X272833D01*
X273500Y-48250D01*
X274000Y-47833D01*
X274250Y-47250D01*
X274083Y-46667D01*
X273667Y-46167D01*
X272917Y-45833D01*
X271917Y-45667D01*
X271333Y-45333D01*
X271083Y-44750D01*
X271250Y-44167D01*
X271667Y-43750D01*
X272250Y-43500D01*
X272833D01*
X273417Y-43667D01*
X273917Y-44083D01*
G01X278100Y-48500D02*
X277600Y-48417D01*
X277100Y-48083D01*
X276767Y-47500D01*
X276600Y-46833D01*
X276767Y-46167D01*
X277100Y-45583D01*
X277600Y-45250D01*
X278100Y-45167D01*
X278600Y-45250D01*
X279100Y-45583D01*
X279433Y-46167D01*
X279517Y-46833D01*
X279433Y-47500D01*
X279100Y-48083D01*
X278600Y-48417D01*
X278100Y-48500D01*
G01X283700D02*
Y-43500D01*
G01X290800D02*
Y-48500D01*
G01Y-47750D02*
X290467Y-48167D01*
X289967Y-48417D01*
X289383Y-48500D01*
X288717Y-48333D01*
X288217Y-47917D01*
X287883Y-47417D01*
X287800Y-46833D01*
X287883Y-46250D01*
X288217Y-45750D01*
X288717Y-45333D01*
X289383Y-45167D01*
X289967Y-45250D01*
X290383Y-45417D01*
X290800Y-45750D01*
G01X293650Y-46250D02*
X296317D01*
X296067Y-45667D01*
X295650Y-45333D01*
X295067Y-45167D01*
X294483Y-45250D01*
X293983Y-45500D01*
X293650Y-46083D01*
X293483Y-46583D01*
Y-47083D01*
X293650Y-47583D01*
X294067Y-48083D01*
X294567Y-48417D01*
X295150Y-48500D01*
X295733Y-48333D01*
X296317Y-47833D01*
G01X299333Y-48500D02*
Y-45167D01*
G01Y-45833D02*
X299750Y-45500D01*
X300167Y-45250D01*
X300750Y-45167D01*
X301167Y-45250D01*
X301667Y-45500D01*
G01X309200Y-48500D02*
Y-45167D01*
G01Y-46083D02*
X309450Y-45667D01*
X309867Y-45333D01*
X310450Y-45167D01*
X311033Y-45333D01*
X311450Y-45667D01*
X311700Y-46083D01*
Y-48500D01*
G01Y-46083D02*
X311950Y-45667D01*
X312367Y-45333D01*
X312950Y-45167D01*
X313533Y-45333D01*
X313950Y-45667D01*
X314200Y-46167D01*
Y-48500D01*
G01X318800D02*
Y-45167D01*
G01Y-45750D02*
X318467Y-45417D01*
X317967Y-45250D01*
X317383Y-45167D01*
X316800Y-45333D01*
X316300Y-45667D01*
X315967Y-46167D01*
X315800Y-46833D01*
X315967Y-47500D01*
X316300Y-48000D01*
X316800Y-48333D01*
X317383Y-48500D01*
X317967Y-48417D01*
X318467Y-48167D01*
X318800Y-47833D01*
G01X321650Y-47917D02*
X322067Y-48250D01*
X322650Y-48500D01*
X323150D01*
X323650Y-48333D01*
X323983Y-48083D01*
X324150Y-47750D01*
X324067Y-47250D01*
X323733Y-47000D01*
X322233Y-46500D01*
X321900Y-45917D01*
X322067Y-45500D01*
X322400Y-45250D01*
X322900Y-45167D01*
X323400Y-45250D01*
X323900Y-45500D01*
G01X327083Y-48500D02*
Y-43500D01*
G01X329750Y-45167D02*
X327083Y-47083D01*
G01X328167Y-46333D02*
X329917Y-48500D01*
G01X339700Y-43500D02*
Y-48500D01*
G01X338533Y-45167D02*
X340867D01*
G01X343883Y-48500D02*
Y-43500D01*
G01Y-45917D02*
X344300Y-45500D01*
X344717Y-45250D01*
X345383Y-45167D01*
X345883Y-45250D01*
X346467Y-45583D01*
X346717Y-46083D01*
Y-48500D01*
G01X350900Y-45167D02*
Y-48500D01*
G01Y-43833D02*
X350733Y-43750D01*
Y-43583D01*
X350900Y-43500D01*
X351067Y-43583D01*
Y-43750D01*
X350900Y-43833D01*
G01X357833Y-45583D02*
X357250Y-45250D01*
X356750Y-45167D01*
X356083Y-45333D01*
X355583Y-45667D01*
X355250Y-46250D01*
X355167Y-46833D01*
X355250Y-47417D01*
X355583Y-47917D01*
X356083Y-48333D01*
X356750Y-48500D01*
X357333Y-48333D01*
X357833Y-48000D01*
G01X360683Y-48500D02*
Y-43500D01*
G01X363350Y-45167D02*
X360683Y-47083D01*
G01X361767Y-46333D02*
X363517Y-48500D01*
G01X366283D02*
Y-45167D01*
G01Y-46000D02*
X366617Y-45583D01*
X367117Y-45250D01*
X367783Y-45167D01*
X368367Y-45250D01*
X368867Y-45583D01*
X369117Y-46167D01*
Y-48500D01*
G01X372050Y-46250D02*
X374717D01*
X374467Y-45667D01*
X374050Y-45333D01*
X373467Y-45167D01*
X372883Y-45250D01*
X372383Y-45500D01*
X372050Y-46083D01*
X371883Y-46583D01*
Y-47083D01*
X372050Y-47583D01*
X372467Y-48083D01*
X372967Y-48417D01*
X373550Y-48500D01*
X374133Y-48333D01*
X374717Y-47833D01*
G01X377650Y-47917D02*
X378067Y-48250D01*
X378650Y-48500D01*
X379150D01*
X379650Y-48333D01*
X379983Y-48083D01*
X380150Y-47750D01*
X380067Y-47250D01*
X379733Y-47000D01*
X378233Y-46500D01*
X377900Y-45917D01*
X378067Y-45500D01*
X378400Y-45250D01*
X378900Y-45167D01*
X379400Y-45250D01*
X379900Y-45500D01*
G01X383250Y-47917D02*
X383667Y-48250D01*
X384250Y-48500D01*
X384750D01*
X385250Y-48333D01*
X385583Y-48083D01*
X385750Y-47750D01*
X385667Y-47250D01*
X385333Y-47000D01*
X383833Y-46500D01*
X383500Y-45917D01*
X383667Y-45500D01*
X384000Y-45250D01*
X384500Y-45167D01*
X385000Y-45250D01*
X385500Y-45500D01*
G01X394200Y-50167D02*
Y-45167D01*
G01Y-45917D02*
X394617Y-45500D01*
X395033Y-45250D01*
X395700Y-45167D01*
X396283Y-45250D01*
X396867Y-45667D01*
X397117Y-46250D01*
X397200Y-46833D01*
X397117Y-47417D01*
X396867Y-48000D01*
X396367Y-48333D01*
X395700Y-48500D01*
X395117Y-48417D01*
X394533Y-48167D01*
X394200Y-47833D01*
G01X401300Y-48500D02*
Y-43500D01*
G01X405483Y-45167D02*
Y-47500D01*
X405817Y-48083D01*
X406317Y-48417D01*
X406900Y-48500D01*
X407483Y-48417D01*
X407983Y-48083D01*
X408317Y-47500D01*
G01Y-48500D02*
Y-45167D01*
G01X411250Y-47917D02*
X411667Y-48250D01*
X412250Y-48500D01*
X412750D01*
X413250Y-48333D01*
X413583Y-48083D01*
X413750Y-47750D01*
X413667Y-47250D01*
X413333Y-47000D01*
X411833Y-46500D01*
X411500Y-45917D01*
X411667Y-45500D01*
X412000Y-45250D01*
X412500Y-45167D01*
X413000Y-45250D01*
X413500Y-45500D01*
G01X423700Y-48500D02*
Y-43500D01*
G01X428050Y-46250D02*
X430717D01*
X430467Y-45667D01*
X430050Y-45333D01*
X429467Y-45167D01*
X428883Y-45250D01*
X428383Y-45500D01*
X428050Y-46083D01*
X427883Y-46583D01*
Y-47083D01*
X428050Y-47583D01*
X428467Y-48083D01*
X428967Y-48417D01*
X429550Y-48500D01*
X430133Y-48333D01*
X430717Y-47833D01*
G01X433733Y-49750D02*
X434317Y-50083D01*
X434983Y-50167D01*
X435567Y-50083D01*
X436067Y-49667D01*
X436400Y-49083D01*
Y-45167D01*
G01Y-45833D02*
X436067Y-45500D01*
X435567Y-45250D01*
X434983Y-45167D01*
X434317Y-45333D01*
X433900Y-45667D01*
X433567Y-46250D01*
X433400Y-46833D01*
X433483Y-47333D01*
X433817Y-47917D01*
X434317Y-48333D01*
X434983Y-48500D01*
X435483Y-48417D01*
X436067Y-48083D01*
X436400Y-47750D01*
G01X439250Y-46250D02*
X441917D01*
X441667Y-45667D01*
X441250Y-45333D01*
X440667Y-45167D01*
X440083Y-45250D01*
X439583Y-45500D01*
X439250Y-46083D01*
X439083Y-46583D01*
Y-47083D01*
X439250Y-47583D01*
X439667Y-48083D01*
X440167Y-48417D01*
X440750Y-48500D01*
X441333Y-48333D01*
X441917Y-47833D01*
G01X444683Y-48500D02*
Y-45167D01*
G01Y-46000D02*
X445017Y-45583D01*
X445517Y-45250D01*
X446183Y-45167D01*
X446767Y-45250D01*
X447267Y-45583D01*
X447517Y-46167D01*
Y-48500D01*
G01X453200Y-43500D02*
Y-48500D01*
G01Y-47750D02*
X452867Y-48167D01*
X452367Y-48417D01*
X451783Y-48500D01*
X451117Y-48333D01*
X450617Y-47917D01*
X450283Y-47417D01*
X450200Y-46833D01*
X450283Y-46250D01*
X450617Y-45750D01*
X451117Y-45333D01*
X451783Y-45167D01*
X452367Y-45250D01*
X452783Y-45417D01*
X453200Y-45750D01*
G01X462900Y-43500D02*
Y-48500D01*
G01X461733Y-45167D02*
X464067D01*
G01X467083Y-48500D02*
Y-43500D01*
G01Y-45917D02*
X467500Y-45500D01*
X467917Y-45250D01*
X468583Y-45167D01*
X469083Y-45250D01*
X469667Y-45583D01*
X469917Y-46083D01*
Y-48500D01*
G01X474100Y-45167D02*
Y-48500D01*
G01Y-43833D02*
X473933Y-43750D01*
Y-43583D01*
X474100Y-43500D01*
X474267Y-43583D01*
Y-43750D01*
X474100Y-43833D01*
G01X481033Y-45583D02*
X480450Y-45250D01*
X479950Y-45167D01*
X479283Y-45333D01*
X478783Y-45667D01*
X478450Y-46250D01*
X478367Y-46833D01*
X478450Y-47417D01*
X478783Y-47917D01*
X479283Y-48333D01*
X479950Y-48500D01*
X480533Y-48333D01*
X481033Y-48000D01*
G01X483883Y-48500D02*
Y-43500D01*
G01X486550Y-45167D02*
X483883Y-47083D01*
G01X484967Y-46333D02*
X486717Y-48500D01*
G01X489483D02*
Y-45167D01*
G01Y-46000D02*
X489817Y-45583D01*
X490317Y-45250D01*
X490983Y-45167D01*
X491567Y-45250D01*
X492067Y-45583D01*
X492317Y-46167D01*
Y-48500D01*
G01X495250Y-46250D02*
X497917D01*
X497667Y-45667D01*
X497250Y-45333D01*
X496667Y-45167D01*
X496083Y-45250D01*
X495583Y-45500D01*
X495250Y-46083D01*
X495083Y-46583D01*
Y-47083D01*
X495250Y-47583D01*
X495667Y-48083D01*
X496167Y-48417D01*
X496750Y-48500D01*
X497333Y-48333D01*
X497917Y-47833D01*
G01X500850Y-47917D02*
X501267Y-48250D01*
X501850Y-48500D01*
X502350D01*
X502850Y-48333D01*
X503183Y-48083D01*
X503350Y-47750D01*
X503267Y-47250D01*
X502933Y-47000D01*
X501433Y-46500D01*
X501100Y-45917D01*
X501267Y-45500D01*
X501600Y-45250D01*
X502100Y-45167D01*
X502600Y-45250D01*
X503100Y-45500D01*
G01X506450Y-47917D02*
X506867Y-48250D01*
X507450Y-48500D01*
X507950D01*
X508450Y-48333D01*
X508783Y-48083D01*
X508950Y-47750D01*
X508867Y-47250D01*
X508533Y-47000D01*
X507033Y-46500D01*
X506700Y-45917D01*
X506867Y-45500D01*
X507200Y-45250D01*
X507700Y-45167D01*
X508200Y-45250D01*
X508700Y-45500D01*
G01X518900Y-48500D02*
X518400Y-48417D01*
X517900Y-48083D01*
X517567Y-47500D01*
X517400Y-46833D01*
X517567Y-46167D01*
X517900Y-45583D01*
X518400Y-45250D01*
X518900Y-45167D01*
X519400Y-45250D01*
X519900Y-45583D01*
X520233Y-46167D01*
X520317Y-46833D01*
X520233Y-47500D01*
X519900Y-48083D01*
X519400Y-48417D01*
X518900Y-48500D01*
G01X523083D02*
Y-45167D01*
G01Y-46000D02*
X523417Y-45583D01*
X523917Y-45250D01*
X524583Y-45167D01*
X525167Y-45250D01*
X525667Y-45583D01*
X525917Y-46167D01*
Y-48500D01*
G01X535700Y-43500D02*
Y-48500D01*
G01X534533Y-45167D02*
X536867D01*
G01X540133Y-48500D02*
Y-45167D01*
G01Y-45833D02*
X540550Y-45500D01*
X540967Y-45250D01*
X541550Y-45167D01*
X541967Y-45250D01*
X542467Y-45500D01*
G01X548400Y-48500D02*
Y-45167D01*
G01Y-45750D02*
X548067Y-45417D01*
X547567Y-45250D01*
X546983Y-45167D01*
X546400Y-45333D01*
X545900Y-45667D01*
X545567Y-46167D01*
X545400Y-46833D01*
X545567Y-47500D01*
X545900Y-48000D01*
X546400Y-48333D01*
X546983Y-48500D01*
X547567Y-48417D01*
X548067Y-48167D01*
X548400Y-47833D01*
G01X553833Y-45583D02*
X553250Y-45250D01*
X552750Y-45167D01*
X552083Y-45333D01*
X551583Y-45667D01*
X551250Y-46250D01*
X551167Y-46833D01*
X551250Y-47417D01*
X551583Y-47917D01*
X552083Y-48333D01*
X552750Y-48500D01*
X553333Y-48333D01*
X553833Y-48000D01*
G01X556850Y-46250D02*
X559517D01*
X559267Y-45667D01*
X558850Y-45333D01*
X558267Y-45167D01*
X557683Y-45250D01*
X557183Y-45500D01*
X556850Y-46083D01*
X556683Y-46583D01*
Y-47083D01*
X556850Y-47583D01*
X557267Y-48083D01*
X557767Y-48417D01*
X558350Y-48500D01*
X558933Y-48333D01*
X559517Y-47833D01*
G01X563700Y-48667D02*
X563533Y-48583D01*
Y-48417D01*
X563700Y-48333D01*
X563867Y-48417D01*
Y-48583D01*
X563700Y-48667D01*
G01X272500Y-33500D02*
Y-28500D01*
G01X276850Y-31250D02*
X279517D01*
X279267Y-30667D01*
X278850Y-30333D01*
X278267Y-30167D01*
X277683Y-30250D01*
X277183Y-30500D01*
X276850Y-31083D01*
X276683Y-31583D01*
Y-32083D01*
X276850Y-32583D01*
X277267Y-33083D01*
X277767Y-33417D01*
X278350Y-33500D01*
X278933Y-33333D01*
X279517Y-32833D01*
G01X282533Y-34750D02*
X283117Y-35083D01*
X283783Y-35167D01*
X284367Y-35083D01*
X284867Y-34667D01*
X285200Y-34083D01*
Y-30167D01*
G01Y-30833D02*
X284867Y-30500D01*
X284367Y-30250D01*
X283783Y-30167D01*
X283117Y-30333D01*
X282700Y-30667D01*
X282367Y-31250D01*
X282200Y-31833D01*
X282283Y-32333D01*
X282617Y-32917D01*
X283117Y-33333D01*
X283783Y-33500D01*
X284283Y-33417D01*
X284867Y-33083D01*
X285200Y-32750D01*
G01X288050Y-31250D02*
X290717D01*
X290467Y-30667D01*
X290050Y-30333D01*
X289467Y-30167D01*
X288883Y-30250D01*
X288383Y-30500D01*
X288050Y-31083D01*
X287883Y-31583D01*
Y-32083D01*
X288050Y-32583D01*
X288467Y-33083D01*
X288967Y-33417D01*
X289550Y-33500D01*
X290133Y-33333D01*
X290717Y-32833D01*
G01X293483Y-33500D02*
Y-30167D01*
G01Y-31000D02*
X293817Y-30583D01*
X294317Y-30250D01*
X294983Y-30167D01*
X295567Y-30250D01*
X296067Y-30583D01*
X296317Y-31167D01*
Y-33500D01*
G01X302000Y-28500D02*
Y-33500D01*
G01Y-32750D02*
X301667Y-33167D01*
X301167Y-33417D01*
X300583Y-33500D01*
X299917Y-33333D01*
X299417Y-32917D01*
X299083Y-32417D01*
X299000Y-31833D01*
X299083Y-31250D01*
X299417Y-30750D01*
X299917Y-30333D01*
X300583Y-30167D01*
X301167Y-30250D01*
X301583Y-30417D01*
X302000Y-30750D01*
G01X311700Y-28500D02*
Y-33500D01*
G01X310533Y-30167D02*
X312867D01*
G01X315883Y-33500D02*
Y-28500D01*
G01Y-30917D02*
X316300Y-30500D01*
X316717Y-30250D01*
X317383Y-30167D01*
X317883Y-30250D01*
X318467Y-30583D01*
X318717Y-31083D01*
Y-33500D01*
G01X322900Y-30167D02*
Y-33500D01*
G01Y-28833D02*
X322733Y-28750D01*
Y-28583D01*
X322900Y-28500D01*
X323067Y-28583D01*
Y-28750D01*
X322900Y-28833D01*
G01X329833Y-30583D02*
X329250Y-30250D01*
X328750Y-30167D01*
X328083Y-30333D01*
X327583Y-30667D01*
X327250Y-31250D01*
X327167Y-31833D01*
X327250Y-32417D01*
X327583Y-32917D01*
X328083Y-33333D01*
X328750Y-33500D01*
X329333Y-33333D01*
X329833Y-33000D01*
G01X332683Y-33500D02*
Y-28500D01*
G01X335350Y-30167D02*
X332683Y-32083D01*
G01X333767Y-31333D02*
X335517Y-33500D01*
G01X338283D02*
Y-30167D01*
G01Y-31000D02*
X338617Y-30583D01*
X339117Y-30250D01*
X339783Y-30167D01*
X340367Y-30250D01*
X340867Y-30583D01*
X341117Y-31167D01*
Y-33500D01*
G01X344050Y-31250D02*
X346717D01*
X346467Y-30667D01*
X346050Y-30333D01*
X345467Y-30167D01*
X344883Y-30250D01*
X344383Y-30500D01*
X344050Y-31083D01*
X343883Y-31583D01*
Y-32083D01*
X344050Y-32583D01*
X344467Y-33083D01*
X344967Y-33417D01*
X345550Y-33500D01*
X346133Y-33333D01*
X346717Y-32833D01*
G01X349650Y-32917D02*
X350067Y-33250D01*
X350650Y-33500D01*
X351150D01*
X351650Y-33333D01*
X351983Y-33083D01*
X352150Y-32750D01*
X352067Y-32250D01*
X351733Y-32000D01*
X350233Y-31500D01*
X349900Y-30917D01*
X350067Y-30500D01*
X350400Y-30250D01*
X350900Y-30167D01*
X351400Y-30250D01*
X351900Y-30500D01*
G01X355250Y-32917D02*
X355667Y-33250D01*
X356250Y-33500D01*
X356750D01*
X357250Y-33333D01*
X357583Y-33083D01*
X357750Y-32750D01*
X357667Y-32250D01*
X357333Y-32000D01*
X355833Y-31500D01*
X355500Y-30917D01*
X355667Y-30500D01*
X356000Y-30250D01*
X356500Y-30167D01*
X357000Y-30250D01*
X357500Y-30500D01*
G01X367700Y-33500D02*
X367200Y-33417D01*
X366700Y-33083D01*
X366367Y-32500D01*
X366200Y-31833D01*
X366367Y-31167D01*
X366700Y-30583D01*
X367200Y-30250D01*
X367700Y-30167D01*
X368200Y-30250D01*
X368700Y-30583D01*
X369033Y-31167D01*
X369117Y-31833D01*
X369033Y-32500D01*
X368700Y-33083D01*
X368200Y-33417D01*
X367700Y-33500D01*
G01X371883D02*
Y-30167D01*
G01Y-31000D02*
X372217Y-30583D01*
X372717Y-30250D01*
X373383Y-30167D01*
X373967Y-30250D01*
X374467Y-30583D01*
X374717Y-31167D01*
Y-33500D01*
G01X385833Y-30583D02*
X385250Y-30250D01*
X384750Y-30167D01*
X384083Y-30333D01*
X383583Y-30667D01*
X383250Y-31250D01*
X383167Y-31833D01*
X383250Y-32417D01*
X383583Y-32917D01*
X384083Y-33333D01*
X384750Y-33500D01*
X385333Y-33333D01*
X385833Y-33000D01*
G01X390100Y-33500D02*
X389600Y-33417D01*
X389100Y-33083D01*
X388767Y-32500D01*
X388600Y-31833D01*
X388767Y-31167D01*
X389100Y-30583D01*
X389600Y-30250D01*
X390100Y-30167D01*
X390600Y-30250D01*
X391100Y-30583D01*
X391433Y-31167D01*
X391517Y-31833D01*
X391433Y-32500D01*
X391100Y-33083D01*
X390600Y-33417D01*
X390100Y-33500D01*
G01X394200Y-35167D02*
Y-30167D01*
G01Y-30917D02*
X394617Y-30500D01*
X395033Y-30250D01*
X395700Y-30167D01*
X396283Y-30250D01*
X396867Y-30667D01*
X397117Y-31250D01*
X397200Y-31833D01*
X397117Y-32417D01*
X396867Y-33000D01*
X396367Y-33333D01*
X395700Y-33500D01*
X395117Y-33417D01*
X394533Y-33167D01*
X394200Y-32833D01*
G01X399800Y-35167D02*
Y-30167D01*
G01Y-30917D02*
X400217Y-30500D01*
X400633Y-30250D01*
X401300Y-30167D01*
X401883Y-30250D01*
X402467Y-30667D01*
X402717Y-31250D01*
X402800Y-31833D01*
X402717Y-32417D01*
X402467Y-33000D01*
X401967Y-33333D01*
X401300Y-33500D01*
X400717Y-33417D01*
X400133Y-33167D01*
X399800Y-32833D01*
G01X405650Y-31250D02*
X408317D01*
X408067Y-30667D01*
X407650Y-30333D01*
X407067Y-30167D01*
X406483Y-30250D01*
X405983Y-30500D01*
X405650Y-31083D01*
X405483Y-31583D01*
Y-32083D01*
X405650Y-32583D01*
X406067Y-33083D01*
X406567Y-33417D01*
X407150Y-33500D01*
X407733Y-33333D01*
X408317Y-32833D01*
G01X411333Y-33500D02*
Y-30167D01*
G01Y-30833D02*
X411750Y-30500D01*
X412167Y-30250D01*
X412750Y-30167D01*
X413167Y-30250D01*
X413667Y-30500D01*
G01X423283Y-35167D02*
X422450Y-34333D01*
X422033Y-33500D01*
Y-30167D01*
X422450Y-29333D01*
X423283Y-28500D01*
G01X427217Y-30167D02*
X428217Y-33500D01*
X429300Y-30167D01*
X430383Y-33500D01*
X431383Y-30167D01*
G01X433483Y-33500D02*
Y-28500D01*
G01Y-30917D02*
X433900Y-30500D01*
X434317Y-30250D01*
X434983Y-30167D01*
X435483Y-30250D01*
X436067Y-30583D01*
X436317Y-31083D01*
Y-33500D01*
G01X440500Y-30167D02*
Y-33500D01*
G01Y-28833D02*
X440333Y-28750D01*
Y-28583D01*
X440500Y-28500D01*
X440667Y-28583D01*
Y-28750D01*
X440500Y-28833D01*
G01X447433Y-30583D02*
X446850Y-30250D01*
X446350Y-30167D01*
X445683Y-30333D01*
X445183Y-30667D01*
X444850Y-31250D01*
X444767Y-31833D01*
X444850Y-32417D01*
X445183Y-32917D01*
X445683Y-33333D01*
X446350Y-33500D01*
X446933Y-33333D01*
X447433Y-33000D01*
G01X450283Y-33500D02*
Y-28500D01*
G01Y-30917D02*
X450700Y-30500D01*
X451117Y-30250D01*
X451783Y-30167D01*
X452283Y-30250D01*
X452867Y-30583D01*
X453117Y-31083D01*
Y-33500D01*
G01X462900Y-30167D02*
Y-33500D01*
G01Y-28833D02*
X462733Y-28750D01*
Y-28583D01*
X462900Y-28500D01*
X463067Y-28583D01*
Y-28750D01*
X462900Y-28833D01*
G01X467250Y-32917D02*
X467667Y-33250D01*
X468250Y-33500D01*
X468750D01*
X469250Y-33333D01*
X469583Y-33083D01*
X469750Y-32750D01*
X469667Y-32250D01*
X469333Y-32000D01*
X467833Y-31500D01*
X467500Y-30917D01*
X467667Y-30500D01*
X468000Y-30250D01*
X468500Y-30167D01*
X469000Y-30250D01*
X469500Y-30500D01*
G01X478200Y-33500D02*
Y-28500D01*
G01Y-31000D02*
X478617Y-30500D01*
X479117Y-30250D01*
X479617Y-30167D01*
X480367Y-30333D01*
X480867Y-30667D01*
X481200Y-31250D01*
Y-31917D01*
X481033Y-32583D01*
X480700Y-33083D01*
X480117Y-33417D01*
X479617Y-33500D01*
X479117Y-33417D01*
X478617Y-33167D01*
X478200Y-32750D01*
G01X484050Y-31250D02*
X486717D01*
X486467Y-30667D01*
X486050Y-30333D01*
X485467Y-30167D01*
X484883Y-30250D01*
X484383Y-30500D01*
X484050Y-31083D01*
X483883Y-31583D01*
Y-32083D01*
X484050Y-32583D01*
X484467Y-33083D01*
X484967Y-33417D01*
X485550Y-33500D01*
X486133Y-33333D01*
X486717Y-32833D01*
G01X490900Y-28500D02*
Y-33500D01*
G01X489733Y-30167D02*
X492067D01*
G01X496500Y-28500D02*
Y-33500D01*
G01X495333Y-30167D02*
X497667D01*
G01X500850Y-31250D02*
X503517D01*
X503267Y-30667D01*
X502850Y-30333D01*
X502267Y-30167D01*
X501683Y-30250D01*
X501183Y-30500D01*
X500850Y-31083D01*
X500683Y-31583D01*
Y-32083D01*
X500850Y-32583D01*
X501267Y-33083D01*
X501767Y-33417D01*
X502350Y-33500D01*
X502933Y-33333D01*
X503517Y-32833D01*
G01X506533Y-33500D02*
Y-30167D01*
G01Y-30833D02*
X506950Y-30500D01*
X507367Y-30250D01*
X507950Y-30167D01*
X508367Y-30250D01*
X508867Y-30500D01*
G01X513717Y-35167D02*
X514550Y-34333D01*
X514967Y-33500D01*
Y-30167D01*
X514550Y-29333D01*
X513717Y-28500D01*
G01X271250Y-19417D02*
X271667Y-19750D01*
X272250Y-20000D01*
X272750D01*
X273250Y-19833D01*
X273583Y-19583D01*
X273750Y-19250D01*
X273667Y-18750D01*
X273333Y-18500D01*
X271833Y-18000D01*
X271500Y-17417D01*
X271667Y-17000D01*
X272000Y-16750D01*
X272500Y-16667D01*
X273000Y-16750D01*
X273500Y-17000D01*
G01X278100Y-20000D02*
X277600Y-19917D01*
X277100Y-19583D01*
X276767Y-19000D01*
X276600Y-18333D01*
X276767Y-17667D01*
X277100Y-17083D01*
X277600Y-16750D01*
X278100Y-16667D01*
X278600Y-16750D01*
X279100Y-17083D01*
X279433Y-17667D01*
X279517Y-18333D01*
X279433Y-19000D01*
X279100Y-19583D01*
X278600Y-19917D01*
X278100Y-20000D01*
G01X283700D02*
Y-15000D01*
G01X290800D02*
Y-20000D01*
G01Y-19250D02*
X290467Y-19667D01*
X289967Y-19917D01*
X289383Y-20000D01*
X288717Y-19833D01*
X288217Y-19417D01*
X287883Y-18917D01*
X287800Y-18333D01*
X287883Y-17750D01*
X288217Y-17250D01*
X288717Y-16833D01*
X289383Y-16667D01*
X289967Y-16750D01*
X290383Y-16917D01*
X290800Y-17250D01*
G01X293650Y-17750D02*
X296317D01*
X296067Y-17167D01*
X295650Y-16833D01*
X295067Y-16667D01*
X294483Y-16750D01*
X293983Y-17000D01*
X293650Y-17583D01*
X293483Y-18083D01*
Y-18583D01*
X293650Y-19083D01*
X294067Y-19583D01*
X294567Y-19917D01*
X295150Y-20000D01*
X295733Y-19833D01*
X296317Y-19333D01*
G01X299333Y-20000D02*
Y-16667D01*
G01Y-17333D02*
X299750Y-17000D01*
X300167Y-16750D01*
X300750Y-16667D01*
X301167Y-16750D01*
X301667Y-17000D01*
G01X309200Y-20000D02*
Y-16667D01*
G01Y-17583D02*
X309450Y-17167D01*
X309867Y-16833D01*
X310450Y-16667D01*
X311033Y-16833D01*
X311450Y-17167D01*
X311700Y-17583D01*
Y-20000D01*
G01Y-17583D02*
X311950Y-17167D01*
X312367Y-16833D01*
X312950Y-16667D01*
X313533Y-16833D01*
X313950Y-17167D01*
X314200Y-17667D01*
Y-20000D01*
G01X318800D02*
Y-16667D01*
G01Y-17250D02*
X318467Y-16917D01*
X317967Y-16750D01*
X317383Y-16667D01*
X316800Y-16833D01*
X316300Y-17167D01*
X315967Y-17667D01*
X315800Y-18333D01*
X315967Y-19000D01*
X316300Y-19500D01*
X316800Y-19833D01*
X317383Y-20000D01*
X317967Y-19917D01*
X318467Y-19667D01*
X318800Y-19333D01*
G01X321650Y-19417D02*
X322067Y-19750D01*
X322650Y-20000D01*
X323150D01*
X323650Y-19833D01*
X323983Y-19583D01*
X324150Y-19250D01*
X324067Y-18750D01*
X323733Y-18500D01*
X322233Y-18000D01*
X321900Y-17417D01*
X322067Y-17000D01*
X322400Y-16750D01*
X322900Y-16667D01*
X323400Y-16750D01*
X323900Y-17000D01*
G01X327083Y-20000D02*
Y-15000D01*
G01X329750Y-16667D02*
X327083Y-18583D01*
G01X328167Y-17833D02*
X329917Y-20000D01*
G01X339700Y-15000D02*
Y-20000D01*
G01X338533Y-16667D02*
X340867D01*
G01X343883Y-20000D02*
Y-15000D01*
G01Y-17417D02*
X344300Y-17000D01*
X344717Y-16750D01*
X345383Y-16667D01*
X345883Y-16750D01*
X346467Y-17083D01*
X346717Y-17583D01*
Y-20000D01*
G01X350900Y-16667D02*
Y-20000D01*
G01Y-15333D02*
X350733Y-15250D01*
Y-15083D01*
X350900Y-15000D01*
X351067Y-15083D01*
Y-15250D01*
X350900Y-15333D01*
G01X357833Y-17083D02*
X357250Y-16750D01*
X356750Y-16667D01*
X356083Y-16833D01*
X355583Y-17167D01*
X355250Y-17750D01*
X355167Y-18333D01*
X355250Y-18917D01*
X355583Y-19417D01*
X356083Y-19833D01*
X356750Y-20000D01*
X357333Y-19833D01*
X357833Y-19500D01*
G01X360683Y-20000D02*
Y-15000D01*
G01X363350Y-16667D02*
X360683Y-18583D01*
G01X361767Y-17833D02*
X363517Y-20000D01*
G01X366283D02*
Y-16667D01*
G01Y-17500D02*
X366617Y-17083D01*
X367117Y-16750D01*
X367783Y-16667D01*
X368367Y-16750D01*
X368867Y-17083D01*
X369117Y-17667D01*
Y-20000D01*
G01X372050Y-17750D02*
X374717D01*
X374467Y-17167D01*
X374050Y-16833D01*
X373467Y-16667D01*
X372883Y-16750D01*
X372383Y-17000D01*
X372050Y-17583D01*
X371883Y-18083D01*
Y-18583D01*
X372050Y-19083D01*
X372467Y-19583D01*
X372967Y-19917D01*
X373550Y-20000D01*
X374133Y-19833D01*
X374717Y-19333D01*
G01X377650Y-19417D02*
X378067Y-19750D01*
X378650Y-20000D01*
X379150D01*
X379650Y-19833D01*
X379983Y-19583D01*
X380150Y-19250D01*
X380067Y-18750D01*
X379733Y-18500D01*
X378233Y-18000D01*
X377900Y-17417D01*
X378067Y-17000D01*
X378400Y-16750D01*
X378900Y-16667D01*
X379400Y-16750D01*
X379900Y-17000D01*
G01X383250Y-19417D02*
X383667Y-19750D01*
X384250Y-20000D01*
X384750D01*
X385250Y-19833D01*
X385583Y-19583D01*
X385750Y-19250D01*
X385667Y-18750D01*
X385333Y-18500D01*
X383833Y-18000D01*
X383500Y-17417D01*
X383667Y-17000D01*
X384000Y-16750D01*
X384500Y-16667D01*
X385000Y-16750D01*
X385500Y-17000D01*
G01X272500Y0D02*
Y-5000D01*
G01X270583Y0D02*
X274417D01*
G01X276683Y-5000D02*
Y0D01*
G01Y-2417D02*
X277100Y-2000D01*
X277517Y-1750D01*
X278183Y-1667D01*
X278683Y-1750D01*
X279267Y-2083D01*
X279517Y-2583D01*
Y-5000D01*
G01X282450Y-2750D02*
X285117D01*
X284867Y-2167D01*
X284450Y-1833D01*
X283867Y-1667D01*
X283283Y-1750D01*
X282783Y-2000D01*
X282450Y-2583D01*
X282283Y-3083D01*
Y-3583D01*
X282450Y-4083D01*
X282867Y-4583D01*
X283367Y-4917D01*
X283950Y-5000D01*
X284533Y-4833D01*
X285117Y-4333D01*
G01X294900Y-5000D02*
Y0D01*
G01X302000Y-5000D02*
Y-1667D01*
G01Y-2250D02*
X301667Y-1917D01*
X301167Y-1750D01*
X300583Y-1667D01*
X300000Y-1833D01*
X299500Y-2167D01*
X299167Y-2667D01*
X299000Y-3333D01*
X299167Y-4000D01*
X299500Y-4500D01*
X300000Y-4833D01*
X300583Y-5000D01*
X301167Y-4917D01*
X301667Y-4667D01*
X302000Y-4333D01*
G01X304933Y-5000D02*
Y-1667D01*
G01Y-2333D02*
X305350Y-2000D01*
X305767Y-1750D01*
X306350Y-1667D01*
X306767Y-1750D01*
X307267Y-2000D01*
G01X310533Y-6250D02*
X311117Y-6583D01*
X311783Y-6667D01*
X312367Y-6583D01*
X312867Y-6167D01*
X313200Y-5583D01*
Y-1667D01*
G01Y-2333D02*
X312867Y-2000D01*
X312367Y-1750D01*
X311783Y-1667D01*
X311117Y-1833D01*
X310700Y-2167D01*
X310367Y-2750D01*
X310200Y-3333D01*
X310283Y-3833D01*
X310617Y-4417D01*
X311117Y-4833D01*
X311783Y-5000D01*
X312283Y-4917D01*
X312867Y-4583D01*
X313200Y-4250D01*
G01X316050Y-2750D02*
X318717D01*
X318467Y-2167D01*
X318050Y-1833D01*
X317467Y-1667D01*
X316883Y-1750D01*
X316383Y-2000D01*
X316050Y-2583D01*
X315883Y-3083D01*
Y-3583D01*
X316050Y-4083D01*
X316467Y-4583D01*
X316967Y-4917D01*
X317550Y-5000D01*
X318133Y-4833D01*
X318717Y-4333D01*
G01X321650Y-4417D02*
X322067Y-4750D01*
X322650Y-5000D01*
X323150D01*
X323650Y-4833D01*
X323983Y-4583D01*
X324150Y-4250D01*
X324067Y-3750D01*
X323733Y-3500D01*
X322233Y-3000D01*
X321900Y-2417D01*
X322067Y-2000D01*
X322400Y-1750D01*
X322900Y-1667D01*
X323400Y-1750D01*
X323900Y-2000D01*
G01X328500Y0D02*
Y-5000D01*
G01X327333Y-1667D02*
X329667D01*
G01X341200Y0D02*
Y-5000D01*
G01Y-4250D02*
X340867Y-4667D01*
X340367Y-4917D01*
X339783Y-5000D01*
X339117Y-4833D01*
X338617Y-4417D01*
X338283Y-3917D01*
X338200Y-3333D01*
X338283Y-2750D01*
X338617Y-2250D01*
X339117Y-1833D01*
X339783Y-1667D01*
X340367Y-1750D01*
X340783Y-1917D01*
X341200Y-2250D01*
G01X345300Y-1667D02*
Y-5000D01*
G01Y-333D02*
X345133Y-250D01*
Y-83D01*
X345300Y0D01*
X345467Y-83D01*
Y-250D01*
X345300Y-333D01*
G01X348400Y-5000D02*
Y-1667D01*
G01Y-2583D02*
X348650Y-2167D01*
X349067Y-1833D01*
X349650Y-1667D01*
X350233Y-1833D01*
X350650Y-2167D01*
X350900Y-2583D01*
Y-5000D01*
G01Y-2583D02*
X351150Y-2167D01*
X351567Y-1833D01*
X352150Y-1667D01*
X352733Y-1833D01*
X353150Y-2167D01*
X353400Y-2667D01*
Y-5000D01*
G01X355250Y-2750D02*
X357917D01*
X357667Y-2167D01*
X357250Y-1833D01*
X356667Y-1667D01*
X356083Y-1750D01*
X355583Y-2000D01*
X355250Y-2583D01*
X355083Y-3083D01*
Y-3583D01*
X355250Y-4083D01*
X355667Y-4583D01*
X356167Y-4917D01*
X356750Y-5000D01*
X357333Y-4833D01*
X357917Y-4333D01*
G01X360683Y-5000D02*
Y-1667D01*
G01Y-2500D02*
X361017Y-2083D01*
X361517Y-1750D01*
X362183Y-1667D01*
X362767Y-1750D01*
X363267Y-2083D01*
X363517Y-2667D01*
Y-5000D01*
G01X366450Y-4417D02*
X366867Y-4750D01*
X367450Y-5000D01*
X367950D01*
X368450Y-4833D01*
X368783Y-4583D01*
X368950Y-4250D01*
X368867Y-3750D01*
X368533Y-3500D01*
X367033Y-3000D01*
X366700Y-2417D01*
X366867Y-2000D01*
X367200Y-1750D01*
X367700Y-1667D01*
X368200Y-1750D01*
X368700Y-2000D01*
G01X373300Y-1667D02*
Y-5000D01*
G01Y-333D02*
X373133Y-250D01*
Y-83D01*
X373300Y0D01*
X373467Y-83D01*
Y-250D01*
X373300Y-333D01*
G01X378900Y-5000D02*
X378400Y-4917D01*
X377900Y-4583D01*
X377567Y-4000D01*
X377400Y-3333D01*
X377567Y-2667D01*
X377900Y-2083D01*
X378400Y-1750D01*
X378900Y-1667D01*
X379400Y-1750D01*
X379900Y-2083D01*
X380233Y-2667D01*
X380317Y-3333D01*
X380233Y-4000D01*
X379900Y-4583D01*
X379400Y-4917D01*
X378900Y-5000D01*
G01X383083D02*
Y-1667D01*
G01Y-2500D02*
X383417Y-2083D01*
X383917Y-1750D01*
X384583Y-1667D01*
X385167Y-1750D01*
X385667Y-2083D01*
X385917Y-2667D01*
Y-5000D01*
G01X395700D02*
X395200Y-4917D01*
X394700Y-4583D01*
X394367Y-4000D01*
X394200Y-3333D01*
X394367Y-2667D01*
X394700Y-2083D01*
X395200Y-1750D01*
X395700Y-1667D01*
X396200Y-1750D01*
X396700Y-2083D01*
X397033Y-2667D01*
X397117Y-3333D01*
X397033Y-4000D01*
X396700Y-4583D01*
X396200Y-4917D01*
X395700Y-5000D01*
G01X400800D02*
Y-750D01*
X400967Y-333D01*
X401300Y-83D01*
X401800Y0D01*
X402300Y-167D01*
X402550Y-583D01*
G01X401550Y-2000D02*
X399883D01*
G01X411000Y-6667D02*
Y-1667D01*
G01Y-2417D02*
X411417Y-2000D01*
X411833Y-1750D01*
X412500Y-1667D01*
X413083Y-1750D01*
X413667Y-2167D01*
X413917Y-2750D01*
X414000Y-3333D01*
X413917Y-3917D01*
X413667Y-4500D01*
X413167Y-4833D01*
X412500Y-5000D01*
X411917Y-4917D01*
X411333Y-4667D01*
X411000Y-4333D01*
G01X419600Y-5000D02*
Y-1667D01*
G01Y-2250D02*
X419267Y-1917D01*
X418767Y-1750D01*
X418183Y-1667D01*
X417600Y-1833D01*
X417100Y-2167D01*
X416767Y-2667D01*
X416600Y-3333D01*
X416767Y-4000D01*
X417100Y-4500D01*
X417600Y-4833D01*
X418183Y-5000D01*
X418767Y-4917D01*
X419267Y-4667D01*
X419600Y-4333D01*
G01X425200Y0D02*
Y-5000D01*
G01Y-4250D02*
X424867Y-4667D01*
X424367Y-4917D01*
X423783Y-5000D01*
X423117Y-4833D01*
X422617Y-4417D01*
X422283Y-3917D01*
X422200Y-3333D01*
X422283Y-2750D01*
X422617Y-2250D01*
X423117Y-1833D01*
X423783Y-1667D01*
X424367Y-1750D01*
X424783Y-1917D01*
X425200Y-2250D01*
G01X434900Y-5000D02*
X434400Y-4917D01*
X433900Y-4583D01*
X433567Y-4000D01*
X433400Y-3333D01*
X433567Y-2667D01*
X433900Y-2083D01*
X434400Y-1750D01*
X434900Y-1667D01*
X435400Y-1750D01*
X435900Y-2083D01*
X436233Y-2667D01*
X436317Y-3333D01*
X436233Y-4000D01*
X435900Y-4583D01*
X435400Y-4917D01*
X434900Y-5000D01*
G01X439333D02*
Y-1667D01*
G01Y-2333D02*
X439750Y-2000D01*
X440167Y-1750D01*
X440750Y-1667D01*
X441167Y-1750D01*
X441667Y-2000D01*
G01X453200Y0D02*
Y-5000D01*
G01Y-4250D02*
X452867Y-4667D01*
X452367Y-4917D01*
X451783Y-5000D01*
X451117Y-4833D01*
X450617Y-4417D01*
X450283Y-3917D01*
X450200Y-3333D01*
X450283Y-2750D01*
X450617Y-2250D01*
X451117Y-1833D01*
X451783Y-1667D01*
X452367Y-1750D01*
X452783Y-1917D01*
X453200Y-2250D01*
G01X457300Y-1667D02*
Y-5000D01*
G01Y-333D02*
X457133Y-250D01*
Y-83D01*
X457300Y0D01*
X457467Y-83D01*
Y-250D01*
X457300Y-333D01*
G01X464400Y-5000D02*
Y-1667D01*
G01Y-2250D02*
X464067Y-1917D01*
X463567Y-1750D01*
X462983Y-1667D01*
X462400Y-1833D01*
X461900Y-2167D01*
X461567Y-2667D01*
X461400Y-3333D01*
X461567Y-4000D01*
X461900Y-4500D01*
X462400Y-4833D01*
X462983Y-5000D01*
X463567Y-4917D01*
X464067Y-4667D01*
X464400Y-4333D01*
G01X466000Y-5000D02*
Y-1667D01*
G01Y-2583D02*
X466250Y-2167D01*
X466667Y-1833D01*
X467250Y-1667D01*
X467833Y-1833D01*
X468250Y-2167D01*
X468500Y-2583D01*
Y-5000D01*
G01Y-2583D02*
X468750Y-2167D01*
X469167Y-1833D01*
X469750Y-1667D01*
X470333Y-1833D01*
X470750Y-2167D01*
X471000Y-2667D01*
Y-5000D01*
G01X472850Y-2750D02*
X475517D01*
X475267Y-2167D01*
X474850Y-1833D01*
X474267Y-1667D01*
X473683Y-1750D01*
X473183Y-2000D01*
X472850Y-2583D01*
X472683Y-3083D01*
Y-3583D01*
X472850Y-4083D01*
X473267Y-4583D01*
X473767Y-4917D01*
X474350Y-5000D01*
X474933Y-4833D01*
X475517Y-4333D01*
G01X479700Y0D02*
Y-5000D01*
G01X478533Y-1667D02*
X480867D01*
G01X484050Y-2750D02*
X486717D01*
X486467Y-2167D01*
X486050Y-1833D01*
X485467Y-1667D01*
X484883Y-1750D01*
X484383Y-2000D01*
X484050Y-2583D01*
X483883Y-3083D01*
Y-3583D01*
X484050Y-4083D01*
X484467Y-4583D01*
X484967Y-4917D01*
X485550Y-5000D01*
X486133Y-4833D01*
X486717Y-4333D01*
G01X489733Y-5000D02*
Y-1667D01*
G01Y-2333D02*
X490150Y-2000D01*
X490567Y-1750D01*
X491150Y-1667D01*
X491567Y-1750D01*
X492067Y-2000D01*
G01X503767Y-5000D02*
X500433Y-3333D01*
X503767Y-1667D01*
G01X506617Y-4083D02*
X508783D01*
G01Y-2583D02*
X506617D01*
G01X518900Y-5000D02*
Y0D01*
X517900Y-1000D01*
G01Y-5000D02*
X519900D01*
G01X525500D02*
Y0D01*
X522417Y-3583D01*
X526583D01*
G01X533200Y-5000D02*
Y-1667D01*
G01Y-2583D02*
X533450Y-2167D01*
X533867Y-1833D01*
X534450Y-1667D01*
X535033Y-1833D01*
X535450Y-2167D01*
X535700Y-2583D01*
Y-5000D01*
G01Y-2583D02*
X535950Y-2167D01*
X536367Y-1833D01*
X536950Y-1667D01*
X537533Y-1833D01*
X537950Y-2167D01*
X538200Y-2667D01*
Y-5000D01*
G01X541300Y-1667D02*
Y-5000D01*
G01Y-333D02*
X541133Y-250D01*
Y-83D01*
X541300Y0D01*
X541467Y-83D01*
Y-250D01*
X541300Y-333D01*
G01X546900Y-5000D02*
Y0D01*
G01X273580Y32670D02*
Y27670D01*
G01X271663Y32670D02*
X275497D01*
G01X277763Y27670D02*
Y32670D01*
G01Y30253D02*
X278180Y30670D01*
X278597Y30920D01*
X279263Y31003D01*
X279763Y30920D01*
X280347Y30587D01*
X280597Y30087D01*
Y27670D01*
G01X283530Y29920D02*
X286197D01*
X285947Y30503D01*
X285530Y30837D01*
X284947Y31003D01*
X284363Y30920D01*
X283863Y30670D01*
X283530Y30087D01*
X283363Y29587D01*
Y29087D01*
X283530Y28587D01*
X283947Y28087D01*
X284447Y27753D01*
X285030Y27670D01*
X285613Y27837D01*
X286197Y28337D01*
G01X295980Y27670D02*
Y32670D01*
G01X303080Y27670D02*
Y31003D01*
G01Y30420D02*
X302747Y30753D01*
X302247Y30920D01*
X301663Y31003D01*
X301080Y30837D01*
X300580Y30503D01*
X300247Y30003D01*
X300080Y29337D01*
X300247Y28670D01*
X300580Y28170D01*
X301080Y27837D01*
X301663Y27670D01*
X302247Y27753D01*
X302747Y28003D01*
X303080Y28337D01*
G01X306013Y27670D02*
Y31003D01*
G01Y30337D02*
X306430Y30670D01*
X306847Y30920D01*
X307430Y31003D01*
X307847Y30920D01*
X308347Y30670D01*
G01X311613Y26420D02*
X312197Y26087D01*
X312863Y26003D01*
X313447Y26087D01*
X313947Y26503D01*
X314280Y27087D01*
Y31003D01*
G01Y30337D02*
X313947Y30670D01*
X313447Y30920D01*
X312863Y31003D01*
X312197Y30837D01*
X311780Y30503D01*
X311447Y29920D01*
X311280Y29337D01*
X311363Y28837D01*
X311697Y28253D01*
X312197Y27837D01*
X312863Y27670D01*
X313363Y27753D01*
X313947Y28087D01*
X314280Y28420D01*
G01X317130Y29920D02*
X319797D01*
X319547Y30503D01*
X319130Y30837D01*
X318547Y31003D01*
X317963Y30920D01*
X317463Y30670D01*
X317130Y30087D01*
X316963Y29587D01*
Y29087D01*
X317130Y28587D01*
X317547Y28087D01*
X318047Y27753D01*
X318630Y27670D01*
X319213Y27837D01*
X319797Y28337D01*
G01X322730Y28253D02*
X323147Y27920D01*
X323730Y27670D01*
X324230D01*
X324730Y27837D01*
X325063Y28087D01*
X325230Y28420D01*
X325147Y28920D01*
X324813Y29170D01*
X323313Y29670D01*
X322980Y30253D01*
X323147Y30670D01*
X323480Y30920D01*
X323980Y31003D01*
X324480Y30920D01*
X324980Y30670D01*
G01X329580Y32670D02*
Y27670D01*
G01X328413Y31003D02*
X330747D01*
G01X342280Y32670D02*
Y27670D01*
G01Y28420D02*
X341947Y28003D01*
X341447Y27753D01*
X340863Y27670D01*
X340197Y27837D01*
X339697Y28253D01*
X339363Y28753D01*
X339280Y29337D01*
X339363Y29920D01*
X339697Y30420D01*
X340197Y30837D01*
X340863Y31003D01*
X341447Y30920D01*
X341863Y30753D01*
X342280Y30420D01*
G01X346380Y31003D02*
Y27670D01*
G01Y32337D02*
X346213Y32420D01*
Y32587D01*
X346380Y32670D01*
X346547Y32587D01*
Y32420D01*
X346380Y32337D01*
G01X349480Y27670D02*
Y31003D01*
G01Y30087D02*
X349730Y30503D01*
X350147Y30837D01*
X350730Y31003D01*
X351313Y30837D01*
X351730Y30503D01*
X351980Y30087D01*
Y27670D01*
G01Y30087D02*
X352230Y30503D01*
X352647Y30837D01*
X353230Y31003D01*
X353813Y30837D01*
X354230Y30503D01*
X354480Y30003D01*
Y27670D01*
G01X356330Y29920D02*
X358997D01*
X358747Y30503D01*
X358330Y30837D01*
X357747Y31003D01*
X357163Y30920D01*
X356663Y30670D01*
X356330Y30087D01*
X356163Y29587D01*
Y29087D01*
X356330Y28587D01*
X356747Y28087D01*
X357247Y27753D01*
X357830Y27670D01*
X358413Y27837D01*
X358997Y28337D01*
G01X361763Y27670D02*
Y31003D01*
G01Y30170D02*
X362097Y30587D01*
X362597Y30920D01*
X363263Y31003D01*
X363847Y30920D01*
X364347Y30587D01*
X364597Y30003D01*
Y27670D01*
G01X367530Y28253D02*
X367947Y27920D01*
X368530Y27670D01*
X369030D01*
X369530Y27837D01*
X369863Y28087D01*
X370030Y28420D01*
X369947Y28920D01*
X369613Y29170D01*
X368113Y29670D01*
X367780Y30253D01*
X367947Y30670D01*
X368280Y30920D01*
X368780Y31003D01*
X369280Y30920D01*
X369780Y30670D01*
G01X374380Y31003D02*
Y27670D01*
G01Y32337D02*
X374213Y32420D01*
Y32587D01*
X374380Y32670D01*
X374547Y32587D01*
Y32420D01*
X374380Y32337D01*
G01X379980Y27670D02*
X379480Y27753D01*
X378980Y28087D01*
X378647Y28670D01*
X378480Y29337D01*
X378647Y30003D01*
X378980Y30587D01*
X379480Y30920D01*
X379980Y31003D01*
X380480Y30920D01*
X380980Y30587D01*
X381313Y30003D01*
X381397Y29337D01*
X381313Y28670D01*
X380980Y28087D01*
X380480Y27753D01*
X379980Y27670D01*
G01X384163D02*
Y31003D01*
G01Y30170D02*
X384497Y30587D01*
X384997Y30920D01*
X385663Y31003D01*
X386247Y30920D01*
X386747Y30587D01*
X386997Y30003D01*
Y27670D01*
G01X396780D02*
X396280Y27753D01*
X395780Y28087D01*
X395447Y28670D01*
X395280Y29337D01*
X395447Y30003D01*
X395780Y30587D01*
X396280Y30920D01*
X396780Y31003D01*
X397280Y30920D01*
X397780Y30587D01*
X398113Y30003D01*
X398197Y29337D01*
X398113Y28670D01*
X397780Y28087D01*
X397280Y27753D01*
X396780Y27670D01*
G01X401880D02*
Y31920D01*
X402047Y32337D01*
X402380Y32587D01*
X402880Y32670D01*
X403380Y32503D01*
X403630Y32087D01*
G01X402630Y30670D02*
X400963D01*
G01X412080Y26003D02*
Y31003D01*
G01Y30253D02*
X412497Y30670D01*
X412913Y30920D01*
X413580Y31003D01*
X414163Y30920D01*
X414747Y30503D01*
X414997Y29920D01*
X415080Y29337D01*
X414997Y28753D01*
X414747Y28170D01*
X414247Y27837D01*
X413580Y27670D01*
X412997Y27753D01*
X412413Y28003D01*
X412080Y28337D01*
G01X420680Y27670D02*
Y31003D01*
G01Y30420D02*
X420347Y30753D01*
X419847Y30920D01*
X419263Y31003D01*
X418680Y30837D01*
X418180Y30503D01*
X417847Y30003D01*
X417680Y29337D01*
X417847Y28670D01*
X418180Y28170D01*
X418680Y27837D01*
X419263Y27670D01*
X419847Y27753D01*
X420347Y28003D01*
X420680Y28337D01*
G01X426280Y32670D02*
Y27670D01*
G01Y28420D02*
X425947Y28003D01*
X425447Y27753D01*
X424863Y27670D01*
X424197Y27837D01*
X423697Y28253D01*
X423363Y28753D01*
X423280Y29337D01*
X423363Y29920D01*
X423697Y30420D01*
X424197Y30837D01*
X424863Y31003D01*
X425447Y30920D01*
X425863Y30753D01*
X426280Y30420D01*
G01X435980Y27670D02*
X435480Y27753D01*
X434980Y28087D01*
X434647Y28670D01*
X434480Y29337D01*
X434647Y30003D01*
X434980Y30587D01*
X435480Y30920D01*
X435980Y31003D01*
X436480Y30920D01*
X436980Y30587D01*
X437313Y30003D01*
X437397Y29337D01*
X437313Y28670D01*
X436980Y28087D01*
X436480Y27753D01*
X435980Y27670D01*
G01X440413D02*
Y31003D01*
G01Y30337D02*
X440830Y30670D01*
X441247Y30920D01*
X441830Y31003D01*
X442247Y30920D01*
X442747Y30670D01*
G01X454280Y32670D02*
Y27670D01*
G01Y28420D02*
X453947Y28003D01*
X453447Y27753D01*
X452863Y27670D01*
X452197Y27837D01*
X451697Y28253D01*
X451363Y28753D01*
X451280Y29337D01*
X451363Y29920D01*
X451697Y30420D01*
X452197Y30837D01*
X452863Y31003D01*
X453447Y30920D01*
X453863Y30753D01*
X454280Y30420D01*
G01X458380Y31003D02*
Y27670D01*
G01Y32337D02*
X458213Y32420D01*
Y32587D01*
X458380Y32670D01*
X458547Y32587D01*
Y32420D01*
X458380Y32337D01*
G01X465480Y27670D02*
Y31003D01*
G01Y30420D02*
X465147Y30753D01*
X464647Y30920D01*
X464063Y31003D01*
X463480Y30837D01*
X462980Y30503D01*
X462647Y30003D01*
X462480Y29337D01*
X462647Y28670D01*
X462980Y28170D01*
X463480Y27837D01*
X464063Y27670D01*
X464647Y27753D01*
X465147Y28003D01*
X465480Y28337D01*
G01X467080Y27670D02*
Y31003D01*
G01Y30087D02*
X467330Y30503D01*
X467747Y30837D01*
X468330Y31003D01*
X468913Y30837D01*
X469330Y30503D01*
X469580Y30087D01*
Y27670D01*
G01Y30087D02*
X469830Y30503D01*
X470247Y30837D01*
X470830Y31003D01*
X471413Y30837D01*
X471830Y30503D01*
X472080Y30003D01*
Y27670D01*
G01X473930Y29920D02*
X476597D01*
X476347Y30503D01*
X475930Y30837D01*
X475347Y31003D01*
X474763Y30920D01*
X474263Y30670D01*
X473930Y30087D01*
X473763Y29587D01*
Y29087D01*
X473930Y28587D01*
X474347Y28087D01*
X474847Y27753D01*
X475430Y27670D01*
X476013Y27837D01*
X476597Y28337D01*
G01X480780Y32670D02*
Y27670D01*
G01X479613Y31003D02*
X481947D01*
G01X485130Y29920D02*
X487797D01*
X487547Y30503D01*
X487130Y30837D01*
X486547Y31003D01*
X485963Y30920D01*
X485463Y30670D01*
X485130Y30087D01*
X484963Y29587D01*
Y29087D01*
X485130Y28587D01*
X485547Y28087D01*
X486047Y27753D01*
X486630Y27670D01*
X487213Y27837D01*
X487797Y28337D01*
G01X490813Y27670D02*
Y31003D01*
G01Y30337D02*
X491230Y30670D01*
X491647Y30920D01*
X492230Y31003D01*
X492647Y30920D01*
X493147Y30670D01*
G01X504847Y27670D02*
X501513Y29337D01*
X504847Y31003D01*
G01X507697Y28587D02*
X509863D01*
G01Y30087D02*
X507697D01*
G01X519980Y27670D02*
Y32670D01*
X518980Y31670D01*
G01Y27670D02*
X520980D01*
G01X526580D02*
Y32670D01*
X523497Y29087D01*
X527663D01*
G01X534280Y27670D02*
Y31003D01*
G01Y30087D02*
X534530Y30503D01*
X534947Y30837D01*
X535530Y31003D01*
X536113Y30837D01*
X536530Y30503D01*
X536780Y30087D01*
Y27670D01*
G01Y30087D02*
X537030Y30503D01*
X537447Y30837D01*
X538030Y31003D01*
X538613Y30837D01*
X539030Y30503D01*
X539280Y30003D01*
Y27670D01*
G01X542380Y31003D02*
Y27670D01*
G01Y32337D02*
X542213Y32420D01*
Y32587D01*
X542380Y32670D01*
X542547Y32587D01*
Y32420D01*
X542380Y32337D01*
G01X547980Y27670D02*
Y32670D01*
G01X272500Y15000D02*
Y10000D01*
G01X270583Y15000D02*
X274417D01*
G01X276683Y10000D02*
Y15000D01*
G01Y12583D02*
X277100Y13000D01*
X277517Y13250D01*
X278183Y13333D01*
X278683Y13250D01*
X279267Y12917D01*
X279517Y12417D01*
Y10000D01*
G01X282450Y12250D02*
X285117D01*
X284867Y12833D01*
X284450Y13167D01*
X283867Y13333D01*
X283283Y13250D01*
X282783Y13000D01*
X282450Y12417D01*
X282283Y11917D01*
Y11417D01*
X282450Y10917D01*
X282867Y10417D01*
X283367Y10083D01*
X283950Y10000D01*
X284533Y10167D01*
X285117Y10667D01*
G01X294900Y10000D02*
Y15000D01*
G01X302000Y10000D02*
Y13333D01*
G01Y12750D02*
X301667Y13083D01*
X301167Y13250D01*
X300583Y13333D01*
X300000Y13167D01*
X299500Y12833D01*
X299167Y12333D01*
X299000Y11667D01*
X299167Y11000D01*
X299500Y10500D01*
X300000Y10167D01*
X300583Y10000D01*
X301167Y10083D01*
X301667Y10333D01*
X302000Y10667D01*
G01X304933Y10000D02*
Y13333D01*
G01Y12667D02*
X305350Y13000D01*
X305767Y13250D01*
X306350Y13333D01*
X306767Y13250D01*
X307267Y13000D01*
G01X310533Y8750D02*
X311117Y8417D01*
X311783Y8333D01*
X312367Y8417D01*
X312867Y8833D01*
X313200Y9417D01*
Y13333D01*
G01Y12667D02*
X312867Y13000D01*
X312367Y13250D01*
X311783Y13333D01*
X311117Y13167D01*
X310700Y12833D01*
X310367Y12250D01*
X310200Y11667D01*
X310283Y11167D01*
X310617Y10583D01*
X311117Y10167D01*
X311783Y10000D01*
X312283Y10083D01*
X312867Y10417D01*
X313200Y10750D01*
G01X316050Y12250D02*
X318717D01*
X318467Y12833D01*
X318050Y13167D01*
X317467Y13333D01*
X316883Y13250D01*
X316383Y13000D01*
X316050Y12417D01*
X315883Y11917D01*
Y11417D01*
X316050Y10917D01*
X316467Y10417D01*
X316967Y10083D01*
X317550Y10000D01*
X318133Y10167D01*
X318717Y10667D01*
G01X321650Y10583D02*
X322067Y10250D01*
X322650Y10000D01*
X323150D01*
X323650Y10167D01*
X323983Y10417D01*
X324150Y10750D01*
X324067Y11250D01*
X323733Y11500D01*
X322233Y12000D01*
X321900Y12583D01*
X322067Y13000D01*
X322400Y13250D01*
X322900Y13333D01*
X323400Y13250D01*
X323900Y13000D01*
G01X328500Y15000D02*
Y10000D01*
G01X327333Y13333D02*
X329667D01*
G01X341200Y15000D02*
Y10000D01*
G01Y10750D02*
X340867Y10333D01*
X340367Y10083D01*
X339783Y10000D01*
X339117Y10167D01*
X338617Y10583D01*
X338283Y11083D01*
X338200Y11667D01*
X338283Y12250D01*
X338617Y12750D01*
X339117Y13167D01*
X339783Y13333D01*
X340367Y13250D01*
X340783Y13083D01*
X341200Y12750D01*
G01X345300Y13333D02*
Y10000D01*
G01Y14667D02*
X345133Y14750D01*
Y14917D01*
X345300Y15000D01*
X345467Y14917D01*
Y14750D01*
X345300Y14667D01*
G01X348400Y10000D02*
Y13333D01*
G01Y12417D02*
X348650Y12833D01*
X349067Y13167D01*
X349650Y13333D01*
X350233Y13167D01*
X350650Y12833D01*
X350900Y12417D01*
Y10000D01*
G01Y12417D02*
X351150Y12833D01*
X351567Y13167D01*
X352150Y13333D01*
X352733Y13167D01*
X353150Y12833D01*
X353400Y12333D01*
Y10000D01*
G01X355250Y12250D02*
X357917D01*
X357667Y12833D01*
X357250Y13167D01*
X356667Y13333D01*
X356083Y13250D01*
X355583Y13000D01*
X355250Y12417D01*
X355083Y11917D01*
Y11417D01*
X355250Y10917D01*
X355667Y10417D01*
X356167Y10083D01*
X356750Y10000D01*
X357333Y10167D01*
X357917Y10667D01*
G01X360683Y10000D02*
Y13333D01*
G01Y12500D02*
X361017Y12917D01*
X361517Y13250D01*
X362183Y13333D01*
X362767Y13250D01*
X363267Y12917D01*
X363517Y12333D01*
Y10000D01*
G01X366450Y10583D02*
X366867Y10250D01*
X367450Y10000D01*
X367950D01*
X368450Y10167D01*
X368783Y10417D01*
X368950Y10750D01*
X368867Y11250D01*
X368533Y11500D01*
X367033Y12000D01*
X366700Y12583D01*
X366867Y13000D01*
X367200Y13250D01*
X367700Y13333D01*
X368200Y13250D01*
X368700Y13000D01*
G01X373300Y13333D02*
Y10000D01*
G01Y14667D02*
X373133Y14750D01*
Y14917D01*
X373300Y15000D01*
X373467Y14917D01*
Y14750D01*
X373300Y14667D01*
G01X378900Y10000D02*
X378400Y10083D01*
X377900Y10417D01*
X377567Y11000D01*
X377400Y11667D01*
X377567Y12333D01*
X377900Y12917D01*
X378400Y13250D01*
X378900Y13333D01*
X379400Y13250D01*
X379900Y12917D01*
X380233Y12333D01*
X380317Y11667D01*
X380233Y11000D01*
X379900Y10417D01*
X379400Y10083D01*
X378900Y10000D01*
G01X383083D02*
Y13333D01*
G01Y12500D02*
X383417Y12917D01*
X383917Y13250D01*
X384583Y13333D01*
X385167Y13250D01*
X385667Y12917D01*
X385917Y12333D01*
Y10000D01*
G01X395700D02*
X395200Y10083D01*
X394700Y10417D01*
X394367Y11000D01*
X394200Y11667D01*
X394367Y12333D01*
X394700Y12917D01*
X395200Y13250D01*
X395700Y13333D01*
X396200Y13250D01*
X396700Y12917D01*
X397033Y12333D01*
X397117Y11667D01*
X397033Y11000D01*
X396700Y10417D01*
X396200Y10083D01*
X395700Y10000D01*
G01X400800D02*
Y14250D01*
X400967Y14667D01*
X401300Y14917D01*
X401800Y15000D01*
X402300Y14833D01*
X402550Y14417D01*
G01X401550Y13000D02*
X399883D01*
G01X411000Y8333D02*
Y13333D01*
G01Y12583D02*
X411417Y13000D01*
X411833Y13250D01*
X412500Y13333D01*
X413083Y13250D01*
X413667Y12833D01*
X413917Y12250D01*
X414000Y11667D01*
X413917Y11083D01*
X413667Y10500D01*
X413167Y10167D01*
X412500Y10000D01*
X411917Y10083D01*
X411333Y10333D01*
X411000Y10667D01*
G01X419600Y10000D02*
Y13333D01*
G01Y12750D02*
X419267Y13083D01*
X418767Y13250D01*
X418183Y13333D01*
X417600Y13167D01*
X417100Y12833D01*
X416767Y12333D01*
X416600Y11667D01*
X416767Y11000D01*
X417100Y10500D01*
X417600Y10167D01*
X418183Y10000D01*
X418767Y10083D01*
X419267Y10333D01*
X419600Y10667D01*
G01X425200Y15000D02*
Y10000D01*
G01Y10750D02*
X424867Y10333D01*
X424367Y10083D01*
X423783Y10000D01*
X423117Y10167D01*
X422617Y10583D01*
X422283Y11083D01*
X422200Y11667D01*
X422283Y12250D01*
X422617Y12750D01*
X423117Y13167D01*
X423783Y13333D01*
X424367Y13250D01*
X424783Y13083D01*
X425200Y12750D01*
G01X434900Y10000D02*
X434400Y10083D01*
X433900Y10417D01*
X433567Y11000D01*
X433400Y11667D01*
X433567Y12333D01*
X433900Y12917D01*
X434400Y13250D01*
X434900Y13333D01*
X435400Y13250D01*
X435900Y12917D01*
X436233Y12333D01*
X436317Y11667D01*
X436233Y11000D01*
X435900Y10417D01*
X435400Y10083D01*
X434900Y10000D01*
G01X439333D02*
Y13333D01*
G01Y12667D02*
X439750Y13000D01*
X440167Y13250D01*
X440750Y13333D01*
X441167Y13250D01*
X441667Y13000D01*
G01X453200Y15000D02*
Y10000D01*
G01Y10750D02*
X452867Y10333D01*
X452367Y10083D01*
X451783Y10000D01*
X451117Y10167D01*
X450617Y10583D01*
X450283Y11083D01*
X450200Y11667D01*
X450283Y12250D01*
X450617Y12750D01*
X451117Y13167D01*
X451783Y13333D01*
X452367Y13250D01*
X452783Y13083D01*
X453200Y12750D01*
G01X457300Y13333D02*
Y10000D01*
G01Y14667D02*
X457133Y14750D01*
Y14917D01*
X457300Y15000D01*
X457467Y14917D01*
Y14750D01*
X457300Y14667D01*
G01X464400Y10000D02*
Y13333D01*
G01Y12750D02*
X464067Y13083D01*
X463567Y13250D01*
X462983Y13333D01*
X462400Y13167D01*
X461900Y12833D01*
X461567Y12333D01*
X461400Y11667D01*
X461567Y11000D01*
X461900Y10500D01*
X462400Y10167D01*
X462983Y10000D01*
X463567Y10083D01*
X464067Y10333D01*
X464400Y10667D01*
G01X466000Y10000D02*
Y13333D01*
G01Y12417D02*
X466250Y12833D01*
X466667Y13167D01*
X467250Y13333D01*
X467833Y13167D01*
X468250Y12833D01*
X468500Y12417D01*
Y10000D01*
G01Y12417D02*
X468750Y12833D01*
X469167Y13167D01*
X469750Y13333D01*
X470333Y13167D01*
X470750Y12833D01*
X471000Y12333D01*
Y10000D01*
G01X472850Y12250D02*
X475517D01*
X475267Y12833D01*
X474850Y13167D01*
X474267Y13333D01*
X473683Y13250D01*
X473183Y13000D01*
X472850Y12417D01*
X472683Y11917D01*
Y11417D01*
X472850Y10917D01*
X473267Y10417D01*
X473767Y10083D01*
X474350Y10000D01*
X474933Y10167D01*
X475517Y10667D01*
G01X479700Y15000D02*
Y10000D01*
G01X478533Y13333D02*
X480867D01*
G01X484050Y12250D02*
X486717D01*
X486467Y12833D01*
X486050Y13167D01*
X485467Y13333D01*
X484883Y13250D01*
X484383Y13000D01*
X484050Y12417D01*
X483883Y11917D01*
Y11417D01*
X484050Y10917D01*
X484467Y10417D01*
X484967Y10083D01*
X485550Y10000D01*
X486133Y10167D01*
X486717Y10667D01*
G01X489733Y10000D02*
Y13333D01*
G01Y12667D02*
X490150Y13000D01*
X490567Y13250D01*
X491150Y13333D01*
X491567Y13250D01*
X492067Y13000D01*
G01X500433Y10000D02*
X503767Y11667D01*
X500433Y13333D01*
G01X507700Y10000D02*
Y15000D01*
X506700Y14000D01*
G01Y10000D02*
X508700D01*
G01X514300D02*
Y15000D01*
X511217Y11417D01*
X515383D01*
G01X522000Y10000D02*
Y13333D01*
G01Y12417D02*
X522250Y12833D01*
X522667Y13167D01*
X523250Y13333D01*
X523833Y13167D01*
X524250Y12833D01*
X524500Y12417D01*
Y10000D01*
G01Y12417D02*
X524750Y12833D01*
X525167Y13167D01*
X525750Y13333D01*
X526333Y13167D01*
X526750Y12833D01*
X527000Y12333D01*
Y10000D01*
G01X530100Y13333D02*
Y10000D01*
G01Y14667D02*
X529933Y14750D01*
Y14917D01*
X530100Y15000D01*
X530267Y14917D01*
Y14750D01*
X530100Y14667D01*
G01X535700Y10000D02*
Y15000D01*
G01X272500Y71500D02*
Y66500D01*
G01X271333Y69833D02*
X273667D01*
G01X276933Y66500D02*
Y69833D01*
G01Y69167D02*
X277350Y69500D01*
X277767Y69750D01*
X278350Y69833D01*
X278767Y69750D01*
X279267Y69500D01*
G01X285200Y66500D02*
Y69833D01*
G01Y69250D02*
X284867Y69583D01*
X284367Y69750D01*
X283783Y69833D01*
X283200Y69667D01*
X282700Y69333D01*
X282367Y68833D01*
X282200Y68167D01*
X282367Y67500D01*
X282700Y67000D01*
X283200Y66667D01*
X283783Y66500D01*
X284367Y66583D01*
X284867Y66833D01*
X285200Y67167D01*
G01X290633Y69417D02*
X290050Y69750D01*
X289550Y69833D01*
X288883Y69667D01*
X288383Y69333D01*
X288050Y68750D01*
X287967Y68167D01*
X288050Y67583D01*
X288383Y67083D01*
X288883Y66667D01*
X289550Y66500D01*
X290133Y66667D01*
X290633Y67000D01*
G01X293650Y68750D02*
X296317D01*
X296067Y69333D01*
X295650Y69667D01*
X295067Y69833D01*
X294483Y69750D01*
X293983Y69500D01*
X293650Y68917D01*
X293483Y68417D01*
Y67917D01*
X293650Y67417D01*
X294067Y66917D01*
X294567Y66583D01*
X295150Y66500D01*
X295733Y66667D01*
X296317Y67167D01*
G01X304017Y69833D02*
X305017Y66500D01*
X306100Y69833D01*
X307183Y66500D01*
X308183Y69833D01*
G01X311700D02*
Y66500D01*
G01Y71167D02*
X311533Y71250D01*
Y71417D01*
X311700Y71500D01*
X311867Y71417D01*
Y71250D01*
X311700Y71167D01*
G01X318800Y71500D02*
Y66500D01*
G01Y67250D02*
X318467Y66833D01*
X317967Y66583D01*
X317383Y66500D01*
X316717Y66667D01*
X316217Y67083D01*
X315883Y67583D01*
X315800Y68167D01*
X315883Y68750D01*
X316217Y69250D01*
X316717Y69667D01*
X317383Y69833D01*
X317967Y69750D01*
X318383Y69583D01*
X318800Y69250D01*
G01X322900Y71500D02*
Y66500D01*
G01X321733Y69833D02*
X324067D01*
G01X327083Y66500D02*
Y71500D01*
G01Y69083D02*
X327500Y69500D01*
X327917Y69750D01*
X328583Y69833D01*
X329083Y69750D01*
X329667Y69417D01*
X329917Y68917D01*
Y66500D01*
G01X338033D02*
X341367Y68167D01*
X338033Y69833D01*
G01X350733Y66500D02*
X350900Y67583D01*
X351150Y68500D01*
X351483Y69333D01*
X351900Y70250D01*
X352567Y71500D01*
X349233D01*
G01X359600Y66500D02*
Y69833D01*
G01Y68917D02*
X359850Y69333D01*
X360267Y69667D01*
X360850Y69833D01*
X361433Y69667D01*
X361850Y69333D01*
X362100Y68917D01*
Y66500D01*
G01Y68917D02*
X362350Y69333D01*
X362767Y69667D01*
X363350Y69833D01*
X363933Y69667D01*
X364350Y69333D01*
X364600Y68833D01*
Y66500D01*
G01X367700Y69833D02*
Y66500D01*
G01Y71167D02*
X367533Y71250D01*
Y71417D01*
X367700Y71500D01*
X367867Y71417D01*
Y71250D01*
X367700Y71167D01*
G01X373300Y66500D02*
Y71500D01*
G01X272500Y52000D02*
Y47000D01*
G01X270583Y52000D02*
X274417D01*
G01X276683Y47000D02*
Y52000D01*
G01Y49583D02*
X277100Y50000D01*
X277517Y50250D01*
X278183Y50333D01*
X278683Y50250D01*
X279267Y49917D01*
X279517Y49417D01*
Y47000D01*
G01X282450Y49250D02*
X285117D01*
X284867Y49833D01*
X284450Y50167D01*
X283867Y50333D01*
X283283Y50250D01*
X282783Y50000D01*
X282450Y49417D01*
X282283Y48917D01*
Y48417D01*
X282450Y47917D01*
X282867Y47417D01*
X283367Y47083D01*
X283950Y47000D01*
X284533Y47167D01*
X285117Y47667D01*
G01X294900Y47000D02*
Y52000D01*
G01X302000Y47000D02*
Y50333D01*
G01Y49750D02*
X301667Y50083D01*
X301167Y50250D01*
X300583Y50333D01*
X300000Y50167D01*
X299500Y49833D01*
X299167Y49333D01*
X299000Y48667D01*
X299167Y48000D01*
X299500Y47500D01*
X300000Y47167D01*
X300583Y47000D01*
X301167Y47083D01*
X301667Y47333D01*
X302000Y47667D01*
G01X304933Y47000D02*
Y50333D01*
G01Y49667D02*
X305350Y50000D01*
X305767Y50250D01*
X306350Y50333D01*
X306767Y50250D01*
X307267Y50000D01*
G01X310533Y45750D02*
X311117Y45417D01*
X311783Y45333D01*
X312367Y45417D01*
X312867Y45833D01*
X313200Y46417D01*
Y50333D01*
G01Y49667D02*
X312867Y50000D01*
X312367Y50250D01*
X311783Y50333D01*
X311117Y50167D01*
X310700Y49833D01*
X310367Y49250D01*
X310200Y48667D01*
X310283Y48167D01*
X310617Y47583D01*
X311117Y47167D01*
X311783Y47000D01*
X312283Y47083D01*
X312867Y47417D01*
X313200Y47750D01*
G01X316050Y49250D02*
X318717D01*
X318467Y49833D01*
X318050Y50167D01*
X317467Y50333D01*
X316883Y50250D01*
X316383Y50000D01*
X316050Y49417D01*
X315883Y48917D01*
Y48417D01*
X316050Y47917D01*
X316467Y47417D01*
X316967Y47083D01*
X317550Y47000D01*
X318133Y47167D01*
X318717Y47667D01*
G01X321650Y47583D02*
X322067Y47250D01*
X322650Y47000D01*
X323150D01*
X323650Y47167D01*
X323983Y47417D01*
X324150Y47750D01*
X324067Y48250D01*
X323733Y48500D01*
X322233Y49000D01*
X321900Y49583D01*
X322067Y50000D01*
X322400Y50250D01*
X322900Y50333D01*
X323400Y50250D01*
X323900Y50000D01*
G01X328500Y52000D02*
Y47000D01*
G01X327333Y50333D02*
X329667D01*
G01X341200Y52000D02*
Y47000D01*
G01Y47750D02*
X340867Y47333D01*
X340367Y47083D01*
X339783Y47000D01*
X339117Y47167D01*
X338617Y47583D01*
X338283Y48083D01*
X338200Y48667D01*
X338283Y49250D01*
X338617Y49750D01*
X339117Y50167D01*
X339783Y50333D01*
X340367Y50250D01*
X340783Y50083D01*
X341200Y49750D01*
G01X345300Y50333D02*
Y47000D01*
G01Y51667D02*
X345133Y51750D01*
Y51917D01*
X345300Y52000D01*
X345467Y51917D01*
Y51750D01*
X345300Y51667D01*
G01X348400Y47000D02*
Y50333D01*
G01Y49417D02*
X348650Y49833D01*
X349067Y50167D01*
X349650Y50333D01*
X350233Y50167D01*
X350650Y49833D01*
X350900Y49417D01*
Y47000D01*
G01Y49417D02*
X351150Y49833D01*
X351567Y50167D01*
X352150Y50333D01*
X352733Y50167D01*
X353150Y49833D01*
X353400Y49333D01*
Y47000D01*
G01X355250Y49250D02*
X357917D01*
X357667Y49833D01*
X357250Y50167D01*
X356667Y50333D01*
X356083Y50250D01*
X355583Y50000D01*
X355250Y49417D01*
X355083Y48917D01*
Y48417D01*
X355250Y47917D01*
X355667Y47417D01*
X356167Y47083D01*
X356750Y47000D01*
X357333Y47167D01*
X357917Y47667D01*
G01X360683Y47000D02*
Y50333D01*
G01Y49500D02*
X361017Y49917D01*
X361517Y50250D01*
X362183Y50333D01*
X362767Y50250D01*
X363267Y49917D01*
X363517Y49333D01*
Y47000D01*
G01X366450Y47583D02*
X366867Y47250D01*
X367450Y47000D01*
X367950D01*
X368450Y47167D01*
X368783Y47417D01*
X368950Y47750D01*
X368867Y48250D01*
X368533Y48500D01*
X367033Y49000D01*
X366700Y49583D01*
X366867Y50000D01*
X367200Y50250D01*
X367700Y50333D01*
X368200Y50250D01*
X368700Y50000D01*
G01X373300Y50333D02*
Y47000D01*
G01Y51667D02*
X373133Y51750D01*
Y51917D01*
X373300Y52000D01*
X373467Y51917D01*
Y51750D01*
X373300Y51667D01*
G01X378900Y47000D02*
X378400Y47083D01*
X377900Y47417D01*
X377567Y48000D01*
X377400Y48667D01*
X377567Y49333D01*
X377900Y49917D01*
X378400Y50250D01*
X378900Y50333D01*
X379400Y50250D01*
X379900Y49917D01*
X380233Y49333D01*
X380317Y48667D01*
X380233Y48000D01*
X379900Y47417D01*
X379400Y47083D01*
X378900Y47000D01*
G01X383083D02*
Y50333D01*
G01Y49500D02*
X383417Y49917D01*
X383917Y50250D01*
X384583Y50333D01*
X385167Y50250D01*
X385667Y49917D01*
X385917Y49333D01*
Y47000D01*
G01X395700D02*
X395200Y47083D01*
X394700Y47417D01*
X394367Y48000D01*
X394200Y48667D01*
X394367Y49333D01*
X394700Y49917D01*
X395200Y50250D01*
X395700Y50333D01*
X396200Y50250D01*
X396700Y49917D01*
X397033Y49333D01*
X397117Y48667D01*
X397033Y48000D01*
X396700Y47417D01*
X396200Y47083D01*
X395700Y47000D01*
G01X400800D02*
Y51250D01*
X400967Y51667D01*
X401300Y51917D01*
X401800Y52000D01*
X402300Y51833D01*
X402550Y51417D01*
G01X401550Y50000D02*
X399883D01*
G01X411000Y45333D02*
Y50333D01*
G01Y49583D02*
X411417Y50000D01*
X411833Y50250D01*
X412500Y50333D01*
X413083Y50250D01*
X413667Y49833D01*
X413917Y49250D01*
X414000Y48667D01*
X413917Y48083D01*
X413667Y47500D01*
X413167Y47167D01*
X412500Y47000D01*
X411917Y47083D01*
X411333Y47333D01*
X411000Y47667D01*
G01X419600Y47000D02*
Y50333D01*
G01Y49750D02*
X419267Y50083D01*
X418767Y50250D01*
X418183Y50333D01*
X417600Y50167D01*
X417100Y49833D01*
X416767Y49333D01*
X416600Y48667D01*
X416767Y48000D01*
X417100Y47500D01*
X417600Y47167D01*
X418183Y47000D01*
X418767Y47083D01*
X419267Y47333D01*
X419600Y47667D01*
G01X425200Y52000D02*
Y47000D01*
G01Y47750D02*
X424867Y47333D01*
X424367Y47083D01*
X423783Y47000D01*
X423117Y47167D01*
X422617Y47583D01*
X422283Y48083D01*
X422200Y48667D01*
X422283Y49250D01*
X422617Y49750D01*
X423117Y50167D01*
X423783Y50333D01*
X424367Y50250D01*
X424783Y50083D01*
X425200Y49750D01*
G01X434900Y47000D02*
X434400Y47083D01*
X433900Y47417D01*
X433567Y48000D01*
X433400Y48667D01*
X433567Y49333D01*
X433900Y49917D01*
X434400Y50250D01*
X434900Y50333D01*
X435400Y50250D01*
X435900Y49917D01*
X436233Y49333D01*
X436317Y48667D01*
X436233Y48000D01*
X435900Y47417D01*
X435400Y47083D01*
X434900Y47000D01*
G01X439333D02*
Y50333D01*
G01Y49667D02*
X439750Y50000D01*
X440167Y50250D01*
X440750Y50333D01*
X441167Y50250D01*
X441667Y50000D01*
G01X453200Y52000D02*
Y47000D01*
G01Y47750D02*
X452867Y47333D01*
X452367Y47083D01*
X451783Y47000D01*
X451117Y47167D01*
X450617Y47583D01*
X450283Y48083D01*
X450200Y48667D01*
X450283Y49250D01*
X450617Y49750D01*
X451117Y50167D01*
X451783Y50333D01*
X452367Y50250D01*
X452783Y50083D01*
X453200Y49750D01*
G01X457300Y50333D02*
Y47000D01*
G01Y51667D02*
X457133Y51750D01*
Y51917D01*
X457300Y52000D01*
X457467Y51917D01*
Y51750D01*
X457300Y51667D01*
G01X464400Y47000D02*
Y50333D01*
G01Y49750D02*
X464067Y50083D01*
X463567Y50250D01*
X462983Y50333D01*
X462400Y50167D01*
X461900Y49833D01*
X461567Y49333D01*
X461400Y48667D01*
X461567Y48000D01*
X461900Y47500D01*
X462400Y47167D01*
X462983Y47000D01*
X463567Y47083D01*
X464067Y47333D01*
X464400Y47667D01*
G01X466000Y47000D02*
Y50333D01*
G01Y49417D02*
X466250Y49833D01*
X466667Y50167D01*
X467250Y50333D01*
X467833Y50167D01*
X468250Y49833D01*
X468500Y49417D01*
Y47000D01*
G01Y49417D02*
X468750Y49833D01*
X469167Y50167D01*
X469750Y50333D01*
X470333Y50167D01*
X470750Y49833D01*
X471000Y49333D01*
Y47000D01*
G01X472850Y49250D02*
X475517D01*
X475267Y49833D01*
X474850Y50167D01*
X474267Y50333D01*
X473683Y50250D01*
X473183Y50000D01*
X472850Y49417D01*
X472683Y48917D01*
Y48417D01*
X472850Y47917D01*
X473267Y47417D01*
X473767Y47083D01*
X474350Y47000D01*
X474933Y47167D01*
X475517Y47667D01*
G01X479700Y52000D02*
Y47000D01*
G01X478533Y50333D02*
X480867D01*
G01X484050Y49250D02*
X486717D01*
X486467Y49833D01*
X486050Y50167D01*
X485467Y50333D01*
X484883Y50250D01*
X484383Y50000D01*
X484050Y49417D01*
X483883Y48917D01*
Y48417D01*
X484050Y47917D01*
X484467Y47417D01*
X484967Y47083D01*
X485550Y47000D01*
X486133Y47167D01*
X486717Y47667D01*
G01X489733Y47000D02*
Y50333D01*
G01Y49667D02*
X490150Y50000D01*
X490567Y50250D01*
X491150Y50333D01*
X491567Y50250D01*
X492067Y50000D01*
G01X500433Y47000D02*
X503767Y48667D01*
X500433Y50333D01*
G01X513300Y47000D02*
Y52000D01*
X512300Y51000D01*
G01Y47000D02*
X514300D01*
G01X519900D02*
Y52000D01*
X516817Y48417D01*
X520983D01*
G01X527600Y47000D02*
Y50333D01*
G01Y49417D02*
X527850Y49833D01*
X528267Y50167D01*
X528850Y50333D01*
X529433Y50167D01*
X529850Y49833D01*
X530100Y49417D01*
Y47000D01*
G01Y49417D02*
X530350Y49833D01*
X530767Y50167D01*
X531350Y50333D01*
X531933Y50167D01*
X532350Y49833D01*
X532600Y49333D01*
Y47000D01*
G01X535700Y50333D02*
Y47000D01*
G01Y51667D02*
X535533Y51750D01*
Y51917D01*
X535700Y52000D01*
X535867Y51917D01*
Y51750D01*
X535700Y51667D01*
G01X541300Y47000D02*
Y52000D01*
G01X272500Y101500D02*
Y96500D01*
G01X271333Y99833D02*
X273667D01*
G01X276933Y96500D02*
Y99833D01*
G01Y99167D02*
X277350Y99500D01*
X277767Y99750D01*
X278350Y99833D01*
X278767Y99750D01*
X279267Y99500D01*
G01X285200Y96500D02*
Y99833D01*
G01Y99250D02*
X284867Y99583D01*
X284367Y99750D01*
X283783Y99833D01*
X283200Y99667D01*
X282700Y99333D01*
X282367Y98833D01*
X282200Y98167D01*
X282367Y97500D01*
X282700Y97000D01*
X283200Y96667D01*
X283783Y96500D01*
X284367Y96583D01*
X284867Y96833D01*
X285200Y97167D01*
G01X290633Y99417D02*
X290050Y99750D01*
X289550Y99833D01*
X288883Y99667D01*
X288383Y99333D01*
X288050Y98750D01*
X287967Y98167D01*
X288050Y97583D01*
X288383Y97083D01*
X288883Y96667D01*
X289550Y96500D01*
X290133Y96667D01*
X290633Y97000D01*
G01X293650Y98750D02*
X296317D01*
X296067Y99333D01*
X295650Y99667D01*
X295067Y99833D01*
X294483Y99750D01*
X293983Y99500D01*
X293650Y98917D01*
X293483Y98417D01*
Y97917D01*
X293650Y97417D01*
X294067Y96917D01*
X294567Y96583D01*
X295150Y96500D01*
X295733Y96667D01*
X296317Y97167D01*
G01X304017Y99833D02*
X305017Y96500D01*
X306100Y99833D01*
X307183Y96500D01*
X308183Y99833D01*
G01X311700D02*
Y96500D01*
G01Y101167D02*
X311533Y101250D01*
Y101417D01*
X311700Y101500D01*
X311867Y101417D01*
Y101250D01*
X311700Y101167D01*
G01X318800Y101500D02*
Y96500D01*
G01Y97250D02*
X318467Y96833D01*
X317967Y96583D01*
X317383Y96500D01*
X316717Y96667D01*
X316217Y97083D01*
X315883Y97583D01*
X315800Y98167D01*
X315883Y98750D01*
X316217Y99250D01*
X316717Y99667D01*
X317383Y99833D01*
X317967Y99750D01*
X318383Y99583D01*
X318800Y99250D01*
G01X322900Y101500D02*
Y96500D01*
G01X321733Y99833D02*
X324067D01*
G01X327083Y96500D02*
Y101500D01*
G01Y99083D02*
X327500Y99500D01*
X327917Y99750D01*
X328583Y99833D01*
X329083Y99750D01*
X329667Y99417D01*
X329917Y98917D01*
Y96500D01*
G01X341367D02*
X338033Y98167D01*
X341367Y99833D01*
G01X344217Y97417D02*
X346383D01*
G01Y98917D02*
X344217D01*
G01X354667Y97250D02*
X355167Y96833D01*
X355750Y96583D01*
X356500Y96500D01*
X357250Y96667D01*
X357833Y97000D01*
X358250Y97583D01*
X358333Y98250D01*
X358167Y98917D01*
X357750Y99333D01*
X357167Y99667D01*
X356583Y99750D01*
X356000Y99667D01*
X355250Y99333D01*
X355500Y101500D01*
X357750D01*
G01X365200Y96500D02*
Y99833D01*
G01Y98917D02*
X365450Y99333D01*
X365867Y99667D01*
X366450Y99833D01*
X367033Y99667D01*
X367450Y99333D01*
X367700Y98917D01*
Y96500D01*
G01Y98917D02*
X367950Y99333D01*
X368367Y99667D01*
X368950Y99833D01*
X369533Y99667D01*
X369950Y99333D01*
X370200Y98833D01*
Y96500D01*
G01X373300Y99833D02*
Y96500D01*
G01Y101167D02*
X373133Y101250D01*
Y101417D01*
X373300Y101500D01*
X373467Y101417D01*
Y101250D01*
X373300Y101167D01*
G01X378900Y96500D02*
Y101500D01*
G01X270667Y82250D02*
X271167Y81833D01*
X271750Y81583D01*
X272500Y81500D01*
X273250Y81667D01*
X273833Y82000D01*
X274250Y82583D01*
X274333Y83250D01*
X274167Y83917D01*
X273750Y84333D01*
X273167Y84667D01*
X272583Y84750D01*
X272000Y84667D01*
X271250Y84333D01*
X271500Y86500D01*
X273750D01*
G01X281200Y81500D02*
Y84833D01*
G01Y83917D02*
X281450Y84333D01*
X281867Y84667D01*
X282450Y84833D01*
X283033Y84667D01*
X283450Y84333D01*
X283700Y83917D01*
Y81500D01*
G01Y83917D02*
X283950Y84333D01*
X284367Y84667D01*
X284950Y84833D01*
X285533Y84667D01*
X285950Y84333D01*
X286200Y83833D01*
Y81500D01*
G01X289300Y84833D02*
Y81500D01*
G01Y86167D02*
X289133Y86250D01*
Y86417D01*
X289300Y86500D01*
X289467Y86417D01*
Y86250D01*
X289300Y86167D01*
G01X294900Y81500D02*
Y86500D01*
G01X307767Y81500D02*
X304433Y83167D01*
X307767Y84833D01*
G01X317300Y86500D02*
Y81500D01*
G01X316133Y84833D02*
X318467D01*
G01X321733Y81500D02*
Y84833D01*
G01Y84167D02*
X322150Y84500D01*
X322567Y84750D01*
X323150Y84833D01*
X323567Y84750D01*
X324067Y84500D01*
G01X330000Y81500D02*
Y84833D01*
G01Y84250D02*
X329667Y84583D01*
X329167Y84750D01*
X328583Y84833D01*
X328000Y84667D01*
X327500Y84333D01*
X327167Y83833D01*
X327000Y83167D01*
X327167Y82500D01*
X327500Y82000D01*
X328000Y81667D01*
X328583Y81500D01*
X329167Y81583D01*
X329667Y81833D01*
X330000Y82167D01*
G01X335433Y84417D02*
X334850Y84750D01*
X334350Y84833D01*
X333683Y84667D01*
X333183Y84333D01*
X332850Y83750D01*
X332767Y83167D01*
X332850Y82583D01*
X333183Y82083D01*
X333683Y81667D01*
X334350Y81500D01*
X334933Y81667D01*
X335433Y82000D01*
G01X338450Y83750D02*
X341117D01*
X340867Y84333D01*
X340450Y84667D01*
X339867Y84833D01*
X339283Y84750D01*
X338783Y84500D01*
X338450Y83917D01*
X338283Y83417D01*
Y82917D01*
X338450Y82417D01*
X338867Y81917D01*
X339367Y81583D01*
X339950Y81500D01*
X340533Y81667D01*
X341117Y82167D01*
G01X348817Y84833D02*
X349817Y81500D01*
X350900Y84833D01*
X351983Y81500D01*
X352983Y84833D01*
G01X356500D02*
Y81500D01*
G01Y86167D02*
X356333Y86250D01*
Y86417D01*
X356500Y86500D01*
X356667Y86417D01*
Y86250D01*
X356500Y86167D01*
G01X363600Y86500D02*
Y81500D01*
G01Y82250D02*
X363267Y81833D01*
X362767Y81583D01*
X362183Y81500D01*
X361517Y81667D01*
X361017Y82083D01*
X360683Y82583D01*
X360600Y83167D01*
X360683Y83750D01*
X361017Y84250D01*
X361517Y84667D01*
X362183Y84833D01*
X362767Y84750D01*
X363183Y84583D01*
X363600Y84250D01*
G01X367700Y86500D02*
Y81500D01*
G01X366533Y84833D02*
X368867D01*
G01X371883Y81500D02*
Y86500D01*
G01Y84083D02*
X372300Y84500D01*
X372717Y84750D01*
X373383Y84833D01*
X373883Y84750D01*
X374467Y84417D01*
X374717Y83917D01*
Y81500D01*
G01X386167D02*
X382833Y83167D01*
X386167Y84833D01*
G01X389017Y82417D02*
X391183D01*
G01Y83917D02*
X389017D01*
G01X401133Y81500D02*
X401300Y82583D01*
X401550Y83500D01*
X401883Y84333D01*
X402300Y85250D01*
X402967Y86500D01*
X399633D01*
G01X410000Y81500D02*
Y84833D01*
G01Y83917D02*
X410250Y84333D01*
X410667Y84667D01*
X411250Y84833D01*
X411833Y84667D01*
X412250Y84333D01*
X412500Y83917D01*
Y81500D01*
G01Y83917D02*
X412750Y84333D01*
X413167Y84667D01*
X413750Y84833D01*
X414333Y84667D01*
X414750Y84333D01*
X415000Y83833D01*
Y81500D01*
G01X418100Y84833D02*
Y81500D01*
G01Y86167D02*
X417933Y86250D01*
Y86417D01*
X418100Y86500D01*
X418267Y86417D01*
Y86250D01*
X418100Y86167D01*
G01X423700Y81500D02*
Y86500D01*
G01X271250Y141583D02*
X271667Y141250D01*
X272250Y141000D01*
X272750D01*
X273250Y141167D01*
X273583Y141417D01*
X273750Y141750D01*
X273667Y142250D01*
X273333Y142500D01*
X271833Y143000D01*
X271500Y143583D01*
X271667Y144000D01*
X272000Y144250D01*
X272500Y144333D01*
X273000Y144250D01*
X273500Y144000D01*
G01X276600Y139333D02*
Y144333D01*
G01Y143583D02*
X277017Y144000D01*
X277433Y144250D01*
X278100Y144333D01*
X278683Y144250D01*
X279267Y143833D01*
X279517Y143250D01*
X279600Y142667D01*
X279517Y142083D01*
X279267Y141500D01*
X278767Y141167D01*
X278100Y141000D01*
X277517Y141083D01*
X276933Y141333D01*
X276600Y141667D01*
G01X282450Y143250D02*
X285117D01*
X284867Y143833D01*
X284450Y144167D01*
X283867Y144333D01*
X283283Y144250D01*
X282783Y144000D01*
X282450Y143417D01*
X282283Y142917D01*
Y142417D01*
X282450Y141917D01*
X282867Y141417D01*
X283367Y141083D01*
X283950Y141000D01*
X284533Y141167D01*
X285117Y141667D01*
G01X290633Y143917D02*
X290050Y144250D01*
X289550Y144333D01*
X288883Y144167D01*
X288383Y143833D01*
X288050Y143250D01*
X287967Y142667D01*
X288050Y142083D01*
X288383Y141583D01*
X288883Y141167D01*
X289550Y141000D01*
X290133Y141167D01*
X290633Y141500D01*
G01X294900Y144333D02*
Y141000D01*
G01Y145667D02*
X294733Y145750D01*
Y145917D01*
X294900Y146000D01*
X295067Y145917D01*
Y145750D01*
X294900Y145667D01*
G01X300000Y141000D02*
Y145250D01*
X300167Y145667D01*
X300500Y145917D01*
X301000Y146000D01*
X301500Y145833D01*
X301750Y145417D01*
G01X300750Y144000D02*
X299083D01*
G01X306100Y144333D02*
Y141000D01*
G01Y145667D02*
X305933Y145750D01*
Y145917D01*
X306100Y146000D01*
X306267Y145917D01*
Y145750D01*
X306100Y145667D01*
G01X313033Y143917D02*
X312450Y144250D01*
X311950Y144333D01*
X311283Y144167D01*
X310783Y143833D01*
X310450Y143250D01*
X310367Y142667D01*
X310450Y142083D01*
X310783Y141583D01*
X311283Y141167D01*
X311950Y141000D01*
X312533Y141167D01*
X313033Y141500D01*
G01X318800Y141000D02*
Y144333D01*
G01Y143750D02*
X318467Y144083D01*
X317967Y144250D01*
X317383Y144333D01*
X316800Y144167D01*
X316300Y143833D01*
X315967Y143333D01*
X315800Y142667D01*
X315967Y142000D01*
X316300Y141500D01*
X316800Y141167D01*
X317383Y141000D01*
X317967Y141083D01*
X318467Y141333D01*
X318800Y141667D01*
G01X322900Y146000D02*
Y141000D01*
G01X321733Y144333D02*
X324067D01*
G01X328500D02*
Y141000D01*
G01Y145667D02*
X328333Y145750D01*
Y145917D01*
X328500Y146000D01*
X328667Y145917D01*
Y145750D01*
X328500Y145667D01*
G01X334100Y141000D02*
X333600Y141083D01*
X333100Y141417D01*
X332767Y142000D01*
X332600Y142667D01*
X332767Y143333D01*
X333100Y143917D01*
X333600Y144250D01*
X334100Y144333D01*
X334600Y144250D01*
X335100Y143917D01*
X335433Y143333D01*
X335517Y142667D01*
X335433Y142000D01*
X335100Y141417D01*
X334600Y141083D01*
X334100Y141000D01*
G01X338283D02*
Y144333D01*
G01Y143500D02*
X338617Y143917D01*
X339117Y144250D01*
X339783Y144333D01*
X340367Y144250D01*
X340867Y143917D01*
X341117Y143333D01*
Y141000D01*
G01X345300Y140833D02*
X345133Y140917D01*
Y141083D01*
X345300Y141167D01*
X345467Y141083D01*
Y140917D01*
X345300Y140833D01*
G01X270833Y110000D02*
Y115000D01*
X272917D01*
X273583Y114750D01*
X274000Y114417D01*
X274167Y113750D01*
X274000Y113083D01*
X273500Y112667D01*
X272917Y112417D01*
X270833D01*
G01X272917D02*
X274167Y110000D01*
G01X276850Y112250D02*
X279517D01*
X279267Y112833D01*
X278850Y113167D01*
X278267Y113333D01*
X277683Y113250D01*
X277183Y113000D01*
X276850Y112417D01*
X276683Y111917D01*
Y111417D01*
X276850Y110917D01*
X277267Y110417D01*
X277767Y110083D01*
X278350Y110000D01*
X278933Y110167D01*
X279517Y110667D01*
G01X283700Y110000D02*
Y115000D01*
G01X290800Y110000D02*
Y113333D01*
G01Y112750D02*
X290467Y113083D01*
X289967Y113250D01*
X289383Y113333D01*
X288800Y113167D01*
X288300Y112833D01*
X287967Y112333D01*
X287800Y111667D01*
X287967Y111000D01*
X288300Y110500D01*
X288800Y110167D01*
X289383Y110000D01*
X289967Y110083D01*
X290467Y110333D01*
X290800Y110667D01*
G01X294900Y115000D02*
Y110000D01*
G01X293733Y113333D02*
X296067D01*
G01X300500D02*
Y110000D01*
G01Y114667D02*
X300333Y114750D01*
Y114917D01*
X300500Y115000D01*
X300667Y114917D01*
Y114750D01*
X300500Y114667D01*
G01X304600Y113333D02*
X306100Y110000D01*
X307600Y113333D01*
G01X310450Y112250D02*
X313117D01*
X312867Y112833D01*
X312450Y113167D01*
X311867Y113333D01*
X311283Y113250D01*
X310783Y113000D01*
X310450Y112417D01*
X310283Y111917D01*
Y111417D01*
X310450Y110917D01*
X310867Y110417D01*
X311367Y110083D01*
X311950Y110000D01*
X312533Y110167D01*
X313117Y110667D01*
G01X321400Y108333D02*
Y113333D01*
G01Y112583D02*
X321817Y113000D01*
X322233Y113250D01*
X322900Y113333D01*
X323483Y113250D01*
X324067Y112833D01*
X324317Y112250D01*
X324400Y111667D01*
X324317Y111083D01*
X324067Y110500D01*
X323567Y110167D01*
X322900Y110000D01*
X322317Y110083D01*
X321733Y110333D01*
X321400Y110667D01*
G01X328500Y110000D02*
X328000Y110083D01*
X327500Y110417D01*
X327167Y111000D01*
X327000Y111667D01*
X327167Y112333D01*
X327500Y112917D01*
X328000Y113250D01*
X328500Y113333D01*
X329000Y113250D01*
X329500Y112917D01*
X329833Y112333D01*
X329917Y111667D01*
X329833Y111000D01*
X329500Y110417D01*
X329000Y110083D01*
X328500Y110000D01*
G01X332850Y110583D02*
X333267Y110250D01*
X333850Y110000D01*
X334350D01*
X334850Y110167D01*
X335183Y110417D01*
X335350Y110750D01*
X335267Y111250D01*
X334933Y111500D01*
X333433Y112000D01*
X333100Y112583D01*
X333267Y113000D01*
X333600Y113250D01*
X334100Y113333D01*
X334600Y113250D01*
X335100Y113000D01*
G01X339700Y113333D02*
Y110000D01*
G01Y114667D02*
X339533Y114750D01*
Y114917D01*
X339700Y115000D01*
X339867Y114917D01*
Y114750D01*
X339700Y114667D01*
G01X345300Y115000D02*
Y110000D01*
G01X344133Y113333D02*
X346467D01*
G01X350900D02*
Y110000D01*
G01Y114667D02*
X350733Y114750D01*
Y114917D01*
X350900Y115000D01*
X351067Y114917D01*
Y114750D01*
X350900Y114667D01*
G01X356500Y110000D02*
X356000Y110083D01*
X355500Y110417D01*
X355167Y111000D01*
X355000Y111667D01*
X355167Y112333D01*
X355500Y112917D01*
X356000Y113250D01*
X356500Y113333D01*
X357000Y113250D01*
X357500Y112917D01*
X357833Y112333D01*
X357917Y111667D01*
X357833Y111000D01*
X357500Y110417D01*
X357000Y110083D01*
X356500Y110000D01*
G01X360683D02*
Y113333D01*
G01Y112500D02*
X361017Y112917D01*
X361517Y113250D01*
X362183Y113333D01*
X362767Y113250D01*
X363267Y112917D01*
X363517Y112333D01*
Y110000D01*
G01X371800D02*
Y115000D01*
G01Y112500D02*
X372217Y113000D01*
X372717Y113250D01*
X373217Y113333D01*
X373967Y113167D01*
X374467Y112833D01*
X374800Y112250D01*
Y111583D01*
X374633Y110917D01*
X374300Y110417D01*
X373717Y110083D01*
X373217Y110000D01*
X372717Y110083D01*
X372217Y110333D01*
X371800Y110750D01*
G01X377650Y112250D02*
X380317D01*
X380067Y112833D01*
X379650Y113167D01*
X379067Y113333D01*
X378483Y113250D01*
X377983Y113000D01*
X377650Y112417D01*
X377483Y111917D01*
Y111417D01*
X377650Y110917D01*
X378067Y110417D01*
X378567Y110083D01*
X379150Y110000D01*
X379733Y110167D01*
X380317Y110667D01*
G01X384500Y115000D02*
Y110000D01*
G01X383333Y113333D02*
X385667D01*
G01X388017D02*
X389017Y110000D01*
X390100Y113333D01*
X391183Y110000D01*
X392183Y113333D01*
G01X394450Y112250D02*
X397117D01*
X396867Y112833D01*
X396450Y113167D01*
X395867Y113333D01*
X395283Y113250D01*
X394783Y113000D01*
X394450Y112417D01*
X394283Y111917D01*
Y111417D01*
X394450Y110917D01*
X394867Y110417D01*
X395367Y110083D01*
X395950Y110000D01*
X396533Y110167D01*
X397117Y110667D01*
G01X400050Y112250D02*
X402717D01*
X402467Y112833D01*
X402050Y113167D01*
X401467Y113333D01*
X400883Y113250D01*
X400383Y113000D01*
X400050Y112417D01*
X399883Y111917D01*
Y111417D01*
X400050Y110917D01*
X400467Y110417D01*
X400967Y110083D01*
X401550Y110000D01*
X402133Y110167D01*
X402717Y110667D01*
G01X405483Y110000D02*
Y113333D01*
G01Y112500D02*
X405817Y112917D01*
X406317Y113250D01*
X406983Y113333D01*
X407567Y113250D01*
X408067Y112917D01*
X408317Y112333D01*
Y110000D01*
G01X419600D02*
Y113333D01*
G01Y112750D02*
X419267Y113083D01*
X418767Y113250D01*
X418183Y113333D01*
X417600Y113167D01*
X417100Y112833D01*
X416767Y112333D01*
X416600Y111667D01*
X416767Y111000D01*
X417100Y110500D01*
X417600Y110167D01*
X418183Y110000D01*
X418767Y110083D01*
X419267Y110333D01*
X419600Y110667D01*
G01X422283Y110000D02*
Y113333D01*
G01Y112500D02*
X422617Y112917D01*
X423117Y113250D01*
X423783Y113333D01*
X424367Y113250D01*
X424867Y112917D01*
X425117Y112333D01*
Y110000D01*
G01X427550Y108500D02*
X428050Y108333D01*
X428717Y108500D01*
X429133Y108833D01*
X429467Y109250D01*
X429967Y110583D01*
X431050Y113333D01*
G01X428383D02*
X429967Y110583D01*
G01X439000Y108333D02*
Y113333D01*
G01Y112583D02*
X439417Y113000D01*
X439833Y113250D01*
X440500Y113333D01*
X441083Y113250D01*
X441667Y112833D01*
X441917Y112250D01*
X442000Y111667D01*
X441917Y111083D01*
X441667Y110500D01*
X441167Y110167D01*
X440500Y110000D01*
X439917Y110083D01*
X439333Y110333D01*
X439000Y110667D01*
G01X447600Y110000D02*
Y113333D01*
G01Y112750D02*
X447267Y113083D01*
X446767Y113250D01*
X446183Y113333D01*
X445600Y113167D01*
X445100Y112833D01*
X444767Y112333D01*
X444600Y111667D01*
X444767Y111000D01*
X445100Y110500D01*
X445600Y110167D01*
X446183Y110000D01*
X446767Y110083D01*
X447267Y110333D01*
X447600Y110667D01*
G01X453200Y115000D02*
Y110000D01*
G01Y110750D02*
X452867Y110333D01*
X452367Y110083D01*
X451783Y110000D01*
X451117Y110167D01*
X450617Y110583D01*
X450283Y111083D01*
X450200Y111667D01*
X450283Y112250D01*
X450617Y112750D01*
X451117Y113167D01*
X451783Y113333D01*
X452367Y113250D01*
X452783Y113083D01*
X453200Y112750D01*
G01X462900Y115000D02*
Y110000D01*
G01X461733Y113333D02*
X464067D01*
G01X468500Y110000D02*
X468000Y110083D01*
X467500Y110417D01*
X467167Y111000D01*
X467000Y111667D01*
X467167Y112333D01*
X467500Y112917D01*
X468000Y113250D01*
X468500Y113333D01*
X469000Y113250D01*
X469500Y112917D01*
X469833Y112333D01*
X469917Y111667D01*
X469833Y111000D01*
X469500Y110417D01*
X469000Y110083D01*
X468500Y110000D01*
G01X478200Y108333D02*
Y113333D01*
G01Y112583D02*
X478617Y113000D01*
X479033Y113250D01*
X479700Y113333D01*
X480283Y113250D01*
X480867Y112833D01*
X481117Y112250D01*
X481200Y111667D01*
X481117Y111083D01*
X480867Y110500D01*
X480367Y110167D01*
X479700Y110000D01*
X479117Y110083D01*
X478533Y110333D01*
X478200Y110667D01*
G01X486800Y110000D02*
Y113333D01*
G01Y112750D02*
X486467Y113083D01*
X485967Y113250D01*
X485383Y113333D01*
X484800Y113167D01*
X484300Y112833D01*
X483967Y112333D01*
X483800Y111667D01*
X483967Y111000D01*
X484300Y110500D01*
X484800Y110167D01*
X485383Y110000D01*
X485967Y110083D01*
X486467Y110333D01*
X486800Y110667D01*
G01X492400Y115000D02*
Y110000D01*
G01Y110750D02*
X492067Y110333D01*
X491567Y110083D01*
X490983Y110000D01*
X490317Y110167D01*
X489817Y110583D01*
X489483Y111083D01*
X489400Y111667D01*
X489483Y112250D01*
X489817Y112750D01*
X490317Y113167D01*
X490983Y113333D01*
X491567Y113250D01*
X491983Y113083D01*
X492400Y112750D01*
G01X270750Y125000D02*
Y130000D01*
G01X274250D02*
Y125000D01*
G01Y127500D02*
X270750D01*
G01X276267Y125000D02*
Y130000D01*
X277933D01*
X278600Y129750D01*
X279100Y129417D01*
X279517Y128917D01*
X279850Y128333D01*
X279933Y127500D01*
X279850Y126667D01*
X279517Y126083D01*
X279100Y125583D01*
X278600Y125250D01*
X277933Y125000D01*
X276267D01*
G01X282700Y130000D02*
X284700D01*
G01X283700D02*
Y125000D01*
G01X282700D02*
X284700D01*
G01X293233D02*
Y130000D01*
X295233D01*
X295900Y129750D01*
X296400Y129167D01*
X296567Y128500D01*
X296400Y127833D01*
X295983Y127333D01*
X295233Y127083D01*
X293233D01*
G01X302333Y129583D02*
X301833Y129833D01*
X301250Y130000D01*
X300583D01*
X299833Y129750D01*
X299250Y129333D01*
X298833Y128833D01*
X298500Y128000D01*
X298417Y127250D01*
X298583Y126500D01*
X298833Y126000D01*
X299333Y125500D01*
X299917Y125167D01*
X300500Y125000D01*
X301083D01*
X301667Y125167D01*
X302167Y125417D01*
X302583Y125750D01*
G01X306767Y127667D02*
X307100Y127917D01*
X307350Y128333D01*
X307517Y128917D01*
X307350Y129417D01*
X307017Y129750D01*
X306433Y130000D01*
X304183D01*
Y125000D01*
X306933D01*
X307517Y125333D01*
X307850Y125833D01*
X308017Y126417D01*
X307850Y127000D01*
X307350Y127500D01*
X306767Y127667D01*
X304183D01*
G01X311700Y124833D02*
X311533Y124917D01*
Y125083D01*
X311700Y125167D01*
X311867Y125083D01*
Y124917D01*
X311700Y124833D01*
G01X270750Y150667D02*
X271417Y150250D01*
X272167Y150000D01*
X272833D01*
X273500Y150250D01*
X274000Y150667D01*
X274250Y151250D01*
X274083Y151833D01*
X273667Y152333D01*
X272917Y152667D01*
X271917Y152833D01*
X271333Y153167D01*
X271083Y153750D01*
X271250Y154333D01*
X271667Y154750D01*
X272250Y155000D01*
X272833D01*
X273417Y154833D01*
X273917Y154417D01*
G01X276850Y152250D02*
X279517D01*
X279267Y152833D01*
X278850Y153167D01*
X278267Y153333D01*
X277683Y153250D01*
X277183Y153000D01*
X276850Y152417D01*
X276683Y151917D01*
Y151417D01*
X276850Y150917D01*
X277267Y150417D01*
X277767Y150083D01*
X278350Y150000D01*
X278933Y150167D01*
X279517Y150667D01*
G01X282533Y150000D02*
Y153333D01*
G01Y152667D02*
X282950Y153000D01*
X283367Y153250D01*
X283950Y153333D01*
X284367Y153250D01*
X284867Y153000D01*
G01X287800Y153333D02*
X289300Y150000D01*
X290800Y153333D01*
G01X293650Y152250D02*
X296317D01*
X296067Y152833D01*
X295650Y153167D01*
X295067Y153333D01*
X294483Y153250D01*
X293983Y153000D01*
X293650Y152417D01*
X293483Y151917D01*
Y151417D01*
X293650Y150917D01*
X294067Y150417D01*
X294567Y150083D01*
X295150Y150000D01*
X295733Y150167D01*
X296317Y150667D01*
G01X299333Y150000D02*
Y153333D01*
G01Y152667D02*
X299750Y153000D01*
X300167Y153250D01*
X300750Y153333D01*
X301167Y153250D01*
X301667Y153000D01*
G01X310033Y150000D02*
Y155000D01*
X312033D01*
X312700Y154750D01*
X313200Y154167D01*
X313367Y153500D01*
X313200Y152833D01*
X312783Y152333D01*
X312033Y152083D01*
X310033D01*
G01X319133Y154583D02*
X318633Y154833D01*
X318050Y155000D01*
X317383D01*
X316633Y154750D01*
X316050Y154333D01*
X315633Y153833D01*
X315300Y153000D01*
X315217Y152250D01*
X315383Y151500D01*
X315633Y151000D01*
X316133Y150500D01*
X316717Y150167D01*
X317300Y150000D01*
X317883D01*
X318467Y150167D01*
X318967Y150417D01*
X319383Y150750D01*
G01X323567Y152667D02*
X323900Y152917D01*
X324150Y153333D01*
X324317Y153917D01*
X324150Y154417D01*
X323817Y154750D01*
X323233Y155000D01*
X320983D01*
Y150000D01*
X323733D01*
X324317Y150333D01*
X324650Y150833D01*
X324817Y151417D01*
X324650Y152000D01*
X324150Y152500D01*
X323567Y152667D01*
X320983D01*
G01X328500Y149833D02*
X328333Y149917D01*
Y150083D01*
X328500Y150167D01*
X328667Y150083D01*
Y149917D01*
X328500Y149833D01*
G01Y152083D02*
X328333Y152167D01*
Y152333D01*
X328500Y152417D01*
X328667Y152333D01*
Y152167D01*
X328500Y152083D01*
G01X332517Y150000D02*
Y155000D01*
X335683D01*
G01X334517Y152583D02*
X332517D01*
G01X339700Y150000D02*
X339200Y150083D01*
X338700Y150417D01*
X338367Y151000D01*
X338200Y151667D01*
X338367Y152333D01*
X338700Y152917D01*
X339200Y153250D01*
X339700Y153333D01*
X340200Y153250D01*
X340700Y152917D01*
X341033Y152333D01*
X341117Y151667D01*
X341033Y151000D01*
X340700Y150417D01*
X340200Y150083D01*
X339700Y150000D01*
G01X345300D02*
Y155000D01*
G01X350900Y150000D02*
Y155000D01*
G01X356500Y150000D02*
X356000Y150083D01*
X355500Y150417D01*
X355167Y151000D01*
X355000Y151667D01*
X355167Y152333D01*
X355500Y152917D01*
X356000Y153250D01*
X356500Y153333D01*
X357000Y153250D01*
X357500Y152917D01*
X357833Y152333D01*
X357917Y151667D01*
X357833Y151000D01*
X357500Y150417D01*
X357000Y150083D01*
X356500Y150000D01*
G01X360017Y153333D02*
X361017Y150000D01*
X362100Y153333D01*
X363183Y150000D01*
X364183Y153333D01*
G01X372133Y150000D02*
Y153333D01*
G01Y152667D02*
X372550Y153000D01*
X372967Y153250D01*
X373550Y153333D01*
X373967Y153250D01*
X374467Y153000D01*
G01X378900Y153333D02*
Y150000D01*
G01Y154667D02*
X378733Y154750D01*
Y154917D01*
X378900Y155000D01*
X379067Y154917D01*
Y154750D01*
X378900Y154667D01*
G01X383333Y148750D02*
X383917Y148417D01*
X384583Y148333D01*
X385167Y148417D01*
X385667Y148833D01*
X386000Y149417D01*
Y153333D01*
G01Y152667D02*
X385667Y153000D01*
X385167Y153250D01*
X384583Y153333D01*
X383917Y153167D01*
X383500Y152833D01*
X383167Y152250D01*
X383000Y151667D01*
X383083Y151167D01*
X383417Y150583D01*
X383917Y150167D01*
X384583Y150000D01*
X385083Y150083D01*
X385667Y150417D01*
X386000Y150750D01*
G01X388683Y150000D02*
Y155000D01*
G01Y152583D02*
X389100Y153000D01*
X389517Y153250D01*
X390183Y153333D01*
X390683Y153250D01*
X391267Y152917D01*
X391517Y152417D01*
Y150000D01*
G01X395700Y155000D02*
Y150000D01*
G01X394533Y153333D02*
X396867D01*
G01X405650Y150583D02*
X406067Y150250D01*
X406650Y150000D01*
X407150D01*
X407650Y150167D01*
X407983Y150417D01*
X408150Y150750D01*
X408067Y151250D01*
X407733Y151500D01*
X406233Y152000D01*
X405900Y152583D01*
X406067Y153000D01*
X406400Y153250D01*
X406900Y153333D01*
X407400Y153250D01*
X407900Y153000D01*
G01X412500Y153333D02*
Y150000D01*
G01Y154667D02*
X412333Y154750D01*
Y154917D01*
X412500Y155000D01*
X412667Y154917D01*
Y154750D01*
X412500Y154667D01*
G01X419600Y155000D02*
Y150000D01*
G01Y150750D02*
X419267Y150333D01*
X418767Y150083D01*
X418183Y150000D01*
X417517Y150167D01*
X417017Y150583D01*
X416683Y151083D01*
X416600Y151667D01*
X416683Y152250D01*
X417017Y152750D01*
X417517Y153167D01*
X418183Y153333D01*
X418767Y153250D01*
X419183Y153083D01*
X419600Y152750D01*
G01X422450Y152250D02*
X425117D01*
X424867Y152833D01*
X424450Y153167D01*
X423867Y153333D01*
X423283Y153250D01*
X422783Y153000D01*
X422450Y152417D01*
X422283Y151917D01*
Y151417D01*
X422450Y150917D01*
X422867Y150417D01*
X423367Y150083D01*
X423950Y150000D01*
X424533Y150167D01*
X425117Y150667D01*
G01X433650Y150583D02*
X434067Y150250D01*
X434650Y150000D01*
X435150D01*
X435650Y150167D01*
X435983Y150417D01*
X436150Y150750D01*
X436067Y151250D01*
X435733Y151500D01*
X434233Y152000D01*
X433900Y152583D01*
X434067Y153000D01*
X434400Y153250D01*
X434900Y153333D01*
X435400Y153250D01*
X435900Y153000D01*
G01X439000Y148333D02*
Y153333D01*
G01Y152583D02*
X439417Y153000D01*
X439833Y153250D01*
X440500Y153333D01*
X441083Y153250D01*
X441667Y152833D01*
X441917Y152250D01*
X442000Y151667D01*
X441917Y151083D01*
X441667Y150500D01*
X441167Y150167D01*
X440500Y150000D01*
X439917Y150083D01*
X439333Y150333D01*
X439000Y150667D01*
G01X444850Y152250D02*
X447517D01*
X447267Y152833D01*
X446850Y153167D01*
X446267Y153333D01*
X445683Y153250D01*
X445183Y153000D01*
X444850Y152417D01*
X444683Y151917D01*
Y151417D01*
X444850Y150917D01*
X445267Y150417D01*
X445767Y150083D01*
X446350Y150000D01*
X446933Y150167D01*
X447517Y150667D01*
G01X453033Y152917D02*
X452450Y153250D01*
X451950Y153333D01*
X451283Y153167D01*
X450783Y152833D01*
X450450Y152250D01*
X450367Y151667D01*
X450450Y151083D01*
X450783Y150583D01*
X451283Y150167D01*
X451950Y150000D01*
X452533Y150167D01*
X453033Y150500D01*
G01X462733Y149083D02*
X463067Y150167D01*
G01X468500Y153333D02*
Y150000D01*
G01Y154667D02*
X468333Y154750D01*
Y154917D01*
X468500Y155000D01*
X468667Y154917D01*
Y154750D01*
X468500Y154667D01*
G01X473600Y150000D02*
Y154250D01*
X473767Y154667D01*
X474100Y154917D01*
X474600Y155000D01*
X475100Y154833D01*
X475350Y154417D01*
G01X474350Y153000D02*
X472683D01*
G01X484050Y150583D02*
X484467Y150250D01*
X485050Y150000D01*
X485550D01*
X486050Y150167D01*
X486383Y150417D01*
X486550Y150750D01*
X486467Y151250D01*
X486133Y151500D01*
X484633Y152000D01*
X484300Y152583D01*
X484467Y153000D01*
X484800Y153250D01*
X485300Y153333D01*
X485800Y153250D01*
X486300Y153000D01*
G01X490900Y155000D02*
Y150000D01*
G01X489733Y153333D02*
X492067D01*
G01X498000Y150000D02*
Y153333D01*
G01Y152750D02*
X497667Y153083D01*
X497167Y153250D01*
X496583Y153333D01*
X496000Y153167D01*
X495500Y152833D01*
X495167Y152333D01*
X495000Y151667D01*
X495167Y151000D01*
X495500Y150500D01*
X496000Y150167D01*
X496583Y150000D01*
X497167Y150083D01*
X497667Y150333D01*
X498000Y150667D01*
G01X503433Y152917D02*
X502850Y153250D01*
X502350Y153333D01*
X501683Y153167D01*
X501183Y152833D01*
X500850Y152250D01*
X500767Y151667D01*
X500850Y151083D01*
X501183Y150583D01*
X501683Y150167D01*
X502350Y150000D01*
X502933Y150167D01*
X503433Y150500D01*
G01X506283Y150000D02*
Y155000D01*
G01X508950Y153333D02*
X506283Y151417D01*
G01X507367Y152167D02*
X509117Y150000D01*
G01X517483Y153333D02*
Y151000D01*
X517817Y150417D01*
X518317Y150083D01*
X518900Y150000D01*
X519483Y150083D01*
X519983Y150417D01*
X520317Y151000D01*
G01Y150000D02*
Y153333D01*
G01X523000Y148333D02*
Y153333D01*
G01Y152583D02*
X523417Y153000D01*
X523833Y153250D01*
X524500Y153333D01*
X525083Y153250D01*
X525667Y152833D01*
X525917Y152250D01*
X526000Y151667D01*
X525917Y151083D01*
X525667Y150500D01*
X525167Y150167D01*
X524500Y150000D01*
X523917Y150083D01*
X523333Y150333D01*
X523000Y150667D01*
G01X533617Y153333D02*
X534617Y150000D01*
X535700Y153333D01*
X536783Y150000D01*
X537783Y153333D01*
G01X541300D02*
Y150000D01*
G01Y154667D02*
X541133Y154750D01*
Y154917D01*
X541300Y155000D01*
X541467Y154917D01*
Y154750D01*
X541300Y154667D01*
G01X546900Y155000D02*
Y150000D01*
G01X545733Y153333D02*
X548067D01*
G01X551083Y150000D02*
Y155000D01*
G01Y152583D02*
X551500Y153000D01*
X551917Y153250D01*
X552583Y153333D01*
X553083Y153250D01*
X553667Y152917D01*
X553917Y152417D01*
Y150000D01*
G01X558100D02*
X557600Y150083D01*
X557100Y150417D01*
X556767Y151000D01*
X556600Y151667D01*
X556767Y152333D01*
X557100Y152917D01*
X557600Y153250D01*
X558100Y153333D01*
X558600Y153250D01*
X559100Y152917D01*
X559433Y152333D01*
X559517Y151667D01*
X559433Y151000D01*
X559100Y150417D01*
X558600Y150083D01*
X558100Y150000D01*
G01X562283Y153333D02*
Y151000D01*
X562617Y150417D01*
X563117Y150083D01*
X563700Y150000D01*
X564283Y150083D01*
X564783Y150417D01*
X565117Y151000D01*
G01Y150000D02*
Y153333D01*
G01X569300Y155000D02*
Y150000D01*
G01X568133Y153333D02*
X570467D01*
G01X272500Y170000D02*
Y165000D01*
G01X270583Y170000D02*
X274417D01*
G01X276933Y165000D02*
Y168333D01*
G01Y167667D02*
X277350Y168000D01*
X277767Y168250D01*
X278350Y168333D01*
X278767Y168250D01*
X279267Y168000D01*
G01X285200Y165000D02*
Y168333D01*
G01Y167750D02*
X284867Y168083D01*
X284367Y168250D01*
X283783Y168333D01*
X283200Y168167D01*
X282700Y167833D01*
X282367Y167333D01*
X282200Y166667D01*
X282367Y166000D01*
X282700Y165500D01*
X283200Y165167D01*
X283783Y165000D01*
X284367Y165083D01*
X284867Y165333D01*
X285200Y165667D01*
G01X290800Y170000D02*
Y165000D01*
G01Y165750D02*
X290467Y165333D01*
X289967Y165083D01*
X289383Y165000D01*
X288717Y165167D01*
X288217Y165583D01*
X287883Y166083D01*
X287800Y166667D01*
X287883Y167250D01*
X288217Y167750D01*
X288717Y168167D01*
X289383Y168333D01*
X289967Y168250D01*
X290383Y168083D01*
X290800Y167750D01*
G01X294900Y168333D02*
Y165000D01*
G01Y169667D02*
X294733Y169750D01*
Y169917D01*
X294900Y170000D01*
X295067Y169917D01*
Y169750D01*
X294900Y169667D01*
G01X300500Y170000D02*
Y165000D01*
G01X299333Y168333D02*
X301667D01*
G01X306100D02*
Y165000D01*
G01Y169667D02*
X305933Y169750D01*
Y169917D01*
X306100Y170000D01*
X306267Y169917D01*
Y169750D01*
X306100Y169667D01*
G01X311700Y165000D02*
X311200Y165083D01*
X310700Y165417D01*
X310367Y166000D01*
X310200Y166667D01*
X310367Y167333D01*
X310700Y167917D01*
X311200Y168250D01*
X311700Y168333D01*
X312200Y168250D01*
X312700Y167917D01*
X313033Y167333D01*
X313117Y166667D01*
X313033Y166000D01*
X312700Y165417D01*
X312200Y165083D01*
X311700Y165000D01*
G01X315883D02*
Y168333D01*
G01Y167500D02*
X316217Y167917D01*
X316717Y168250D01*
X317383Y168333D01*
X317967Y168250D01*
X318467Y167917D01*
X318717Y167333D01*
Y165000D01*
G01X324400D02*
Y168333D01*
G01Y167750D02*
X324067Y168083D01*
X323567Y168250D01*
X322983Y168333D01*
X322400Y168167D01*
X321900Y167833D01*
X321567Y167333D01*
X321400Y166667D01*
X321567Y166000D01*
X321900Y165500D01*
X322400Y165167D01*
X322983Y165000D01*
X323567Y165083D01*
X324067Y165333D01*
X324400Y165667D01*
G01X328500Y165000D02*
Y170000D01*
G01X338033Y165000D02*
Y170000D01*
X340033D01*
X340700Y169750D01*
X341200Y169167D01*
X341367Y168500D01*
X341200Y167833D01*
X340783Y167333D01*
X340033Y167083D01*
X338033D01*
G01X347133Y169583D02*
X346633Y169833D01*
X346050Y170000D01*
X345383D01*
X344633Y169750D01*
X344050Y169333D01*
X343633Y168833D01*
X343300Y168000D01*
X343217Y167250D01*
X343383Y166500D01*
X343633Y166000D01*
X344133Y165500D01*
X344717Y165167D01*
X345300Y165000D01*
X345883D01*
X346467Y165167D01*
X346967Y165417D01*
X347383Y165750D01*
G01X351567Y167667D02*
X351900Y167917D01*
X352150Y168333D01*
X352317Y168917D01*
X352150Y169417D01*
X351817Y169750D01*
X351233Y170000D01*
X348983D01*
Y165000D01*
X351733D01*
X352317Y165333D01*
X352650Y165833D01*
X352817Y166417D01*
X352650Y167000D01*
X352150Y167500D01*
X351567Y167667D01*
X348983D01*
G01X356500Y164833D02*
X356333Y164917D01*
Y165083D01*
X356500Y165167D01*
X356667Y165083D01*
Y164917D01*
X356500Y164833D01*
G01X270000Y374000D02*
Y369000D01*
G01X268833Y372333D02*
X271167D01*
G01X275600Y369000D02*
X275100Y369083D01*
X274600Y369417D01*
X274267Y370000D01*
X274100Y370667D01*
X274267Y371333D01*
X274600Y371917D01*
X275100Y372250D01*
X275600Y372333D01*
X276100Y372250D01*
X276600Y371917D01*
X276933Y371333D01*
X277017Y370667D01*
X276933Y370000D01*
X276600Y369417D01*
X276100Y369083D01*
X275600Y369000D01*
G01X281200D02*
Y374000D01*
G01X285550Y371250D02*
X288217D01*
X287967Y371833D01*
X287550Y372167D01*
X286967Y372333D01*
X286383Y372250D01*
X285883Y372000D01*
X285550Y371417D01*
X285383Y370917D01*
Y370417D01*
X285550Y369917D01*
X285967Y369417D01*
X286467Y369083D01*
X287050Y369000D01*
X287633Y369167D01*
X288217Y369667D01*
G01X291233Y369000D02*
Y372333D01*
G01Y371667D02*
X291650Y372000D01*
X292067Y372250D01*
X292650Y372333D01*
X293067Y372250D01*
X293567Y372000D01*
G01X299500Y369000D02*
Y372333D01*
G01Y371750D02*
X299167Y372083D01*
X298667Y372250D01*
X298083Y372333D01*
X297500Y372167D01*
X297000Y371833D01*
X296667Y371333D01*
X296500Y370667D01*
X296667Y370000D01*
X297000Y369500D01*
X297500Y369167D01*
X298083Y369000D01*
X298667Y369083D01*
X299167Y369333D01*
X299500Y369667D01*
G01X302183Y369000D02*
Y372333D01*
G01Y371500D02*
X302517Y371917D01*
X303017Y372250D01*
X303683Y372333D01*
X304267Y372250D01*
X304767Y371917D01*
X305017Y371333D01*
Y369000D01*
G01X310533Y371917D02*
X309950Y372250D01*
X309450Y372333D01*
X308783Y372167D01*
X308283Y371833D01*
X307950Y371250D01*
X307867Y370667D01*
X307950Y370083D01*
X308283Y369583D01*
X308783Y369167D01*
X309450Y369000D01*
X310033Y369167D01*
X310533Y369500D01*
G01X313550Y371250D02*
X316217D01*
X315967Y371833D01*
X315550Y372167D01*
X314967Y372333D01*
X314383Y372250D01*
X313883Y372000D01*
X313550Y371417D01*
X313383Y370917D01*
Y370417D01*
X313550Y369917D01*
X313967Y369417D01*
X314467Y369083D01*
X315050Y369000D01*
X315633Y369167D01*
X316217Y369667D01*
G01X326000Y374000D02*
Y369000D01*
G01X324833Y372333D02*
X327167D01*
G01X333100Y369000D02*
Y372333D01*
G01Y371750D02*
X332767Y372083D01*
X332267Y372250D01*
X331683Y372333D01*
X331100Y372167D01*
X330600Y371833D01*
X330267Y371333D01*
X330100Y370667D01*
X330267Y370000D01*
X330600Y369500D01*
X331100Y369167D01*
X331683Y369000D01*
X332267Y369083D01*
X332767Y369333D01*
X333100Y369667D01*
G01X335700Y369000D02*
Y374000D01*
G01Y371500D02*
X336117Y372000D01*
X336617Y372250D01*
X337117Y372333D01*
X337867Y372167D01*
X338367Y371833D01*
X338700Y371250D01*
Y370583D01*
X338533Y369917D01*
X338200Y369417D01*
X337617Y369083D01*
X337117Y369000D01*
X336617Y369083D01*
X336117Y369333D01*
X335700Y369750D01*
G01X342800Y369000D02*
Y374000D01*
G01X347150Y371250D02*
X349817D01*
X349567Y371833D01*
X349150Y372167D01*
X348567Y372333D01*
X347983Y372250D01*
X347483Y372000D01*
X347150Y371417D01*
X346983Y370917D01*
Y370417D01*
X347150Y369917D01*
X347567Y369417D01*
X348067Y369083D01*
X348650Y369000D01*
X349233Y369167D01*
X349817Y369667D01*
G01X354000Y368833D02*
X353833Y368917D01*
Y369083D01*
X354000Y369167D01*
X354167Y369083D01*
Y368917D01*
X354000Y368833D01*
G01X268667Y379750D02*
X269250Y379417D01*
X269750Y379333D01*
X270417Y379500D01*
X270917Y379917D01*
X271167Y380667D01*
Y384333D01*
G01Y385667D02*
X271000Y385750D01*
Y385917D01*
X271167Y386000D01*
X271333Y385917D01*
Y385750D01*
X271167Y385667D01*
G01X274183Y384333D02*
Y382000D01*
X274517Y381417D01*
X275017Y381083D01*
X275600Y381000D01*
X276183Y381083D01*
X276683Y381417D01*
X277017Y382000D01*
G01Y381000D02*
Y384333D01*
G01X279783Y381000D02*
Y384333D01*
G01Y383500D02*
X280117Y383917D01*
X280617Y384250D01*
X281283Y384333D01*
X281867Y384250D01*
X282367Y383917D01*
X282617Y383333D01*
Y381000D01*
G01X288133Y383917D02*
X287550Y384250D01*
X287050Y384333D01*
X286383Y384167D01*
X285883Y383833D01*
X285550Y383250D01*
X285467Y382667D01*
X285550Y382083D01*
X285883Y381583D01*
X286383Y381167D01*
X287050Y381000D01*
X287633Y381167D01*
X288133Y381500D01*
G01X292400Y386000D02*
Y381000D01*
G01X291233Y384333D02*
X293567D01*
G01X298000D02*
Y381000D01*
G01Y385667D02*
X297833Y385750D01*
Y385917D01*
X298000Y386000D01*
X298167Y385917D01*
Y385750D01*
X298000Y385667D01*
G01X303600Y381000D02*
X303100Y381083D01*
X302600Y381417D01*
X302267Y382000D01*
X302100Y382667D01*
X302267Y383333D01*
X302600Y383917D01*
X303100Y384250D01*
X303600Y384333D01*
X304100Y384250D01*
X304600Y383917D01*
X304933Y383333D01*
X305017Y382667D01*
X304933Y382000D01*
X304600Y381417D01*
X304100Y381083D01*
X303600Y381000D01*
G01X307783D02*
Y384333D01*
G01Y383500D02*
X308117Y383917D01*
X308617Y384250D01*
X309283Y384333D01*
X309867Y384250D01*
X310367Y383917D01*
X310617Y383333D01*
Y381000D01*
G01X318900D02*
Y386000D01*
G01Y383500D02*
X319317Y384000D01*
X319817Y384250D01*
X320317Y384333D01*
X321067Y384167D01*
X321567Y383833D01*
X321900Y383250D01*
Y382583D01*
X321733Y381917D01*
X321400Y381417D01*
X320817Y381083D01*
X320317Y381000D01*
X319817Y381083D01*
X319317Y381333D01*
X318900Y381750D01*
G01X324750Y383250D02*
X327417D01*
X327167Y383833D01*
X326750Y384167D01*
X326167Y384333D01*
X325583Y384250D01*
X325083Y384000D01*
X324750Y383417D01*
X324583Y382917D01*
Y382417D01*
X324750Y381917D01*
X325167Y381417D01*
X325667Y381083D01*
X326250Y381000D01*
X326833Y381167D01*
X327417Y381667D01*
G01X331600Y381000D02*
Y386000D01*
G01X337200Y381000D02*
X336700Y381083D01*
X336200Y381417D01*
X335867Y382000D01*
X335700Y382667D01*
X335867Y383333D01*
X336200Y383917D01*
X336700Y384250D01*
X337200Y384333D01*
X337700Y384250D01*
X338200Y383917D01*
X338533Y383333D01*
X338617Y382667D01*
X338533Y382000D01*
X338200Y381417D01*
X337700Y381083D01*
X337200Y381000D01*
G01X340717Y384333D02*
X341717Y381000D01*
X342800Y384333D01*
X343883Y381000D01*
X344883Y384333D01*
G01X354000Y386000D02*
Y381000D01*
G01X352833Y384333D02*
X355167D01*
G01X358183Y381000D02*
Y386000D01*
G01Y383583D02*
X358600Y384000D01*
X359017Y384250D01*
X359683Y384333D01*
X360183Y384250D01*
X360767Y383917D01*
X361017Y383417D01*
Y381000D01*
G01X363950Y383250D02*
X366617D01*
X366367Y383833D01*
X365950Y384167D01*
X365367Y384333D01*
X364783Y384250D01*
X364283Y384000D01*
X363950Y383417D01*
X363783Y382917D01*
Y382417D01*
X363950Y381917D01*
X364367Y381417D01*
X364867Y381083D01*
X365450Y381000D01*
X366033Y381167D01*
X366617Y381667D01*
G01X373900Y381000D02*
Y384333D01*
G01Y383417D02*
X374150Y383833D01*
X374567Y384167D01*
X375150Y384333D01*
X375733Y384167D01*
X376150Y383833D01*
X376400Y383417D01*
Y381000D01*
G01Y383417D02*
X376650Y383833D01*
X377067Y384167D01*
X377650Y384333D01*
X378233Y384167D01*
X378650Y383833D01*
X378900Y383333D01*
Y381000D01*
G01X382000Y384333D02*
Y381000D01*
G01Y385667D02*
X381833Y385750D01*
Y385917D01*
X382000Y386000D01*
X382167Y385917D01*
Y385750D01*
X382000Y385667D01*
G01X386183Y381000D02*
Y384333D01*
G01Y383500D02*
X386517Y383917D01*
X387017Y384250D01*
X387683Y384333D01*
X388267Y384250D01*
X388767Y383917D01*
X389017Y383333D01*
Y381000D01*
G01X400133Y383917D02*
X399550Y384250D01*
X399050Y384333D01*
X398383Y384167D01*
X397883Y383833D01*
X397550Y383250D01*
X397467Y382667D01*
X397550Y382083D01*
X397883Y381583D01*
X398383Y381167D01*
X399050Y381000D01*
X399633Y381167D01*
X400133Y381500D01*
G01X404400Y381000D02*
X403900Y381083D01*
X403400Y381417D01*
X403067Y382000D01*
X402900Y382667D01*
X403067Y383333D01*
X403400Y383917D01*
X403900Y384250D01*
X404400Y384333D01*
X404900Y384250D01*
X405400Y383917D01*
X405733Y383333D01*
X405817Y382667D01*
X405733Y382000D01*
X405400Y381417D01*
X404900Y381083D01*
X404400Y381000D01*
G01X408583D02*
Y384333D01*
G01Y383500D02*
X408917Y383917D01*
X409417Y384250D01*
X410083Y384333D01*
X410667Y384250D01*
X411167Y383917D01*
X411417Y383333D01*
Y381000D01*
G01X417100Y386000D02*
Y381000D01*
G01Y381750D02*
X416767Y381333D01*
X416267Y381083D01*
X415683Y381000D01*
X415017Y381167D01*
X414517Y381583D01*
X414183Y382083D01*
X414100Y382667D01*
X414183Y383250D01*
X414517Y383750D01*
X415017Y384167D01*
X415683Y384333D01*
X416267Y384250D01*
X416683Y384083D01*
X417100Y383750D01*
G01X419783Y384333D02*
Y382000D01*
X420117Y381417D01*
X420617Y381083D01*
X421200Y381000D01*
X421783Y381083D01*
X422283Y381417D01*
X422617Y382000D01*
G01Y381000D02*
Y384333D01*
G01X428133Y383917D02*
X427550Y384250D01*
X427050Y384333D01*
X426383Y384167D01*
X425883Y383833D01*
X425550Y383250D01*
X425467Y382667D01*
X425550Y382083D01*
X425883Y381583D01*
X426383Y381167D01*
X427050Y381000D01*
X427633Y381167D01*
X428133Y381500D01*
G01X432400Y386000D02*
Y381000D01*
G01X431233Y384333D02*
X433567D01*
G01X438000Y381000D02*
X437500Y381083D01*
X437000Y381417D01*
X436667Y382000D01*
X436500Y382667D01*
X436667Y383333D01*
X437000Y383917D01*
X437500Y384250D01*
X438000Y384333D01*
X438500Y384250D01*
X439000Y383917D01*
X439333Y383333D01*
X439417Y382667D01*
X439333Y382000D01*
X439000Y381417D01*
X438500Y381083D01*
X438000Y381000D01*
G01X442433D02*
Y384333D01*
G01Y383667D02*
X442850Y384000D01*
X443267Y384250D01*
X443850Y384333D01*
X444267Y384250D01*
X444767Y384000D01*
G01X452717Y384333D02*
X453717Y381000D01*
X454800Y384333D01*
X455883Y381000D01*
X456883Y384333D01*
G01X460400D02*
Y381000D01*
G01Y385667D02*
X460233Y385750D01*
Y385917D01*
X460400Y386000D01*
X460567Y385917D01*
Y385750D01*
X460400Y385667D01*
G01X467500Y386000D02*
Y381000D01*
G01Y381750D02*
X467167Y381333D01*
X466667Y381083D01*
X466083Y381000D01*
X465417Y381167D01*
X464917Y381583D01*
X464583Y382083D01*
X464500Y382667D01*
X464583Y383250D01*
X464917Y383750D01*
X465417Y384167D01*
X466083Y384333D01*
X466667Y384250D01*
X467083Y384083D01*
X467500Y383750D01*
G01X471600Y386000D02*
Y381000D01*
G01X470433Y384333D02*
X472767D01*
G01X475783Y381000D02*
Y386000D01*
G01Y383583D02*
X476200Y384000D01*
X476617Y384250D01*
X477283Y384333D01*
X477783Y384250D01*
X478367Y383917D01*
X478617Y383417D01*
Y381000D01*
G01X487150Y381583D02*
X487567Y381250D01*
X488150Y381000D01*
X488650D01*
X489150Y381167D01*
X489483Y381417D01*
X489650Y381750D01*
X489567Y382250D01*
X489233Y382500D01*
X487733Y383000D01*
X487400Y383583D01*
X487567Y384000D01*
X487900Y384250D01*
X488400Y384333D01*
X488900Y384250D01*
X489400Y384000D01*
G01X492500Y379333D02*
Y384333D01*
G01Y383583D02*
X492917Y384000D01*
X493333Y384250D01*
X494000Y384333D01*
X494583Y384250D01*
X495167Y383833D01*
X495417Y383250D01*
X495500Y382667D01*
X495417Y382083D01*
X495167Y381500D01*
X494667Y381167D01*
X494000Y381000D01*
X493417Y381083D01*
X492833Y381333D01*
X492500Y381667D01*
G01X498350Y383250D02*
X501017D01*
X500767Y383833D01*
X500350Y384167D01*
X499767Y384333D01*
X499183Y384250D01*
X498683Y384000D01*
X498350Y383417D01*
X498183Y382917D01*
Y382417D01*
X498350Y381917D01*
X498767Y381417D01*
X499267Y381083D01*
X499850Y381000D01*
X500433Y381167D01*
X501017Y381667D01*
G01X506533Y383917D02*
X505950Y384250D01*
X505450Y384333D01*
X504783Y384167D01*
X504283Y383833D01*
X503950Y383250D01*
X503867Y382667D01*
X503950Y382083D01*
X504283Y381583D01*
X504783Y381167D01*
X505450Y381000D01*
X506033Y381167D01*
X506533Y381500D01*
G01X510800Y384333D02*
Y381000D01*
G01Y385667D02*
X510633Y385750D01*
Y385917D01*
X510800Y386000D01*
X510967Y385917D01*
Y385750D01*
X510800Y385667D01*
G01X515900Y381000D02*
Y385250D01*
X516067Y385667D01*
X516400Y385917D01*
X516900Y386000D01*
X517400Y385833D01*
X517650Y385417D01*
G01X516650Y384000D02*
X514983D01*
G01X522000Y384333D02*
Y381000D01*
G01Y385667D02*
X521833Y385750D01*
Y385917D01*
X522000Y386000D01*
X522167Y385917D01*
Y385750D01*
X522000Y385667D01*
G01X526350Y383250D02*
X529017D01*
X528767Y383833D01*
X528350Y384167D01*
X527767Y384333D01*
X527183Y384250D01*
X526683Y384000D01*
X526350Y383417D01*
X526183Y382917D01*
Y382417D01*
X526350Y381917D01*
X526767Y381417D01*
X527267Y381083D01*
X527850Y381000D01*
X528433Y381167D01*
X529017Y381667D01*
G01X534700Y386000D02*
Y381000D01*
G01Y381750D02*
X534367Y381333D01*
X533867Y381083D01*
X533283Y381000D01*
X532617Y381167D01*
X532117Y381583D01*
X531783Y382083D01*
X531700Y382667D01*
X531783Y383250D01*
X532117Y383750D01*
X532617Y384167D01*
X533283Y384333D01*
X533867Y384250D01*
X534283Y384083D01*
X534700Y383750D01*
G01X544400Y381000D02*
X543900Y381083D01*
X543400Y381417D01*
X543067Y382000D01*
X542900Y382667D01*
X543067Y383333D01*
X543400Y383917D01*
X543900Y384250D01*
X544400Y384333D01*
X544900Y384250D01*
X545400Y383917D01*
X545733Y383333D01*
X545817Y382667D01*
X545733Y382000D01*
X545400Y381417D01*
X544900Y381083D01*
X544400Y381000D01*
G01X548583D02*
Y384333D01*
G01Y383500D02*
X548917Y383917D01*
X549417Y384250D01*
X550083Y384333D01*
X550667Y384250D01*
X551167Y383917D01*
X551417Y383333D01*
Y381000D01*
G01X561200Y386000D02*
Y381000D01*
G01X560033Y384333D02*
X562367D01*
G01X565383Y381000D02*
Y386000D01*
G01Y383583D02*
X565800Y384000D01*
X566217Y384250D01*
X566883Y384333D01*
X567383Y384250D01*
X567967Y383917D01*
X568217Y383417D01*
Y381000D01*
G01X571150Y383250D02*
X573817D01*
X573567Y383833D01*
X573150Y384167D01*
X572567Y384333D01*
X571983Y384250D01*
X571483Y384000D01*
X571150Y383417D01*
X570983Y382917D01*
Y382417D01*
X571150Y381917D01*
X571567Y381417D01*
X572067Y381083D01*
X572650Y381000D01*
X573233Y381167D01*
X573817Y381667D01*
G01X268250Y391500D02*
Y396500D01*
G01X271750D02*
Y391500D01*
G01Y394000D02*
X268250D01*
G01X275600Y391500D02*
X275100Y391583D01*
X274600Y391917D01*
X274267Y392500D01*
X274100Y393167D01*
X274267Y393833D01*
X274600Y394417D01*
X275100Y394750D01*
X275600Y394833D01*
X276100Y394750D01*
X276600Y394417D01*
X276933Y393833D01*
X277017Y393167D01*
X276933Y392500D01*
X276600Y391917D01*
X276100Y391583D01*
X275600Y391500D01*
G01X279117Y394833D02*
X280117Y391500D01*
X281200Y394833D01*
X282283Y391500D01*
X283283Y394833D01*
G01X285550Y393750D02*
X288217D01*
X287967Y394333D01*
X287550Y394667D01*
X286967Y394833D01*
X286383Y394750D01*
X285883Y394500D01*
X285550Y393917D01*
X285383Y393417D01*
Y392917D01*
X285550Y392417D01*
X285967Y391917D01*
X286467Y391583D01*
X287050Y391500D01*
X287633Y391667D01*
X288217Y392167D01*
G01X290900Y394833D02*
X292400Y391500D01*
X293900Y394833D01*
G01X296750Y393750D02*
X299417D01*
X299167Y394333D01*
X298750Y394667D01*
X298167Y394833D01*
X297583Y394750D01*
X297083Y394500D01*
X296750Y393917D01*
X296583Y393417D01*
Y392917D01*
X296750Y392417D01*
X297167Y391917D01*
X297667Y391583D01*
X298250Y391500D01*
X298833Y391667D01*
X299417Y392167D01*
G01X302433Y391500D02*
Y394833D01*
G01Y394167D02*
X302850Y394500D01*
X303267Y394750D01*
X303850Y394833D01*
X304267Y394750D01*
X304767Y394500D01*
G01X309033Y390583D02*
X309367Y391667D01*
G01X314800Y396500D02*
Y391500D01*
G01X313633Y394833D02*
X315967D01*
G01X318983Y391500D02*
Y396500D01*
G01Y394083D02*
X319400Y394500D01*
X319817Y394750D01*
X320483Y394833D01*
X320983Y394750D01*
X321567Y394417D01*
X321817Y393917D01*
Y391500D01*
G01X324750Y393750D02*
X327417D01*
X327167Y394333D01*
X326750Y394667D01*
X326167Y394833D01*
X325583Y394750D01*
X325083Y394500D01*
X324750Y393917D01*
X324583Y393417D01*
Y392917D01*
X324750Y392417D01*
X325167Y391917D01*
X325667Y391583D01*
X326250Y391500D01*
X326833Y391667D01*
X327417Y392167D01*
G01X337200Y396500D02*
Y391500D01*
G01X336033Y394833D02*
X338367D01*
G01X344300Y391500D02*
Y394833D01*
G01Y394250D02*
X343967Y394583D01*
X343467Y394750D01*
X342883Y394833D01*
X342300Y394667D01*
X341800Y394333D01*
X341467Y393833D01*
X341300Y393167D01*
X341467Y392500D01*
X341800Y392000D01*
X342300Y391667D01*
X342883Y391500D01*
X343467Y391583D01*
X343967Y391833D01*
X344300Y392167D01*
G01X346983Y391500D02*
Y394833D01*
G01Y394000D02*
X347317Y394417D01*
X347817Y394750D01*
X348483Y394833D01*
X349067Y394750D01*
X349567Y394417D01*
X349817Y393833D01*
Y391500D01*
G01X352833Y390250D02*
X353417Y389917D01*
X354083Y389833D01*
X354667Y389917D01*
X355167Y390333D01*
X355500Y390917D01*
Y394833D01*
G01Y394167D02*
X355167Y394500D01*
X354667Y394750D01*
X354083Y394833D01*
X353417Y394667D01*
X353000Y394333D01*
X352667Y393750D01*
X352500Y393167D01*
X352583Y392667D01*
X352917Y392083D01*
X353417Y391667D01*
X354083Y391500D01*
X354583Y391583D01*
X355167Y391917D01*
X355500Y392250D01*
G01X358350Y393750D02*
X361017D01*
X360767Y394333D01*
X360350Y394667D01*
X359767Y394833D01*
X359183Y394750D01*
X358683Y394500D01*
X358350Y393917D01*
X358183Y393417D01*
Y392917D01*
X358350Y392417D01*
X358767Y391917D01*
X359267Y391583D01*
X359850Y391500D01*
X360433Y391667D01*
X361017Y392167D01*
G01X363783Y391500D02*
Y394833D01*
G01Y394000D02*
X364117Y394417D01*
X364617Y394750D01*
X365283Y394833D01*
X365867Y394750D01*
X366367Y394417D01*
X366617Y393833D01*
Y391500D01*
G01X372133Y394417D02*
X371550Y394750D01*
X371050Y394833D01*
X370383Y394667D01*
X369883Y394333D01*
X369550Y393750D01*
X369467Y393167D01*
X369550Y392583D01*
X369883Y392083D01*
X370383Y391667D01*
X371050Y391500D01*
X371633Y391667D01*
X372133Y392000D01*
G01X374650Y390000D02*
X375150Y389833D01*
X375817Y390000D01*
X376233Y390333D01*
X376567Y390750D01*
X377067Y392083D01*
X378150Y394833D01*
G01X375483D02*
X377067Y392083D01*
G01X386350D02*
X386767Y391750D01*
X387350Y391500D01*
X387850D01*
X388350Y391667D01*
X388683Y391917D01*
X388850Y392250D01*
X388767Y392750D01*
X388433Y393000D01*
X386933Y393500D01*
X386600Y394083D01*
X386767Y394500D01*
X387100Y394750D01*
X387600Y394833D01*
X388100Y394750D01*
X388600Y394500D01*
G01X391783Y391500D02*
Y396500D01*
G01Y394083D02*
X392200Y394500D01*
X392617Y394750D01*
X393283Y394833D01*
X393783Y394750D01*
X394367Y394417D01*
X394617Y393917D01*
Y391500D01*
G01X398800D02*
X398300Y391583D01*
X397800Y391917D01*
X397467Y392500D01*
X397300Y393167D01*
X397467Y393833D01*
X397800Y394417D01*
X398300Y394750D01*
X398800Y394833D01*
X399300Y394750D01*
X399800Y394417D01*
X400133Y393833D01*
X400217Y393167D01*
X400133Y392500D01*
X399800Y391917D01*
X399300Y391583D01*
X398800Y391500D01*
G01X402983Y394833D02*
Y392500D01*
X403317Y391917D01*
X403817Y391583D01*
X404400Y391500D01*
X404983Y391583D01*
X405483Y391917D01*
X405817Y392500D01*
G01Y391500D02*
Y394833D01*
G01X410000Y391500D02*
Y396500D01*
G01X417100D02*
Y391500D01*
G01Y392250D02*
X416767Y391833D01*
X416267Y391583D01*
X415683Y391500D01*
X415017Y391667D01*
X414517Y392083D01*
X414183Y392583D01*
X414100Y393167D01*
X414183Y393750D01*
X414517Y394250D01*
X415017Y394667D01*
X415683Y394833D01*
X416267Y394750D01*
X416683Y394583D01*
X417100Y394250D01*
G01X425383Y391500D02*
Y394833D01*
G01Y394000D02*
X425717Y394417D01*
X426217Y394750D01*
X426883Y394833D01*
X427467Y394750D01*
X427967Y394417D01*
X428217Y393833D01*
Y391500D01*
G01X432400D02*
X431900Y391583D01*
X431400Y391917D01*
X431067Y392500D01*
X430900Y393167D01*
X431067Y393833D01*
X431400Y394417D01*
X431900Y394750D01*
X432400Y394833D01*
X432900Y394750D01*
X433400Y394417D01*
X433733Y393833D01*
X433817Y393167D01*
X433733Y392500D01*
X433400Y391917D01*
X432900Y391583D01*
X432400Y391500D01*
G01X438000Y396500D02*
Y391500D01*
G01X436833Y394833D02*
X439167D01*
G01X448033Y391500D02*
Y394833D01*
G01Y394167D02*
X448450Y394500D01*
X448867Y394750D01*
X449450Y394833D01*
X449867Y394750D01*
X450367Y394500D01*
G01X453550Y393750D02*
X456217D01*
X455967Y394333D01*
X455550Y394667D01*
X454967Y394833D01*
X454383Y394750D01*
X453883Y394500D01*
X453550Y393917D01*
X453383Y393417D01*
Y392917D01*
X453550Y392417D01*
X453967Y391917D01*
X454467Y391583D01*
X455050Y391500D01*
X455633Y391667D01*
X456217Y392167D01*
G01X461900Y396500D02*
Y391500D01*
G01Y392250D02*
X461567Y391833D01*
X461067Y391583D01*
X460483Y391500D01*
X459817Y391667D01*
X459317Y392083D01*
X458983Y392583D01*
X458900Y393167D01*
X458983Y393750D01*
X459317Y394250D01*
X459817Y394667D01*
X460483Y394833D01*
X461067Y394750D01*
X461483Y394583D01*
X461900Y394250D01*
G01X464583Y394833D02*
Y392500D01*
X464917Y391917D01*
X465417Y391583D01*
X466000Y391500D01*
X466583Y391583D01*
X467083Y391917D01*
X467417Y392500D01*
G01Y391500D02*
Y394833D01*
G01X472933Y394417D02*
X472350Y394750D01*
X471850Y394833D01*
X471183Y394667D01*
X470683Y394333D01*
X470350Y393750D01*
X470267Y393167D01*
X470350Y392583D01*
X470683Y392083D01*
X471183Y391667D01*
X471850Y391500D01*
X472433Y391667D01*
X472933Y392000D01*
G01X475950Y393750D02*
X478617D01*
X478367Y394333D01*
X477950Y394667D01*
X477367Y394833D01*
X476783Y394750D01*
X476283Y394500D01*
X475950Y393917D01*
X475783Y393417D01*
Y392917D01*
X475950Y392417D01*
X476367Y391917D01*
X476867Y391583D01*
X477450Y391500D01*
X478033Y391667D01*
X478617Y392167D01*
G01X488400Y396500D02*
Y391500D01*
G01X487233Y394833D02*
X489567D01*
G01X492583Y391500D02*
Y396500D01*
G01Y394083D02*
X493000Y394500D01*
X493417Y394750D01*
X494083Y394833D01*
X494583Y394750D01*
X495167Y394417D01*
X495417Y393917D01*
Y391500D01*
G01X498350Y393750D02*
X501017D01*
X500767Y394333D01*
X500350Y394667D01*
X499767Y394833D01*
X499183Y394750D01*
X498683Y394500D01*
X498350Y393917D01*
X498183Y393417D01*
Y392917D01*
X498350Y392417D01*
X498767Y391917D01*
X499267Y391583D01*
X499850Y391500D01*
X500433Y391667D01*
X501017Y392167D01*
G01X510800Y391500D02*
Y396500D01*
G01X517900Y391500D02*
Y394833D01*
G01Y394250D02*
X517567Y394583D01*
X517067Y394750D01*
X516483Y394833D01*
X515900Y394667D01*
X515400Y394333D01*
X515067Y393833D01*
X514900Y393167D01*
X515067Y392500D01*
X515400Y392000D01*
X515900Y391667D01*
X516483Y391500D01*
X517067Y391583D01*
X517567Y391833D01*
X517900Y392167D01*
G01X520583Y391500D02*
Y394833D01*
G01Y394000D02*
X520917Y394417D01*
X521417Y394750D01*
X522083Y394833D01*
X522667Y394750D01*
X523167Y394417D01*
X523417Y393833D01*
Y391500D01*
G01X529100Y396500D02*
Y391500D01*
G01Y392250D02*
X528767Y391833D01*
X528267Y391583D01*
X527683Y391500D01*
X527017Y391667D01*
X526517Y392083D01*
X526183Y392583D01*
X526100Y393167D01*
X526183Y393750D01*
X526517Y394250D01*
X527017Y394667D01*
X527683Y394833D01*
X528267Y394750D01*
X528683Y394583D01*
X529100Y394250D01*
G01X531700Y391333D02*
X534700Y396500D01*
G01X540133Y394417D02*
X539550Y394750D01*
X539050Y394833D01*
X538383Y394667D01*
X537883Y394333D01*
X537550Y393750D01*
X537467Y393167D01*
X537550Y392583D01*
X537883Y392083D01*
X538383Y391667D01*
X539050Y391500D01*
X539633Y391667D01*
X540133Y392000D01*
G01X544400Y391500D02*
X543900Y391583D01*
X543400Y391917D01*
X543067Y392500D01*
X542900Y393167D01*
X543067Y393833D01*
X543400Y394417D01*
X543900Y394750D01*
X544400Y394833D01*
X544900Y394750D01*
X545400Y394417D01*
X545733Y393833D01*
X545817Y393167D01*
X545733Y392500D01*
X545400Y391917D01*
X544900Y391583D01*
X544400Y391500D01*
G01X548583D02*
Y394833D01*
G01Y394000D02*
X548917Y394417D01*
X549417Y394750D01*
X550083Y394833D01*
X550667Y394750D01*
X551167Y394417D01*
X551417Y393833D01*
Y391500D01*
G01X557100Y396500D02*
Y391500D01*
G01Y392250D02*
X556767Y391833D01*
X556267Y391583D01*
X555683Y391500D01*
X555017Y391667D01*
X554517Y392083D01*
X554183Y392583D01*
X554100Y393167D01*
X554183Y393750D01*
X554517Y394250D01*
X555017Y394667D01*
X555683Y394833D01*
X556267Y394750D01*
X556683Y394583D01*
X557100Y394250D01*
G01X559783Y394833D02*
Y392500D01*
X560117Y391917D01*
X560617Y391583D01*
X561200Y391500D01*
X561783Y391583D01*
X562283Y391917D01*
X562617Y392500D01*
G01Y391500D02*
Y394833D01*
G01X568133Y394417D02*
X567550Y394750D01*
X567050Y394833D01*
X566383Y394667D01*
X565883Y394333D01*
X565550Y393750D01*
X565467Y393167D01*
X565550Y392583D01*
X565883Y392083D01*
X566383Y391667D01*
X567050Y391500D01*
X567633Y391667D01*
X568133Y392000D01*
G01X572400Y396500D02*
Y391500D01*
G01X571233Y394833D02*
X573567D01*
G01X578000Y391500D02*
X577500Y391583D01*
X577000Y391917D01*
X576667Y392500D01*
X576500Y393167D01*
X576667Y393833D01*
X577000Y394417D01*
X577500Y394750D01*
X578000Y394833D01*
X578500Y394750D01*
X579000Y394417D01*
X579333Y393833D01*
X579417Y393167D01*
X579333Y392500D01*
X579000Y391917D01*
X578500Y391583D01*
X578000Y391500D01*
G01X582433D02*
Y394833D01*
G01Y394167D02*
X582850Y394500D01*
X583267Y394750D01*
X583850Y394833D01*
X584267Y394750D01*
X584767Y394500D01*
G01X271500Y402000D02*
Y405333D01*
G01Y404750D02*
X271167Y405083D01*
X270667Y405250D01*
X270083Y405333D01*
X269500Y405167D01*
X269000Y404833D01*
X268667Y404333D01*
X268500Y403667D01*
X268667Y403000D01*
X269000Y402500D01*
X269500Y402167D01*
X270083Y402000D01*
X270667Y402083D01*
X271167Y402333D01*
X271500Y402667D01*
G01X276933Y404917D02*
X276350Y405250D01*
X275850Y405333D01*
X275183Y405167D01*
X274683Y404833D01*
X274350Y404250D01*
X274267Y403667D01*
X274350Y403083D01*
X274683Y402583D01*
X275183Y402167D01*
X275850Y402000D01*
X276433Y402167D01*
X276933Y402500D01*
G01X282533Y404917D02*
X281950Y405250D01*
X281450Y405333D01*
X280783Y405167D01*
X280283Y404833D01*
X279950Y404250D01*
X279867Y403667D01*
X279950Y403083D01*
X280283Y402583D01*
X280783Y402167D01*
X281450Y402000D01*
X282033Y402167D01*
X282533Y402500D01*
G01X285550Y404250D02*
X288217D01*
X287967Y404833D01*
X287550Y405167D01*
X286967Y405333D01*
X286383Y405250D01*
X285883Y405000D01*
X285550Y404417D01*
X285383Y403917D01*
Y403417D01*
X285550Y402917D01*
X285967Y402417D01*
X286467Y402083D01*
X287050Y402000D01*
X287633Y402167D01*
X288217Y402667D01*
G01X290900Y400333D02*
Y405333D01*
G01Y404583D02*
X291317Y405000D01*
X291733Y405250D01*
X292400Y405333D01*
X292983Y405250D01*
X293567Y404833D01*
X293817Y404250D01*
X293900Y403667D01*
X293817Y403083D01*
X293567Y402500D01*
X293067Y402167D01*
X292400Y402000D01*
X291817Y402083D01*
X291233Y402333D01*
X290900Y402667D01*
G01X298000Y407000D02*
Y402000D01*
G01X296833Y405333D02*
X299167D01*
G01X305100Y402000D02*
Y405333D01*
G01Y404750D02*
X304767Y405083D01*
X304267Y405250D01*
X303683Y405333D01*
X303100Y405167D01*
X302600Y404833D01*
X302267Y404333D01*
X302100Y403667D01*
X302267Y403000D01*
X302600Y402500D01*
X303100Y402167D01*
X303683Y402000D01*
X304267Y402083D01*
X304767Y402333D01*
X305100Y402667D01*
G01X307700Y402000D02*
Y407000D01*
G01Y404500D02*
X308117Y405000D01*
X308617Y405250D01*
X309117Y405333D01*
X309867Y405167D01*
X310367Y404833D01*
X310700Y404250D01*
Y403583D01*
X310533Y402917D01*
X310200Y402417D01*
X309617Y402083D01*
X309117Y402000D01*
X308617Y402083D01*
X308117Y402333D01*
X307700Y402750D01*
G01X314800Y402000D02*
Y407000D01*
G01X319150Y404250D02*
X321817D01*
X321567Y404833D01*
X321150Y405167D01*
X320567Y405333D01*
X319983Y405250D01*
X319483Y405000D01*
X319150Y404417D01*
X318983Y403917D01*
Y403417D01*
X319150Y402917D01*
X319567Y402417D01*
X320067Y402083D01*
X320650Y402000D01*
X321233Y402167D01*
X321817Y402667D01*
G01X326000Y401833D02*
X325833Y401917D01*
Y402083D01*
X326000Y402167D01*
X326167Y402083D01*
Y401917D01*
X326000Y401833D01*
G01X270000Y417500D02*
Y412500D01*
G01X268083Y417500D02*
X271917D01*
G01X274183Y412500D02*
Y417500D01*
G01Y415083D02*
X274600Y415500D01*
X275017Y415750D01*
X275683Y415833D01*
X276183Y415750D01*
X276767Y415417D01*
X277017Y414917D01*
Y412500D01*
G01X279950Y414750D02*
X282617D01*
X282367Y415333D01*
X281950Y415667D01*
X281367Y415833D01*
X280783Y415750D01*
X280283Y415500D01*
X279950Y414917D01*
X279783Y414417D01*
Y413917D01*
X279950Y413417D01*
X280367Y412917D01*
X280867Y412583D01*
X281450Y412500D01*
X282033Y412667D01*
X282617Y413167D01*
G01X290900Y412500D02*
Y417500D01*
G01Y415000D02*
X291317Y415500D01*
X291817Y415750D01*
X292317Y415833D01*
X293067Y415667D01*
X293567Y415333D01*
X293900Y414750D01*
Y414083D01*
X293733Y413417D01*
X293400Y412917D01*
X292817Y412583D01*
X292317Y412500D01*
X291817Y412583D01*
X291317Y412833D01*
X290900Y413250D01*
G01X296833Y412500D02*
Y415833D01*
G01Y415167D02*
X297250Y415500D01*
X297667Y415750D01*
X298250Y415833D01*
X298667Y415750D01*
X299167Y415500D01*
G01X302350Y414750D02*
X305017D01*
X304767Y415333D01*
X304350Y415667D01*
X303767Y415833D01*
X303183Y415750D01*
X302683Y415500D01*
X302350Y414917D01*
X302183Y414417D01*
Y413917D01*
X302350Y413417D01*
X302767Y412917D01*
X303267Y412583D01*
X303850Y412500D01*
X304433Y412667D01*
X305017Y413167D01*
G01X310700Y412500D02*
Y415833D01*
G01Y415250D02*
X310367Y415583D01*
X309867Y415750D01*
X309283Y415833D01*
X308700Y415667D01*
X308200Y415333D01*
X307867Y414833D01*
X307700Y414167D01*
X307867Y413500D01*
X308200Y413000D01*
X308700Y412667D01*
X309283Y412500D01*
X309867Y412583D01*
X310367Y412833D01*
X310700Y413167D01*
G01X313383Y412500D02*
Y417500D01*
G01X316050Y415833D02*
X313383Y413917D01*
G01X314467Y414667D02*
X316217Y412500D01*
G01X320400D02*
X319900Y412583D01*
X319400Y412917D01*
X319067Y413500D01*
X318900Y414167D01*
X319067Y414833D01*
X319400Y415417D01*
X319900Y415750D01*
X320400Y415833D01*
X320900Y415750D01*
X321400Y415417D01*
X321733Y414833D01*
X321817Y414167D01*
X321733Y413500D01*
X321400Y412917D01*
X320900Y412583D01*
X320400Y412500D01*
G01X324583Y415833D02*
Y413500D01*
X324917Y412917D01*
X325417Y412583D01*
X326000Y412500D01*
X326583Y412583D01*
X327083Y412917D01*
X327417Y413500D01*
G01Y412500D02*
Y415833D01*
G01X331600Y417500D02*
Y412500D01*
G01X330433Y415833D02*
X332767D01*
G01X342800D02*
Y412500D01*
G01Y417167D02*
X342633Y417250D01*
Y417417D01*
X342800Y417500D01*
X342967Y417417D01*
Y417250D01*
X342800Y417167D01*
G01X347150Y413083D02*
X347567Y412750D01*
X348150Y412500D01*
X348650D01*
X349150Y412667D01*
X349483Y412917D01*
X349650Y413250D01*
X349567Y413750D01*
X349233Y414000D01*
X347733Y414500D01*
X347400Y415083D01*
X347567Y415500D01*
X347900Y415750D01*
X348400Y415833D01*
X348900Y415750D01*
X349400Y415500D01*
G01X358183Y412500D02*
Y415833D01*
G01Y415000D02*
X358517Y415417D01*
X359017Y415750D01*
X359683Y415833D01*
X360267Y415750D01*
X360767Y415417D01*
X361017Y414833D01*
Y412500D01*
G01X365200D02*
X364700Y412583D01*
X364200Y412917D01*
X363867Y413500D01*
X363700Y414167D01*
X363867Y414833D01*
X364200Y415417D01*
X364700Y415750D01*
X365200Y415833D01*
X365700Y415750D01*
X366200Y415417D01*
X366533Y414833D01*
X366617Y414167D01*
X366533Y413500D01*
X366200Y412917D01*
X365700Y412583D01*
X365200Y412500D01*
G01X370800Y417500D02*
Y412500D01*
G01X369633Y415833D02*
X371967D01*
G01X383500Y412500D02*
Y415833D01*
G01Y415250D02*
X383167Y415583D01*
X382667Y415750D01*
X382083Y415833D01*
X381500Y415667D01*
X381000Y415333D01*
X380667Y414833D01*
X380500Y414167D01*
X380667Y413500D01*
X381000Y413000D01*
X381500Y412667D01*
X382083Y412500D01*
X382667Y412583D01*
X383167Y412833D01*
X383500Y413167D01*
G01X387600Y412500D02*
Y417500D01*
G01X393200Y412500D02*
Y417500D01*
G01X398800Y412500D02*
X398300Y412583D01*
X397800Y412917D01*
X397467Y413500D01*
X397300Y414167D01*
X397467Y414833D01*
X397800Y415417D01*
X398300Y415750D01*
X398800Y415833D01*
X399300Y415750D01*
X399800Y415417D01*
X400133Y414833D01*
X400217Y414167D01*
X400133Y413500D01*
X399800Y412917D01*
X399300Y412583D01*
X398800Y412500D01*
G01X402317Y415833D02*
X403317Y412500D01*
X404400Y415833D01*
X405483Y412500D01*
X406483Y415833D01*
G01X408750Y414750D02*
X411417D01*
X411167Y415333D01*
X410750Y415667D01*
X410167Y415833D01*
X409583Y415750D01*
X409083Y415500D01*
X408750Y414917D01*
X408583Y414417D01*
Y413917D01*
X408750Y413417D01*
X409167Y412917D01*
X409667Y412583D01*
X410250Y412500D01*
X410833Y412667D01*
X411417Y413167D01*
G01X417100Y417500D02*
Y412500D01*
G01Y413250D02*
X416767Y412833D01*
X416267Y412583D01*
X415683Y412500D01*
X415017Y412667D01*
X414517Y413083D01*
X414183Y413583D01*
X414100Y414167D01*
X414183Y414750D01*
X414517Y415250D01*
X415017Y415667D01*
X415683Y415833D01*
X416267Y415750D01*
X416683Y415583D01*
X417100Y415250D01*
G01X421033Y411583D02*
X421367Y412667D01*
G01X436500Y412500D02*
Y417500D01*
G01Y415000D02*
X436917Y415500D01*
X437417Y415750D01*
X437917Y415833D01*
X438667Y415667D01*
X439167Y415333D01*
X439500Y414750D01*
Y414083D01*
X439333Y413417D01*
X439000Y412917D01*
X438417Y412583D01*
X437917Y412500D01*
X437417Y412583D01*
X436917Y412833D01*
X436500Y413250D01*
G01X442183Y415833D02*
Y413500D01*
X442517Y412917D01*
X443017Y412583D01*
X443600Y412500D01*
X444183Y412583D01*
X444683Y412917D01*
X445017Y413500D01*
G01Y412500D02*
Y415833D01*
G01X449200Y417500D02*
Y412500D01*
G01X448033Y415833D02*
X450367D01*
G01X461900Y412500D02*
Y415833D01*
G01Y415250D02*
X461567Y415583D01*
X461067Y415750D01*
X460483Y415833D01*
X459900Y415667D01*
X459400Y415333D01*
X459067Y414833D01*
X458900Y414167D01*
X459067Y413500D01*
X459400Y413000D01*
X459900Y412667D01*
X460483Y412500D01*
X461067Y412583D01*
X461567Y412833D01*
X461900Y413167D01*
G01X464583Y412500D02*
Y415833D01*
G01Y415000D02*
X464917Y415417D01*
X465417Y415750D01*
X466083Y415833D01*
X466667Y415750D01*
X467167Y415417D01*
X467417Y414833D01*
Y412500D01*
G01X470183D02*
Y415833D01*
G01Y415000D02*
X470517Y415417D01*
X471017Y415750D01*
X471683Y415833D01*
X472267Y415750D01*
X472767Y415417D01*
X473017Y414833D01*
Y412500D01*
G01X475783Y415833D02*
Y413500D01*
X476117Y412917D01*
X476617Y412583D01*
X477200Y412500D01*
X477783Y412583D01*
X478283Y412917D01*
X478617Y413500D01*
G01Y412500D02*
Y415833D01*
G01X484300Y412500D02*
Y415833D01*
G01Y415250D02*
X483967Y415583D01*
X483467Y415750D01*
X482883Y415833D01*
X482300Y415667D01*
X481800Y415333D01*
X481467Y414833D01*
X481300Y414167D01*
X481467Y413500D01*
X481800Y413000D01*
X482300Y412667D01*
X482883Y412500D01*
X483467Y412583D01*
X483967Y412833D01*
X484300Y413167D01*
G01X488400Y412500D02*
Y417500D01*
G01X498433Y412500D02*
Y415833D01*
G01Y415167D02*
X498850Y415500D01*
X499267Y415750D01*
X499850Y415833D01*
X500267Y415750D01*
X500767Y415500D01*
G01X505200Y415833D02*
Y412500D01*
G01Y417167D02*
X505033Y417250D01*
Y417417D01*
X505200Y417500D01*
X505367Y417417D01*
Y417250D01*
X505200Y417167D01*
G01X509383Y412500D02*
Y415833D01*
G01Y415000D02*
X509717Y415417D01*
X510217Y415750D01*
X510883Y415833D01*
X511467Y415750D01*
X511967Y415417D01*
X512217Y414833D01*
Y412500D01*
G01X515233Y411250D02*
X515817Y410917D01*
X516483Y410833D01*
X517067Y410917D01*
X517567Y411333D01*
X517900Y411917D01*
Y415833D01*
G01Y415167D02*
X517567Y415500D01*
X517067Y415750D01*
X516483Y415833D01*
X515817Y415667D01*
X515400Y415333D01*
X515067Y414750D01*
X514900Y414167D01*
X514983Y413667D01*
X515317Y413083D01*
X515817Y412667D01*
X516483Y412500D01*
X516983Y412583D01*
X517567Y412917D01*
X517900Y413250D01*
G01X527600Y417500D02*
Y412500D01*
G01X526433Y415833D02*
X528767D01*
G01X534700Y412500D02*
Y415833D01*
G01Y415250D02*
X534367Y415583D01*
X533867Y415750D01*
X533283Y415833D01*
X532700Y415667D01*
X532200Y415333D01*
X531867Y414833D01*
X531700Y414167D01*
X531867Y413500D01*
X532200Y413000D01*
X532700Y412667D01*
X533283Y412500D01*
X533867Y412583D01*
X534367Y412833D01*
X534700Y413167D01*
G01X537383Y412500D02*
Y415833D01*
G01Y415000D02*
X537717Y415417D01*
X538217Y415750D01*
X538883Y415833D01*
X539467Y415750D01*
X539967Y415417D01*
X540217Y414833D01*
Y412500D01*
G01X543233Y411250D02*
X543817Y410917D01*
X544483Y410833D01*
X545067Y410917D01*
X545567Y411333D01*
X545900Y411917D01*
Y415833D01*
G01Y415167D02*
X545567Y415500D01*
X545067Y415750D01*
X544483Y415833D01*
X543817Y415667D01*
X543400Y415333D01*
X543067Y414750D01*
X542900Y414167D01*
X542983Y413667D01*
X543317Y413083D01*
X543817Y412667D01*
X544483Y412500D01*
X544983Y412583D01*
X545567Y412917D01*
X545900Y413250D01*
G01X548750Y414750D02*
X551417D01*
X551167Y415333D01*
X550750Y415667D01*
X550167Y415833D01*
X549583Y415750D01*
X549083Y415500D01*
X548750Y414917D01*
X548583Y414417D01*
Y413917D01*
X548750Y413417D01*
X549167Y412917D01*
X549667Y412583D01*
X550250Y412500D01*
X550833Y412667D01*
X551417Y413167D01*
G01X554183Y412500D02*
Y415833D01*
G01Y415000D02*
X554517Y415417D01*
X555017Y415750D01*
X555683Y415833D01*
X556267Y415750D01*
X556767Y415417D01*
X557017Y414833D01*
Y412500D01*
G01X562533Y415417D02*
X561950Y415750D01*
X561450Y415833D01*
X560783Y415667D01*
X560283Y415333D01*
X559950Y414750D01*
X559867Y414167D01*
X559950Y413583D01*
X560283Y413083D01*
X560783Y412667D01*
X561450Y412500D01*
X562033Y412667D01*
X562533Y413000D01*
G01X565050Y411000D02*
X565550Y410833D01*
X566217Y411000D01*
X566633Y411333D01*
X566967Y411750D01*
X567467Y413083D01*
X568550Y415833D01*
G01X565883D02*
X567467Y413083D01*
G01X578000Y415833D02*
Y412500D01*
G01Y417167D02*
X577833Y417250D01*
Y417417D01*
X578000Y417500D01*
X578167Y417417D01*
Y417250D01*
X578000Y417167D01*
G01X582350Y413083D02*
X582767Y412750D01*
X583350Y412500D01*
X583850D01*
X584350Y412667D01*
X584683Y412917D01*
X584850Y413250D01*
X584767Y413750D01*
X584433Y414000D01*
X582933Y414500D01*
X582600Y415083D01*
X582767Y415500D01*
X583100Y415750D01*
X583600Y415833D01*
X584100Y415750D01*
X584600Y415500D01*
G01X273000Y437500D02*
Y432500D01*
G01Y433250D02*
X272667Y432833D01*
X272167Y432583D01*
X271583Y432500D01*
X270917Y432667D01*
X270417Y433083D01*
X270083Y433583D01*
X270000Y434167D01*
X270083Y434750D01*
X270417Y435250D01*
X270917Y435667D01*
X271583Y435833D01*
X272167Y435750D01*
X272583Y435583D01*
X273000Y435250D01*
G01X275850Y434750D02*
X278517D01*
X278267Y435333D01*
X277850Y435667D01*
X277267Y435833D01*
X276683Y435750D01*
X276183Y435500D01*
X275850Y434917D01*
X275683Y434417D01*
Y433917D01*
X275850Y433417D01*
X276267Y432917D01*
X276767Y432583D01*
X277350Y432500D01*
X277933Y432667D01*
X278517Y433167D01*
G01X281200Y430833D02*
Y435833D01*
G01Y435083D02*
X281617Y435500D01*
X282033Y435750D01*
X282700Y435833D01*
X283283Y435750D01*
X283867Y435333D01*
X284117Y434750D01*
X284200Y434167D01*
X284117Y433583D01*
X283867Y433000D01*
X283367Y432667D01*
X282700Y432500D01*
X282117Y432583D01*
X281533Y432833D01*
X281200Y433167D01*
G01X288300Y437500D02*
Y432500D01*
G01X287133Y435833D02*
X289467D01*
G01X292483Y432500D02*
Y437500D01*
G01Y435083D02*
X292900Y435500D01*
X293317Y435750D01*
X293983Y435833D01*
X294483Y435750D01*
X295067Y435417D01*
X295317Y434917D01*
Y432500D01*
G01X305100Y437500D02*
Y432500D01*
G01X303933Y435833D02*
X306267D01*
G01X310700Y432500D02*
X310200Y432583D01*
X309700Y432917D01*
X309367Y433500D01*
X309200Y434167D01*
X309367Y434833D01*
X309700Y435417D01*
X310200Y435750D01*
X310700Y435833D01*
X311200Y435750D01*
X311700Y435417D01*
X312033Y434833D01*
X312117Y434167D01*
X312033Y433500D01*
X311700Y432917D01*
X311200Y432583D01*
X310700Y432500D01*
G01X316300D02*
Y437500D01*
G01X320650Y434750D02*
X323317D01*
X323067Y435333D01*
X322650Y435667D01*
X322067Y435833D01*
X321483Y435750D01*
X320983Y435500D01*
X320650Y434917D01*
X320483Y434417D01*
Y433917D01*
X320650Y433417D01*
X321067Y432917D01*
X321567Y432583D01*
X322150Y432500D01*
X322733Y432667D01*
X323317Y433167D01*
G01X326333Y432500D02*
Y435833D01*
G01Y435167D02*
X326750Y435500D01*
X327167Y435750D01*
X327750Y435833D01*
X328167Y435750D01*
X328667Y435500D01*
G01X334600Y432500D02*
Y435833D01*
G01Y435250D02*
X334267Y435583D01*
X333767Y435750D01*
X333183Y435833D01*
X332600Y435667D01*
X332100Y435333D01*
X331767Y434833D01*
X331600Y434167D01*
X331767Y433500D01*
X332100Y433000D01*
X332600Y432667D01*
X333183Y432500D01*
X333767Y432583D01*
X334267Y432833D01*
X334600Y433167D01*
G01X337283Y432500D02*
Y435833D01*
G01Y435000D02*
X337617Y435417D01*
X338117Y435750D01*
X338783Y435833D01*
X339367Y435750D01*
X339867Y435417D01*
X340117Y434833D01*
Y432500D01*
G01X345633Y435417D02*
X345050Y435750D01*
X344550Y435833D01*
X343883Y435667D01*
X343383Y435333D01*
X343050Y434750D01*
X342967Y434167D01*
X343050Y433583D01*
X343383Y433083D01*
X343883Y432667D01*
X344550Y432500D01*
X345133Y432667D01*
X345633Y433000D01*
G01X348650Y434750D02*
X351317D01*
X351067Y435333D01*
X350650Y435667D01*
X350067Y435833D01*
X349483Y435750D01*
X348983Y435500D01*
X348650Y434917D01*
X348483Y434417D01*
Y433917D01*
X348650Y433417D01*
X349067Y432917D01*
X349567Y432583D01*
X350150Y432500D01*
X350733Y432667D01*
X351317Y433167D01*
G01X270750Y453500D02*
Y458500D01*
G01X274250D02*
Y453500D01*
G01Y456000D02*
X270750D01*
G01X278100Y453500D02*
X277600Y453583D01*
X277100Y453917D01*
X276767Y454500D01*
X276600Y455167D01*
X276767Y455833D01*
X277100Y456417D01*
X277600Y456750D01*
X278100Y456833D01*
X278600Y456750D01*
X279100Y456417D01*
X279433Y455833D01*
X279517Y455167D01*
X279433Y454500D01*
X279100Y453917D01*
X278600Y453583D01*
X278100Y453500D01*
G01X283700D02*
Y458500D01*
G01X288050Y455750D02*
X290717D01*
X290467Y456333D01*
X290050Y456667D01*
X289467Y456833D01*
X288883Y456750D01*
X288383Y456500D01*
X288050Y455917D01*
X287883Y455417D01*
Y454917D01*
X288050Y454417D01*
X288467Y453917D01*
X288967Y453583D01*
X289550Y453500D01*
X290133Y453667D01*
X290717Y454167D01*
G01X298000Y458500D02*
X299167Y453500D01*
X300500Y458500D01*
X301833Y453500D01*
X303000Y458500D01*
G01X307600Y453500D02*
Y456833D01*
G01Y456250D02*
X307267Y456583D01*
X306767Y456750D01*
X306183Y456833D01*
X305600Y456667D01*
X305100Y456333D01*
X304767Y455833D01*
X304600Y455167D01*
X304767Y454500D01*
X305100Y454000D01*
X305600Y453667D01*
X306183Y453500D01*
X306767Y453583D01*
X307267Y453833D01*
X307600Y454167D01*
G01X311700Y453500D02*
Y458500D01*
G01X317300Y453500D02*
Y458500D01*
G01X326833Y453500D02*
Y458500D01*
X328917D01*
X329583Y458250D01*
X330000Y457917D01*
X330167Y457250D01*
X330000Y456583D01*
X329500Y456167D01*
X328917Y455917D01*
X326833D01*
G01X328917D02*
X330167Y453500D01*
G01X334100D02*
X333600Y453583D01*
X333100Y453917D01*
X332767Y454500D01*
X332600Y455167D01*
X332767Y455833D01*
X333100Y456417D01*
X333600Y456750D01*
X334100Y456833D01*
X334600Y456750D01*
X335100Y456417D01*
X335433Y455833D01*
X335517Y455167D01*
X335433Y454500D01*
X335100Y453917D01*
X334600Y453583D01*
X334100Y453500D01*
G01X338283Y456833D02*
Y454500D01*
X338617Y453917D01*
X339117Y453583D01*
X339700Y453500D01*
X340283Y453583D01*
X340783Y453917D01*
X341117Y454500D01*
G01Y453500D02*
Y456833D01*
G01X344133Y452250D02*
X344717Y451917D01*
X345383Y451833D01*
X345967Y451917D01*
X346467Y452333D01*
X346800Y452917D01*
Y456833D01*
G01Y456167D02*
X346467Y456500D01*
X345967Y456750D01*
X345383Y456833D01*
X344717Y456667D01*
X344300Y456333D01*
X343967Y455750D01*
X343800Y455167D01*
X343883Y454667D01*
X344217Y454083D01*
X344717Y453667D01*
X345383Y453500D01*
X345883Y453583D01*
X346467Y453917D01*
X346800Y454250D01*
G01X349483Y453500D02*
Y458500D01*
G01Y456083D02*
X349900Y456500D01*
X350317Y456750D01*
X350983Y456833D01*
X351483Y456750D01*
X352067Y456417D01*
X352317Y455917D01*
Y453500D01*
G01X355083D02*
Y456833D01*
G01Y456000D02*
X355417Y456417D01*
X355917Y456750D01*
X356583Y456833D01*
X357167Y456750D01*
X357667Y456417D01*
X357917Y455833D01*
Y453500D01*
G01X360850Y455750D02*
X363517D01*
X363267Y456333D01*
X362850Y456667D01*
X362267Y456833D01*
X361683Y456750D01*
X361183Y456500D01*
X360850Y455917D01*
X360683Y455417D01*
Y454917D01*
X360850Y454417D01*
X361267Y453917D01*
X361767Y453583D01*
X362350Y453500D01*
X362933Y453667D01*
X363517Y454167D01*
G01X366450Y454083D02*
X366867Y453750D01*
X367450Y453500D01*
X367950D01*
X368450Y453667D01*
X368783Y453917D01*
X368950Y454250D01*
X368867Y454750D01*
X368533Y455000D01*
X367033Y455500D01*
X366700Y456083D01*
X366867Y456500D01*
X367200Y456750D01*
X367700Y456833D01*
X368200Y456750D01*
X368700Y456500D01*
G01X372050Y454083D02*
X372467Y453750D01*
X373050Y453500D01*
X373550D01*
X374050Y453667D01*
X374383Y453917D01*
X374550Y454250D01*
X374467Y454750D01*
X374133Y455000D01*
X372633Y455500D01*
X372300Y456083D01*
X372467Y456500D01*
X372800Y456750D01*
X373300Y456833D01*
X373800Y456750D01*
X374300Y456500D01*
G01X272500Y470000D02*
X271833Y470083D01*
X271250Y470417D01*
X270750Y470917D01*
X270417Y471500D01*
X270250Y472167D01*
Y472833D01*
X270417Y473500D01*
X270750Y474083D01*
X271250Y474583D01*
X271833Y474917D01*
X272500Y475000D01*
X273167Y474917D01*
X273750Y474583D01*
X274250Y474083D01*
X274583Y473500D01*
X274750Y472833D01*
Y472167D01*
X274583Y471500D01*
X274250Y470917D01*
X273750Y470417D01*
X273167Y470083D01*
X272500Y470000D01*
G01X278100Y475000D02*
Y470000D01*
G01X276933Y473333D02*
X279267D01*
G01X282283Y470000D02*
Y475000D01*
G01Y472583D02*
X282700Y473000D01*
X283117Y473250D01*
X283783Y473333D01*
X284283Y473250D01*
X284867Y472917D01*
X285117Y472417D01*
Y470000D01*
G01X288050Y472250D02*
X290717D01*
X290467Y472833D01*
X290050Y473167D01*
X289467Y473333D01*
X288883Y473250D01*
X288383Y473000D01*
X288050Y472417D01*
X287883Y471917D01*
Y471417D01*
X288050Y470917D01*
X288467Y470417D01*
X288967Y470083D01*
X289550Y470000D01*
X290133Y470167D01*
X290717Y470667D01*
G01X293733Y470000D02*
Y473333D01*
G01Y472667D02*
X294150Y473000D01*
X294567Y473250D01*
X295150Y473333D01*
X295567Y473250D01*
X296067Y473000D01*
G01X299250Y470583D02*
X299667Y470250D01*
X300250Y470000D01*
X300750D01*
X301250Y470167D01*
X301583Y470417D01*
X301750Y470750D01*
X301667Y471250D01*
X301333Y471500D01*
X299833Y472000D01*
X299500Y472583D01*
X299667Y473000D01*
X300000Y473250D01*
X300500Y473333D01*
X301000Y473250D01*
X301500Y473000D01*
G01X311283Y468333D02*
X310450Y469167D01*
X310033Y470000D01*
Y473333D01*
X310450Y474167D01*
X311283Y475000D01*
G01X317300Y470000D02*
Y475000D01*
G01X322900Y473333D02*
Y470000D01*
G01Y474667D02*
X322733Y474750D01*
Y474917D01*
X322900Y475000D01*
X323067Y474917D01*
Y474750D01*
X322900Y474667D01*
G01X327083Y470000D02*
Y475000D01*
G01X329750Y473333D02*
X327083Y471417D01*
G01X328167Y472167D02*
X329917Y470000D01*
G01X332850Y472250D02*
X335517D01*
X335267Y472833D01*
X334850Y473167D01*
X334267Y473333D01*
X333683Y473250D01*
X333183Y473000D01*
X332850Y472417D01*
X332683Y471917D01*
Y471417D01*
X332850Y470917D01*
X333267Y470417D01*
X333767Y470083D01*
X334350Y470000D01*
X334933Y470167D01*
X335517Y470667D01*
G01X344050Y472250D02*
X346717D01*
X346467Y472833D01*
X346050Y473167D01*
X345467Y473333D01*
X344883Y473250D01*
X344383Y473000D01*
X344050Y472417D01*
X343883Y471917D01*
Y471417D01*
X344050Y470917D01*
X344467Y470417D01*
X344967Y470083D01*
X345550Y470000D01*
X346133Y470167D01*
X346717Y470667D01*
G01X350900Y470000D02*
Y475000D01*
G01X356500Y470000D02*
Y475000D01*
G01X362100Y473333D02*
Y470000D01*
G01Y474667D02*
X361933Y474750D01*
Y474917D01*
X362100Y475000D01*
X362267Y474917D01*
Y474750D01*
X362100Y474667D01*
G01X366200Y468333D02*
Y473333D01*
G01Y472583D02*
X366617Y473000D01*
X367033Y473250D01*
X367700Y473333D01*
X368283Y473250D01*
X368867Y472833D01*
X369117Y472250D01*
X369200Y471667D01*
X369117Y471083D01*
X368867Y470500D01*
X368367Y470167D01*
X367700Y470000D01*
X367117Y470083D01*
X366533Y470333D01*
X366200Y470667D01*
G01X372050Y470583D02*
X372467Y470250D01*
X373050Y470000D01*
X373550D01*
X374050Y470167D01*
X374383Y470417D01*
X374550Y470750D01*
X374467Y471250D01*
X374133Y471500D01*
X372633Y472000D01*
X372300Y472583D01*
X372467Y473000D01*
X372800Y473250D01*
X373300Y473333D01*
X373800Y473250D01*
X374300Y473000D01*
G01X377650Y472250D02*
X380317D01*
X380067Y472833D01*
X379650Y473167D01*
X379067Y473333D01*
X378483Y473250D01*
X377983Y473000D01*
X377650Y472417D01*
X377483Y471917D01*
Y471417D01*
X377650Y470917D01*
X378067Y470417D01*
X378567Y470083D01*
X379150Y470000D01*
X379733Y470167D01*
X380317Y470667D01*
G01X391600Y470000D02*
Y473333D01*
G01Y472750D02*
X391267Y473083D01*
X390767Y473250D01*
X390183Y473333D01*
X389600Y473167D01*
X389100Y472833D01*
X388767Y472333D01*
X388600Y471667D01*
X388767Y471000D01*
X389100Y470500D01*
X389600Y470167D01*
X390183Y470000D01*
X390767Y470083D01*
X391267Y470333D01*
X391600Y470667D01*
G01X394283Y470000D02*
Y473333D01*
G01Y472500D02*
X394617Y472917D01*
X395117Y473250D01*
X395783Y473333D01*
X396367Y473250D01*
X396867Y472917D01*
X397117Y472333D01*
Y470000D01*
G01X402800Y475000D02*
Y470000D01*
G01Y470750D02*
X402467Y470333D01*
X401967Y470083D01*
X401383Y470000D01*
X400717Y470167D01*
X400217Y470583D01*
X399883Y471083D01*
X399800Y471667D01*
X399883Y472250D01*
X400217Y472750D01*
X400717Y473167D01*
X401383Y473333D01*
X401967Y473250D01*
X402383Y473083D01*
X402800Y472750D01*
G01X412500Y470000D02*
X412000Y470083D01*
X411500Y470417D01*
X411167Y471000D01*
X411000Y471667D01*
X411167Y472333D01*
X411500Y472917D01*
X412000Y473250D01*
X412500Y473333D01*
X413000Y473250D01*
X413500Y472917D01*
X413833Y472333D01*
X413917Y471667D01*
X413833Y471000D01*
X413500Y470417D01*
X413000Y470083D01*
X412500Y470000D01*
G01X418100Y475000D02*
Y470000D01*
G01X416933Y473333D02*
X419267D01*
G01X422283Y470000D02*
Y475000D01*
G01Y472583D02*
X422700Y473000D01*
X423117Y473250D01*
X423783Y473333D01*
X424283Y473250D01*
X424867Y472917D01*
X425117Y472417D01*
Y470000D01*
G01X428050Y472250D02*
X430717D01*
X430467Y472833D01*
X430050Y473167D01*
X429467Y473333D01*
X428883Y473250D01*
X428383Y473000D01*
X428050Y472417D01*
X427883Y471917D01*
Y471417D01*
X428050Y470917D01*
X428467Y470417D01*
X428967Y470083D01*
X429550Y470000D01*
X430133Y470167D01*
X430717Y470667D01*
G01X433733Y470000D02*
Y473333D01*
G01Y472667D02*
X434150Y473000D01*
X434567Y473250D01*
X435150Y473333D01*
X435567Y473250D01*
X436067Y473000D01*
G01X439250Y470583D02*
X439667Y470250D01*
X440250Y470000D01*
X440750D01*
X441250Y470167D01*
X441583Y470417D01*
X441750Y470750D01*
X441667Y471250D01*
X441333Y471500D01*
X439833Y472000D01*
X439500Y472583D01*
X439667Y473000D01*
X440000Y473250D01*
X440500Y473333D01*
X441000Y473250D01*
X441500Y473000D01*
G01X446517Y468333D02*
X447350Y469167D01*
X447767Y470000D01*
Y473333D01*
X447350Y474167D01*
X446517Y475000D01*
G01X270833Y485000D02*
Y490000D01*
X272833D01*
X273500Y489750D01*
X274000Y489167D01*
X274167Y488500D01*
X274000Y487833D01*
X273583Y487333D01*
X272833Y487083D01*
X270833D01*
G01X278100Y490000D02*
Y485000D01*
G01X276183Y490000D02*
X280017D01*
G01X281950Y485000D02*
Y490000D01*
G01X285450D02*
Y485000D01*
G01Y487500D02*
X281950D01*
G01X287800Y484833D02*
X290800Y490000D01*
G01X292983Y485000D02*
Y490000D01*
X296817Y485000D01*
Y490000D01*
G01X298833Y485000D02*
Y490000D01*
X300833D01*
X301500Y489750D01*
X302000Y489167D01*
X302167Y488500D01*
X302000Y487833D01*
X301583Y487333D01*
X300833Y487083D01*
X298833D01*
G01X306100Y490000D02*
Y485000D01*
G01X304183Y490000D02*
X308017D01*
G01X309950Y485000D02*
Y490000D01*
G01X313450D02*
Y485000D01*
G01Y487500D02*
X309950D01*
G01X321233Y485000D02*
X324567Y486667D01*
X321233Y488333D01*
G01X327417Y485917D02*
X329583D01*
G01Y487417D02*
X327417D01*
G01X332267Y485750D02*
X332767Y485333D01*
X333350Y485083D01*
X334100Y485000D01*
X334850Y485167D01*
X335433Y485500D01*
X335850Y486083D01*
X335933Y486750D01*
X335767Y487417D01*
X335350Y487833D01*
X334767Y488167D01*
X334183Y488250D01*
X333600Y488167D01*
X332850Y487833D01*
X333100Y490000D01*
X335350D01*
G01X342800Y485000D02*
Y488333D01*
G01Y487417D02*
X343050Y487833D01*
X343467Y488167D01*
X344050Y488333D01*
X344633Y488167D01*
X345050Y487833D01*
X345300Y487417D01*
Y485000D01*
G01Y487417D02*
X345550Y487833D01*
X345967Y488167D01*
X346550Y488333D01*
X347133Y488167D01*
X347550Y487833D01*
X347800Y487333D01*
Y485000D01*
G01X348400D02*
Y488333D01*
G01Y487417D02*
X348650Y487833D01*
X349067Y488167D01*
X349650Y488333D01*
X350233Y488167D01*
X350650Y487833D01*
X350900Y487417D01*
Y485000D01*
G01Y487417D02*
X351150Y487833D01*
X351567Y488167D01*
X352150Y488333D01*
X352733Y488167D01*
X353150Y487833D01*
X353400Y487333D01*
Y485000D01*
G01X270583Y498500D02*
Y503500D01*
X274417Y498500D01*
Y503500D01*
G01X276433Y498500D02*
Y503500D01*
X278433D01*
X279100Y503250D01*
X279600Y502667D01*
X279767Y502000D01*
X279600Y501333D01*
X279183Y500833D01*
X278433Y500583D01*
X276433D01*
G01X283700Y503500D02*
Y498500D01*
G01X281783Y503500D02*
X285617D01*
G01X287550Y498500D02*
Y503500D01*
G01X291050D02*
Y498500D01*
G01Y501000D02*
X287550D01*
G01X298750Y499167D02*
X299417Y498750D01*
X300167Y498500D01*
X300833D01*
X301500Y498750D01*
X302000Y499167D01*
X302250Y499750D01*
X302083Y500333D01*
X301667Y500833D01*
X300917Y501167D01*
X299917Y501333D01*
X299333Y501667D01*
X299083Y502250D01*
X299250Y502833D01*
X299667Y503250D01*
X300250Y503500D01*
X300833D01*
X301417Y503333D01*
X301917Y502917D01*
G01X306100Y501833D02*
Y498500D01*
G01Y503167D02*
X305933Y503250D01*
Y503417D01*
X306100Y503500D01*
X306267Y503417D01*
Y503250D01*
X306100Y503167D01*
G01X310450Y501833D02*
X312950D01*
X310450Y498500D01*
X312950D01*
G01X316050Y500750D02*
X318717D01*
X318467Y501333D01*
X318050Y501667D01*
X317467Y501833D01*
X316883Y501750D01*
X316383Y501500D01*
X316050Y500917D01*
X315883Y500417D01*
Y499917D01*
X316050Y499417D01*
X316467Y498917D01*
X316967Y498583D01*
X317550Y498500D01*
X318133Y498667D01*
X318717Y499167D01*
G01X326667Y499500D02*
X327167Y498917D01*
X327833Y498583D01*
X328583Y498500D01*
X329250Y498583D01*
X329917Y499000D01*
X330333Y499500D01*
X330417Y500000D01*
X330250Y500583D01*
X329667Y501000D01*
X329083Y501167D01*
X328333D01*
G01X329083D02*
X329583Y501417D01*
X330000Y501833D01*
X330167Y502333D01*
X330000Y502833D01*
X329583Y503250D01*
X328833Y503500D01*
X328083Y503417D01*
X327333Y503083D01*
G01X334100Y498333D02*
X333933Y498417D01*
Y498583D01*
X334100Y498667D01*
X334267Y498583D01*
Y498417D01*
X334100Y498333D01*
G01X337867Y499250D02*
X338367Y498833D01*
X338950Y498583D01*
X339700Y498500D01*
X340450Y498667D01*
X341033Y499000D01*
X341450Y499583D01*
X341533Y500250D01*
X341367Y500917D01*
X340950Y501333D01*
X340367Y501667D01*
X339783Y501750D01*
X339200Y501667D01*
X338450Y501333D01*
X338700Y503500D01*
X340950D01*
G01X343467Y499250D02*
X343967Y498833D01*
X344550Y498583D01*
X345300Y498500D01*
X346050Y498667D01*
X346633Y499000D01*
X347050Y499583D01*
X347133Y500250D01*
X346967Y500917D01*
X346550Y501333D01*
X345967Y501667D01*
X345383Y501750D01*
X344800Y501667D01*
X344050Y501333D01*
X344300Y503500D01*
X346550D01*
G01X348400Y498500D02*
Y501833D01*
G01Y500917D02*
X348650Y501333D01*
X349067Y501667D01*
X349650Y501833D01*
X350233Y501667D01*
X350650Y501333D01*
X350900Y500917D01*
Y498500D01*
G01Y500917D02*
X351150Y501333D01*
X351567Y501667D01*
X352150Y501833D01*
X352733Y501667D01*
X353150Y501333D01*
X353400Y500833D01*
Y498500D01*
G01X354000D02*
Y501833D01*
G01Y500917D02*
X354250Y501333D01*
X354667Y501667D01*
X355250Y501833D01*
X355833Y501667D01*
X356250Y501333D01*
X356500Y500917D01*
Y498500D01*
G01Y500917D02*
X356750Y501333D01*
X357167Y501667D01*
X357750Y501833D01*
X358333Y501667D01*
X358750Y501333D01*
X359000Y500833D01*
Y498500D01*
G01X270583Y513500D02*
Y518500D01*
X274417Y513500D01*
Y518500D01*
G01X276433Y513500D02*
Y518500D01*
X278433D01*
X279100Y518250D01*
X279600Y517667D01*
X279767Y517000D01*
X279600Y516333D01*
X279183Y515833D01*
X278433Y515583D01*
X276433D01*
G01X283700Y518500D02*
Y513500D01*
G01X281783Y518500D02*
X285617D01*
G01X287550Y513500D02*
Y518500D01*
G01X291050D02*
Y513500D01*
G01Y516000D02*
X287550D01*
G01X298750Y514167D02*
X299417Y513750D01*
X300167Y513500D01*
X300833D01*
X301500Y513750D01*
X302000Y514167D01*
X302250Y514750D01*
X302083Y515333D01*
X301667Y515833D01*
X300917Y516167D01*
X299917Y516333D01*
X299333Y516667D01*
X299083Y517250D01*
X299250Y517833D01*
X299667Y518250D01*
X300250Y518500D01*
X300833D01*
X301417Y518333D01*
X301917Y517917D01*
G01X306100Y516833D02*
Y513500D01*
G01Y518167D02*
X305933Y518250D01*
Y518417D01*
X306100Y518500D01*
X306267Y518417D01*
Y518250D01*
X306100Y518167D01*
G01X310450Y516833D02*
X312950D01*
X310450Y513500D01*
X312950D01*
G01X316050Y515750D02*
X318717D01*
X318467Y516333D01*
X318050Y516667D01*
X317467Y516833D01*
X316883Y516750D01*
X316383Y516500D01*
X316050Y515917D01*
X315883Y515417D01*
Y514917D01*
X316050Y514417D01*
X316467Y513917D01*
X316967Y513583D01*
X317550Y513500D01*
X318133Y513667D01*
X318717Y514167D01*
G01X324567Y513500D02*
X321233Y515167D01*
X324567Y516833D01*
G01X332267Y514250D02*
X332767Y513833D01*
X333350Y513583D01*
X334100Y513500D01*
X334850Y513667D01*
X335433Y514000D01*
X335850Y514583D01*
X335933Y515250D01*
X335767Y515917D01*
X335350Y516333D01*
X334767Y516667D01*
X334183Y516750D01*
X333600Y516667D01*
X332850Y516333D01*
X333100Y518500D01*
X335350D01*
G01X337200Y513500D02*
Y516833D01*
G01Y515917D02*
X337450Y516333D01*
X337867Y516667D01*
X338450Y516833D01*
X339033Y516667D01*
X339450Y516333D01*
X339700Y515917D01*
Y513500D01*
G01Y515917D02*
X339950Y516333D01*
X340367Y516667D01*
X340950Y516833D01*
X341533Y516667D01*
X341950Y516333D01*
X342200Y515833D01*
Y513500D01*
G01X342800D02*
Y516833D01*
G01Y515917D02*
X343050Y516333D01*
X343467Y516667D01*
X344050Y516833D01*
X344633Y516667D01*
X345050Y516333D01*
X345300Y515917D01*
Y513500D01*
G01Y515917D02*
X345550Y516333D01*
X345967Y516667D01*
X346550Y516833D01*
X347133Y516667D01*
X347550Y516333D01*
X347800Y515833D01*
Y513500D01*
G01X270667Y535000D02*
Y531417D01*
X271000Y530667D01*
X271667Y530167D01*
X272500Y530000D01*
X273333Y530167D01*
X274000Y530667D01*
X274333Y531417D01*
Y535000D01*
G01X276683Y530000D02*
Y533333D01*
G01Y532500D02*
X277017Y532917D01*
X277517Y533250D01*
X278183Y533333D01*
X278767Y533250D01*
X279267Y532917D01*
X279517Y532333D01*
Y530000D01*
G01X282617Y531667D02*
X284783D01*
G01X287800Y528333D02*
Y533333D01*
G01Y532583D02*
X288217Y533000D01*
X288633Y533250D01*
X289300Y533333D01*
X289883Y533250D01*
X290467Y532833D01*
X290717Y532250D01*
X290800Y531667D01*
X290717Y531083D01*
X290467Y530500D01*
X289967Y530167D01*
X289300Y530000D01*
X288717Y530083D01*
X288133Y530333D01*
X287800Y530667D01*
G01X294900Y530000D02*
Y535000D01*
G01X299083Y533333D02*
Y531000D01*
X299417Y530417D01*
X299917Y530083D01*
X300500Y530000D01*
X301083Y530083D01*
X301583Y530417D01*
X301917Y531000D01*
G01Y530000D02*
Y533333D01*
G01X304933Y528750D02*
X305517Y528417D01*
X306183Y528333D01*
X306767Y528417D01*
X307267Y528833D01*
X307600Y529417D01*
Y533333D01*
G01Y532667D02*
X307267Y533000D01*
X306767Y533250D01*
X306183Y533333D01*
X305517Y533167D01*
X305100Y532833D01*
X304767Y532250D01*
X304600Y531667D01*
X304683Y531167D01*
X305017Y530583D01*
X305517Y530167D01*
X306183Y530000D01*
X306683Y530083D01*
X307267Y530417D01*
X307600Y530750D01*
G01X310533Y528750D02*
X311117Y528417D01*
X311783Y528333D01*
X312367Y528417D01*
X312867Y528833D01*
X313200Y529417D01*
Y533333D01*
G01Y532667D02*
X312867Y533000D01*
X312367Y533250D01*
X311783Y533333D01*
X311117Y533167D01*
X310700Y532833D01*
X310367Y532250D01*
X310200Y531667D01*
X310283Y531167D01*
X310617Y530583D01*
X311117Y530167D01*
X311783Y530000D01*
X312283Y530083D01*
X312867Y530417D01*
X313200Y530750D01*
G01X316050Y532250D02*
X318717D01*
X318467Y532833D01*
X318050Y533167D01*
X317467Y533333D01*
X316883Y533250D01*
X316383Y533000D01*
X316050Y532417D01*
X315883Y531917D01*
Y531417D01*
X316050Y530917D01*
X316467Y530417D01*
X316967Y530083D01*
X317550Y530000D01*
X318133Y530167D01*
X318717Y530667D01*
G01X324400Y535000D02*
Y530000D01*
G01Y530750D02*
X324067Y530333D01*
X323567Y530083D01*
X322983Y530000D01*
X322317Y530167D01*
X321817Y530583D01*
X321483Y531083D01*
X321400Y531667D01*
X321483Y532250D01*
X321817Y532750D01*
X322317Y533167D01*
X322983Y533333D01*
X323567Y533250D01*
X323983Y533083D01*
X324400Y532750D01*
G01X332433Y530000D02*
Y535000D01*
X334433D01*
X335100Y534750D01*
X335600Y534167D01*
X335767Y533500D01*
X335600Y532833D01*
X335183Y532333D01*
X334433Y532083D01*
X332433D01*
G01X339700Y535000D02*
Y530000D01*
G01X337783Y535000D02*
X341617D01*
G01X343550Y530000D02*
Y535000D01*
G01X347050D02*
Y530000D01*
G01Y532500D02*
X343550D01*
G01X356083Y528333D02*
X355250Y529167D01*
X354833Y530000D01*
Y533333D01*
X355250Y534167D01*
X356083Y535000D01*
G01X360350Y530000D02*
Y535000D01*
G01X363850D02*
Y530000D01*
G01Y532500D02*
X360350D01*
G01X367700Y530000D02*
X367200Y530083D01*
X366700Y530417D01*
X366367Y531000D01*
X366200Y531667D01*
X366367Y532333D01*
X366700Y532917D01*
X367200Y533250D01*
X367700Y533333D01*
X368200Y533250D01*
X368700Y532917D01*
X369033Y532333D01*
X369117Y531667D01*
X369033Y531000D01*
X368700Y530417D01*
X368200Y530083D01*
X367700Y530000D01*
G01X373300D02*
Y535000D01*
G01X377650Y532250D02*
X380317D01*
X380067Y532833D01*
X379650Y533167D01*
X379067Y533333D01*
X378483Y533250D01*
X377983Y533000D01*
X377650Y532417D01*
X377483Y531917D01*
Y531417D01*
X377650Y530917D01*
X378067Y530417D01*
X378567Y530083D01*
X379150Y530000D01*
X379733Y530167D01*
X380317Y530667D01*
G01X388350D02*
X389017Y530250D01*
X389767Y530000D01*
X390433D01*
X391100Y530250D01*
X391600Y530667D01*
X391850Y531250D01*
X391683Y531833D01*
X391267Y532333D01*
X390517Y532667D01*
X389517Y532833D01*
X388933Y533167D01*
X388683Y533750D01*
X388850Y534333D01*
X389267Y534750D01*
X389850Y535000D01*
X390433D01*
X391017Y534833D01*
X391517Y534417D01*
G01X395700Y533333D02*
Y530000D01*
G01Y534667D02*
X395533Y534750D01*
Y534917D01*
X395700Y535000D01*
X395867Y534917D01*
Y534750D01*
X395700Y534667D01*
G01X400050Y533333D02*
X402550D01*
X400050Y530000D01*
X402550D01*
G01X405650Y532250D02*
X408317D01*
X408067Y532833D01*
X407650Y533167D01*
X407067Y533333D01*
X406483Y533250D01*
X405983Y533000D01*
X405650Y532417D01*
X405483Y531917D01*
Y531417D01*
X405650Y530917D01*
X406067Y530417D01*
X406567Y530083D01*
X407150Y530000D01*
X407733Y530167D01*
X408317Y530667D01*
G01X414167Y530000D02*
X410833Y531667D01*
X414167Y533333D01*
G01X418100Y530000D02*
Y535000D01*
X417100Y534000D01*
G01Y530000D02*
X419100D01*
G01X422283Y530583D02*
X422867Y530167D01*
X423533Y530000D01*
X424200Y530167D01*
X424783Y530667D01*
X425200Y531417D01*
X425367Y532167D01*
Y533083D01*
X425200Y533833D01*
X424783Y534500D01*
X424283Y534833D01*
X423700Y535000D01*
X423033Y534833D01*
X422533Y534500D01*
X422200Y534000D01*
X422033Y533333D01*
X422200Y532750D01*
X422617Y532167D01*
X423117Y531833D01*
X423700Y531750D01*
X424367Y531917D01*
X424867Y532333D01*
X425367Y533083D01*
G01X429133Y530000D02*
X429300Y531083D01*
X429550Y532000D01*
X429883Y532833D01*
X430300Y533750D01*
X430967Y535000D01*
X427633D01*
G01X432400Y530000D02*
Y533333D01*
G01Y532417D02*
X432650Y532833D01*
X433067Y533167D01*
X433650Y533333D01*
X434233Y533167D01*
X434650Y532833D01*
X434900Y532417D01*
Y530000D01*
G01Y532417D02*
X435150Y532833D01*
X435567Y533167D01*
X436150Y533333D01*
X436733Y533167D01*
X437150Y532833D01*
X437400Y532333D01*
Y530000D01*
G01X440500Y533333D02*
Y530000D01*
G01Y534667D02*
X440333Y534750D01*
Y534917D01*
X440500Y535000D01*
X440667Y534917D01*
Y534750D01*
X440500Y534667D01*
G01X446100Y530000D02*
Y535000D01*
G01X455217Y533333D02*
X456217Y530000D01*
X457300Y533333D01*
X458383Y530000D01*
X459383Y533333D01*
G01X462900D02*
Y530000D01*
G01Y534667D02*
X462733Y534750D01*
Y534917D01*
X462900Y535000D01*
X463067Y534917D01*
Y534750D01*
X462900Y534667D01*
G01X468500Y535000D02*
Y530000D01*
G01X467333Y533333D02*
X469667D01*
G01X472683Y530000D02*
Y535000D01*
G01Y532583D02*
X473100Y533000D01*
X473517Y533250D01*
X474183Y533333D01*
X474683Y533250D01*
X475267Y532917D01*
X475517Y532417D01*
Y530000D01*
G01X483550D02*
Y535000D01*
G01X487050D02*
Y530000D01*
G01Y532500D02*
X483550D01*
G01X488817Y530000D02*
X490900Y535000D01*
X492983Y530000D01*
G01X492233Y531750D02*
X489567D01*
G01X494750Y530667D02*
X495417Y530250D01*
X496167Y530000D01*
X496833D01*
X497500Y530250D01*
X498000Y530667D01*
X498250Y531250D01*
X498083Y531833D01*
X497667Y532333D01*
X496917Y532667D01*
X495917Y532833D01*
X495333Y533167D01*
X495083Y533750D01*
X495250Y534333D01*
X495667Y534750D01*
X496250Y535000D01*
X496833D01*
X497417Y534833D01*
X497917Y534417D01*
G01X500433Y535000D02*
Y530000D01*
X503767D01*
G01X511800Y528333D02*
Y533333D01*
G01Y532583D02*
X512217Y533000D01*
X512633Y533250D01*
X513300Y533333D01*
X513883Y533250D01*
X514467Y532833D01*
X514717Y532250D01*
X514800Y531667D01*
X514717Y531083D01*
X514467Y530500D01*
X513967Y530167D01*
X513300Y530000D01*
X512717Y530083D01*
X512133Y530333D01*
X511800Y530667D01*
G01X517733Y530000D02*
Y533333D01*
G01Y532667D02*
X518150Y533000D01*
X518567Y533250D01*
X519150Y533333D01*
X519567Y533250D01*
X520067Y533000D01*
G01X524500Y530000D02*
X524000Y530083D01*
X523500Y530417D01*
X523167Y531000D01*
X523000Y531667D01*
X523167Y532333D01*
X523500Y532917D01*
X524000Y533250D01*
X524500Y533333D01*
X525000Y533250D01*
X525500Y532917D01*
X525833Y532333D01*
X525917Y531667D01*
X525833Y531000D01*
X525500Y530417D01*
X525000Y530083D01*
X524500Y530000D01*
G01X531600Y535000D02*
Y530000D01*
G01Y530750D02*
X531267Y530333D01*
X530767Y530083D01*
X530183Y530000D01*
X529517Y530167D01*
X529017Y530583D01*
X528683Y531083D01*
X528600Y531667D01*
X528683Y532250D01*
X529017Y532750D01*
X529517Y533167D01*
X530183Y533333D01*
X530767Y533250D01*
X531183Y533083D01*
X531600Y532750D01*
G01X534283Y533333D02*
Y531000D01*
X534617Y530417D01*
X535117Y530083D01*
X535700Y530000D01*
X536283Y530083D01*
X536783Y530417D01*
X537117Y531000D01*
G01Y530000D02*
Y533333D01*
G01X542633Y532917D02*
X542050Y533250D01*
X541550Y533333D01*
X540883Y533167D01*
X540383Y532833D01*
X540050Y532250D01*
X539967Y531667D01*
X540050Y531083D01*
X540383Y530583D01*
X540883Y530167D01*
X541550Y530000D01*
X542133Y530167D01*
X542633Y530500D01*
G01X546900Y535000D02*
Y530000D01*
G01X545733Y533333D02*
X548067D01*
G01X551250Y530583D02*
X551667Y530250D01*
X552250Y530000D01*
X552750D01*
X553250Y530167D01*
X553583Y530417D01*
X553750Y530750D01*
X553667Y531250D01*
X553333Y531500D01*
X551833Y532000D01*
X551500Y532583D01*
X551667Y533000D01*
X552000Y533250D01*
X552500Y533333D01*
X553000Y533250D01*
X553500Y533000D01*
G01X558517Y528333D02*
X559350Y529167D01*
X559767Y530000D01*
Y533333D01*
X559350Y534167D01*
X558517Y535000D01*
G01X270667Y550000D02*
Y546417D01*
X271000Y545667D01*
X271667Y545167D01*
X272500Y545000D01*
X273333Y545167D01*
X274000Y545667D01*
X274333Y546417D01*
Y550000D01*
G01X276683Y545000D02*
Y548333D01*
G01Y547500D02*
X277017Y547917D01*
X277517Y548250D01*
X278183Y548333D01*
X278767Y548250D01*
X279267Y547917D01*
X279517Y547333D01*
Y545000D01*
G01X282617Y546667D02*
X284783D01*
G01X287800Y543333D02*
Y548333D01*
G01Y547583D02*
X288217Y548000D01*
X288633Y548250D01*
X289300Y548333D01*
X289883Y548250D01*
X290467Y547833D01*
X290717Y547250D01*
X290800Y546667D01*
X290717Y546083D01*
X290467Y545500D01*
X289967Y545167D01*
X289300Y545000D01*
X288717Y545083D01*
X288133Y545333D01*
X287800Y545667D01*
G01X294900Y545000D02*
Y550000D01*
G01X299083Y548333D02*
Y546000D01*
X299417Y545417D01*
X299917Y545083D01*
X300500Y545000D01*
X301083Y545083D01*
X301583Y545417D01*
X301917Y546000D01*
G01Y545000D02*
Y548333D01*
G01X304933Y543750D02*
X305517Y543417D01*
X306183Y543333D01*
X306767Y543417D01*
X307267Y543833D01*
X307600Y544417D01*
Y548333D01*
G01Y547667D02*
X307267Y548000D01*
X306767Y548250D01*
X306183Y548333D01*
X305517Y548167D01*
X305100Y547833D01*
X304767Y547250D01*
X304600Y546667D01*
X304683Y546167D01*
X305017Y545583D01*
X305517Y545167D01*
X306183Y545000D01*
X306683Y545083D01*
X307267Y545417D01*
X307600Y545750D01*
G01X310533Y543750D02*
X311117Y543417D01*
X311783Y543333D01*
X312367Y543417D01*
X312867Y543833D01*
X313200Y544417D01*
Y548333D01*
G01Y547667D02*
X312867Y548000D01*
X312367Y548250D01*
X311783Y548333D01*
X311117Y548167D01*
X310700Y547833D01*
X310367Y547250D01*
X310200Y546667D01*
X310283Y546167D01*
X310617Y545583D01*
X311117Y545167D01*
X311783Y545000D01*
X312283Y545083D01*
X312867Y545417D01*
X313200Y545750D01*
G01X316050Y547250D02*
X318717D01*
X318467Y547833D01*
X318050Y548167D01*
X317467Y548333D01*
X316883Y548250D01*
X316383Y548000D01*
X316050Y547417D01*
X315883Y546917D01*
Y546417D01*
X316050Y545917D01*
X316467Y545417D01*
X316967Y545083D01*
X317550Y545000D01*
X318133Y545167D01*
X318717Y545667D01*
G01X324400Y550000D02*
Y545000D01*
G01Y545750D02*
X324067Y545333D01*
X323567Y545083D01*
X322983Y545000D01*
X322317Y545167D01*
X321817Y545583D01*
X321483Y546083D01*
X321400Y546667D01*
X321483Y547250D01*
X321817Y547750D01*
X322317Y548167D01*
X322983Y548333D01*
X323567Y548250D01*
X323983Y548083D01*
X324400Y547750D01*
G01X332433Y545000D02*
Y550000D01*
X334433D01*
X335100Y549750D01*
X335600Y549167D01*
X335767Y548500D01*
X335600Y547833D01*
X335183Y547333D01*
X334433Y547083D01*
X332433D01*
G01X339700Y550000D02*
Y545000D01*
G01X337783Y550000D02*
X341617D01*
G01X343550Y545000D02*
Y550000D01*
G01X347050D02*
Y545000D01*
G01Y547500D02*
X343550D01*
G01X356083Y543333D02*
X355250Y544167D01*
X354833Y545000D01*
Y548333D01*
X355250Y549167D01*
X356083Y550000D01*
G01X360350Y545000D02*
Y550000D01*
G01X363850D02*
Y545000D01*
G01Y547500D02*
X360350D01*
G01X367700Y545000D02*
X367200Y545083D01*
X366700Y545417D01*
X366367Y546000D01*
X366200Y546667D01*
X366367Y547333D01*
X366700Y547917D01*
X367200Y548250D01*
X367700Y548333D01*
X368200Y548250D01*
X368700Y547917D01*
X369033Y547333D01*
X369117Y546667D01*
X369033Y546000D01*
X368700Y545417D01*
X368200Y545083D01*
X367700Y545000D01*
G01X373300D02*
Y550000D01*
G01X377650Y547250D02*
X380317D01*
X380067Y547833D01*
X379650Y548167D01*
X379067Y548333D01*
X378483Y548250D01*
X377983Y548000D01*
X377650Y547417D01*
X377483Y546917D01*
Y546417D01*
X377650Y545917D01*
X378067Y545417D01*
X378567Y545083D01*
X379150Y545000D01*
X379733Y545167D01*
X380317Y545667D01*
G01X388350D02*
X389017Y545250D01*
X389767Y545000D01*
X390433D01*
X391100Y545250D01*
X391600Y545667D01*
X391850Y546250D01*
X391683Y546833D01*
X391267Y547333D01*
X390517Y547667D01*
X389517Y547833D01*
X388933Y548167D01*
X388683Y548750D01*
X388850Y549333D01*
X389267Y549750D01*
X389850Y550000D01*
X390433D01*
X391017Y549833D01*
X391517Y549417D01*
G01X395700Y548333D02*
Y545000D01*
G01Y549667D02*
X395533Y549750D01*
Y549917D01*
X395700Y550000D01*
X395867Y549917D01*
Y549750D01*
X395700Y549667D01*
G01X400050Y548333D02*
X402550D01*
X400050Y545000D01*
X402550D01*
G01X405650Y547250D02*
X408317D01*
X408067Y547833D01*
X407650Y548167D01*
X407067Y548333D01*
X406483Y548250D01*
X405983Y548000D01*
X405650Y547417D01*
X405483Y546917D01*
Y546417D01*
X405650Y545917D01*
X406067Y545417D01*
X406567Y545083D01*
X407150Y545000D01*
X407733Y545167D01*
X408317Y545667D01*
G01X414167Y545000D02*
X410833Y546667D01*
X414167Y548333D01*
G01X418100Y545000D02*
Y550000D01*
X417100Y549000D01*
G01Y545000D02*
X419100D01*
G01X422283Y545583D02*
X422867Y545167D01*
X423533Y545000D01*
X424200Y545167D01*
X424783Y545667D01*
X425200Y546417D01*
X425367Y547167D01*
Y548083D01*
X425200Y548833D01*
X424783Y549500D01*
X424283Y549833D01*
X423700Y550000D01*
X423033Y549833D01*
X422533Y549500D01*
X422200Y549000D01*
X422033Y548333D01*
X422200Y547750D01*
X422617Y547167D01*
X423117Y546833D01*
X423700Y546750D01*
X424367Y546917D01*
X424867Y547333D01*
X425367Y548083D01*
G01X429133Y545000D02*
X429300Y546083D01*
X429550Y547000D01*
X429883Y547833D01*
X430300Y548750D01*
X430967Y550000D01*
X427633D01*
G01X432400Y545000D02*
Y548333D01*
G01Y547417D02*
X432650Y547833D01*
X433067Y548167D01*
X433650Y548333D01*
X434233Y548167D01*
X434650Y547833D01*
X434900Y547417D01*
Y545000D01*
G01Y547417D02*
X435150Y547833D01*
X435567Y548167D01*
X436150Y548333D01*
X436733Y548167D01*
X437150Y547833D01*
X437400Y547333D01*
Y545000D01*
G01X440500Y548333D02*
Y545000D01*
G01Y549667D02*
X440333Y549750D01*
Y549917D01*
X440500Y550000D01*
X440667Y549917D01*
Y549750D01*
X440500Y549667D01*
G01X446100Y545000D02*
Y550000D01*
G01X455217Y548333D02*
X456217Y545000D01*
X457300Y548333D01*
X458383Y545000D01*
X459383Y548333D01*
G01X462900D02*
Y545000D01*
G01Y549667D02*
X462733Y549750D01*
Y549917D01*
X462900Y550000D01*
X463067Y549917D01*
Y549750D01*
X462900Y549667D01*
G01X468500Y550000D02*
Y545000D01*
G01X467333Y548333D02*
X469667D01*
G01X472683Y545000D02*
Y550000D01*
G01Y547583D02*
X473100Y548000D01*
X473517Y548250D01*
X474183Y548333D01*
X474683Y548250D01*
X475267Y547917D01*
X475517Y547417D01*
Y545000D01*
G01X483883D02*
Y548333D01*
G01Y547500D02*
X484217Y547917D01*
X484717Y548250D01*
X485383Y548333D01*
X485967Y548250D01*
X486467Y547917D01*
X486717Y547333D01*
Y545000D01*
G01X490900D02*
X490400Y545083D01*
X489900Y545417D01*
X489567Y546000D01*
X489400Y546667D01*
X489567Y547333D01*
X489900Y547917D01*
X490400Y548250D01*
X490900Y548333D01*
X491400Y548250D01*
X491900Y547917D01*
X492233Y547333D01*
X492317Y546667D01*
X492233Y546000D01*
X491900Y545417D01*
X491400Y545083D01*
X490900Y545000D01*
G01X495083D02*
Y548333D01*
G01Y547500D02*
X495417Y547917D01*
X495917Y548250D01*
X496583Y548333D01*
X497167Y548250D01*
X497667Y547917D01*
X497917Y547333D01*
Y545000D01*
G01X501017Y546667D02*
X503183D01*
G01X505950Y545000D02*
Y550000D01*
G01X509450D02*
Y545000D01*
G01Y547500D02*
X505950D01*
G01X511217Y545000D02*
X513300Y550000D01*
X515383Y545000D01*
G01X514633Y546750D02*
X511967D01*
G01X517150Y545667D02*
X517817Y545250D01*
X518567Y545000D01*
X519233D01*
X519900Y545250D01*
X520400Y545667D01*
X520650Y546250D01*
X520483Y546833D01*
X520067Y547333D01*
X519317Y547667D01*
X518317Y547833D01*
X517733Y548167D01*
X517483Y548750D01*
X517650Y549333D01*
X518067Y549750D01*
X518650Y550000D01*
X519233D01*
X519817Y549833D01*
X520317Y549417D01*
G01X522833Y550000D02*
Y545000D01*
X526167D01*
G01X534200Y543333D02*
Y548333D01*
G01Y547583D02*
X534617Y548000D01*
X535033Y548250D01*
X535700Y548333D01*
X536283Y548250D01*
X536867Y547833D01*
X537117Y547250D01*
X537200Y546667D01*
X537117Y546083D01*
X536867Y545500D01*
X536367Y545167D01*
X535700Y545000D01*
X535117Y545083D01*
X534533Y545333D01*
X534200Y545667D01*
G01X540133Y545000D02*
Y548333D01*
G01Y547667D02*
X540550Y548000D01*
X540967Y548250D01*
X541550Y548333D01*
X541967Y548250D01*
X542467Y548000D01*
G01X546900Y545000D02*
X546400Y545083D01*
X545900Y545417D01*
X545567Y546000D01*
X545400Y546667D01*
X545567Y547333D01*
X545900Y547917D01*
X546400Y548250D01*
X546900Y548333D01*
X547400Y548250D01*
X547900Y547917D01*
X548233Y547333D01*
X548317Y546667D01*
X548233Y546000D01*
X547900Y545417D01*
X547400Y545083D01*
X546900Y545000D01*
G01X554000Y550000D02*
Y545000D01*
G01Y545750D02*
X553667Y545333D01*
X553167Y545083D01*
X552583Y545000D01*
X551917Y545167D01*
X551417Y545583D01*
X551083Y546083D01*
X551000Y546667D01*
X551083Y547250D01*
X551417Y547750D01*
X551917Y548167D01*
X552583Y548333D01*
X553167Y548250D01*
X553583Y548083D01*
X554000Y547750D01*
G01X556683Y548333D02*
Y546000D01*
X557017Y545417D01*
X557517Y545083D01*
X558100Y545000D01*
X558683Y545083D01*
X559183Y545417D01*
X559517Y546000D01*
G01Y545000D02*
Y548333D01*
G01X565033Y547917D02*
X564450Y548250D01*
X563950Y548333D01*
X563283Y548167D01*
X562783Y547833D01*
X562450Y547250D01*
X562367Y546667D01*
X562450Y546083D01*
X562783Y545583D01*
X563283Y545167D01*
X563950Y545000D01*
X564533Y545167D01*
X565033Y545500D01*
G01X569300Y550000D02*
Y545000D01*
G01X568133Y548333D02*
X570467D01*
G01X573650Y545583D02*
X574067Y545250D01*
X574650Y545000D01*
X575150D01*
X575650Y545167D01*
X575983Y545417D01*
X576150Y545750D01*
X576067Y546250D01*
X575733Y546500D01*
X574233Y547000D01*
X573900Y547583D01*
X574067Y548000D01*
X574400Y548250D01*
X574900Y548333D01*
X575400Y548250D01*
X575900Y548000D01*
G01X580917Y543333D02*
X581750Y544167D01*
X582167Y545000D01*
Y548333D01*
X581750Y549167D01*
X580917Y550000D01*
G01X270833Y575000D02*
Y580000D01*
X272833D01*
X273500Y579750D01*
X274000Y579167D01*
X274167Y578500D01*
X274000Y577833D01*
X273583Y577333D01*
X272833Y577083D01*
X270833D01*
G01X278100Y575000D02*
Y580000D01*
G01X282283Y578333D02*
Y576000D01*
X282617Y575417D01*
X283117Y575083D01*
X283700Y575000D01*
X284283Y575083D01*
X284783Y575417D01*
X285117Y576000D01*
G01Y575000D02*
Y578333D01*
G01X288133Y573750D02*
X288717Y573417D01*
X289383Y573333D01*
X289967Y573417D01*
X290467Y573833D01*
X290800Y574417D01*
Y578333D01*
G01Y577667D02*
X290467Y578000D01*
X289967Y578250D01*
X289383Y578333D01*
X288717Y578167D01*
X288300Y577833D01*
X287967Y577250D01*
X287800Y576667D01*
X287883Y576167D01*
X288217Y575583D01*
X288717Y575167D01*
X289383Y575000D01*
X289883Y575083D01*
X290467Y575417D01*
X290800Y575750D01*
G01X293733Y573750D02*
X294317Y573417D01*
X294983Y573333D01*
X295567Y573417D01*
X296067Y573833D01*
X296400Y574417D01*
Y578333D01*
G01Y577667D02*
X296067Y578000D01*
X295567Y578250D01*
X294983Y578333D01*
X294317Y578167D01*
X293900Y577833D01*
X293567Y577250D01*
X293400Y576667D01*
X293483Y576167D01*
X293817Y575583D01*
X294317Y575167D01*
X294983Y575000D01*
X295483Y575083D01*
X296067Y575417D01*
X296400Y575750D01*
G01X299250Y577250D02*
X301917D01*
X301667Y577833D01*
X301250Y578167D01*
X300667Y578333D01*
X300083Y578250D01*
X299583Y578000D01*
X299250Y577417D01*
X299083Y576917D01*
Y576417D01*
X299250Y575917D01*
X299667Y575417D01*
X300167Y575083D01*
X300750Y575000D01*
X301333Y575167D01*
X301917Y575667D01*
G01X307600Y580000D02*
Y575000D01*
G01Y575750D02*
X307267Y575333D01*
X306767Y575083D01*
X306183Y575000D01*
X305517Y575167D01*
X305017Y575583D01*
X304683Y576083D01*
X304600Y576667D01*
X304683Y577250D01*
X305017Y577750D01*
X305517Y578167D01*
X306183Y578333D01*
X306767Y578250D01*
X307183Y578083D01*
X307600Y577750D01*
G01X315217Y580000D02*
X317300Y575000D01*
X319383Y580000D01*
G01X322900Y578333D02*
Y575000D01*
G01Y579667D02*
X322733Y579750D01*
Y579917D01*
X322900Y580000D01*
X323067Y579917D01*
Y579750D01*
X322900Y579667D01*
G01X330000Y575000D02*
Y578333D01*
G01Y577750D02*
X329667Y578083D01*
X329167Y578250D01*
X328583Y578333D01*
X328000Y578167D01*
X327500Y577833D01*
X327167Y577333D01*
X327000Y576667D01*
X327167Y576000D01*
X327500Y575500D01*
X328000Y575167D01*
X328583Y575000D01*
X329167Y575083D01*
X329667Y575333D01*
X330000Y575667D01*
G01X333683Y573333D02*
X332850Y574167D01*
X332433Y575000D01*
Y578333D01*
X332850Y579167D01*
X333683Y580000D01*
G01X338283Y575000D02*
Y580000D01*
G01Y577583D02*
X338700Y578000D01*
X339117Y578250D01*
X339783Y578333D01*
X340283Y578250D01*
X340867Y577917D01*
X341117Y577417D01*
Y575000D01*
G01X345300D02*
X344800Y575083D01*
X344300Y575417D01*
X343967Y576000D01*
X343800Y576667D01*
X343967Y577333D01*
X344300Y577917D01*
X344800Y578250D01*
X345300Y578333D01*
X345800Y578250D01*
X346300Y577917D01*
X346633Y577333D01*
X346717Y576667D01*
X346633Y576000D01*
X346300Y575417D01*
X345800Y575083D01*
X345300Y575000D01*
G01X350900D02*
Y580000D01*
G01X355250Y577250D02*
X357917D01*
X357667Y577833D01*
X357250Y578167D01*
X356667Y578333D01*
X356083Y578250D01*
X355583Y578000D01*
X355250Y577417D01*
X355083Y576917D01*
Y576417D01*
X355250Y575917D01*
X355667Y575417D01*
X356167Y575083D01*
X356750Y575000D01*
X357333Y575167D01*
X357917Y575667D01*
G01X366450Y575583D02*
X366867Y575250D01*
X367450Y575000D01*
X367950D01*
X368450Y575167D01*
X368783Y575417D01*
X368950Y575750D01*
X368867Y576250D01*
X368533Y576500D01*
X367033Y577000D01*
X366700Y577583D01*
X366867Y578000D01*
X367200Y578250D01*
X367700Y578333D01*
X368200Y578250D01*
X368700Y578000D01*
G01X373300Y578333D02*
Y575000D01*
G01Y579667D02*
X373133Y579750D01*
Y579917D01*
X373300Y580000D01*
X373467Y579917D01*
Y579750D01*
X373300Y579667D01*
G01X377650Y578333D02*
X380150D01*
X377650Y575000D01*
X380150D01*
G01X383250Y577250D02*
X385917D01*
X385667Y577833D01*
X385250Y578167D01*
X384667Y578333D01*
X384083Y578250D01*
X383583Y578000D01*
X383250Y577417D01*
X383083Y576917D01*
Y576417D01*
X383250Y575917D01*
X383667Y575417D01*
X384167Y575083D01*
X384750Y575000D01*
X385333Y575167D01*
X385917Y575667D01*
G01X391767Y575000D02*
X388433Y576667D01*
X391767Y578333D01*
G01X395700Y575000D02*
Y580000D01*
X394700Y579000D01*
G01Y575000D02*
X396700D01*
G01X399717Y577083D02*
X400300Y577667D01*
X400800Y578000D01*
X401467Y578167D01*
X402050Y578000D01*
X402467Y577667D01*
X402800Y577167D01*
X402883Y576583D01*
X402800Y576083D01*
X402467Y575583D01*
X401967Y575167D01*
X401383Y575000D01*
X400717Y575167D01*
X400133Y575667D01*
X399800Y576417D01*
X399717Y577250D01*
X399883Y578333D01*
X400133Y578917D01*
X400550Y579500D01*
X401133Y579917D01*
X401717Y580000D01*
X402300Y579833D01*
X402717Y579417D01*
G01X410000Y575000D02*
Y578333D01*
G01Y577417D02*
X410250Y577833D01*
X410667Y578167D01*
X411250Y578333D01*
X411833Y578167D01*
X412250Y577833D01*
X412500Y577417D01*
Y575000D01*
G01Y577417D02*
X412750Y577833D01*
X413167Y578167D01*
X413750Y578333D01*
X414333Y578167D01*
X414750Y577833D01*
X415000Y577333D01*
Y575000D01*
G01X418100Y578333D02*
Y575000D01*
G01Y579667D02*
X417933Y579750D01*
Y579917D01*
X418100Y580000D01*
X418267Y579917D01*
Y579750D01*
X418100Y579667D01*
G01X423700Y575000D02*
Y580000D01*
G01X429717Y573333D02*
X430550Y574167D01*
X430967Y575000D01*
Y578333D01*
X430550Y579167D01*
X429717Y580000D01*
G01X270833Y560000D02*
Y565000D01*
X272833D01*
X273500Y564750D01*
X274000Y564167D01*
X274167Y563500D01*
X274000Y562833D01*
X273583Y562333D01*
X272833Y562083D01*
X270833D01*
G01X278100Y560000D02*
Y565000D01*
G01X282283Y563333D02*
Y561000D01*
X282617Y560417D01*
X283117Y560083D01*
X283700Y560000D01*
X284283Y560083D01*
X284783Y560417D01*
X285117Y561000D01*
G01Y560000D02*
Y563333D01*
G01X288133Y558750D02*
X288717Y558417D01*
X289383Y558333D01*
X289967Y558417D01*
X290467Y558833D01*
X290800Y559417D01*
Y563333D01*
G01Y562667D02*
X290467Y563000D01*
X289967Y563250D01*
X289383Y563333D01*
X288717Y563167D01*
X288300Y562833D01*
X287967Y562250D01*
X287800Y561667D01*
X287883Y561167D01*
X288217Y560583D01*
X288717Y560167D01*
X289383Y560000D01*
X289883Y560083D01*
X290467Y560417D01*
X290800Y560750D01*
G01X293733Y558750D02*
X294317Y558417D01*
X294983Y558333D01*
X295567Y558417D01*
X296067Y558833D01*
X296400Y559417D01*
Y563333D01*
G01Y562667D02*
X296067Y563000D01*
X295567Y563250D01*
X294983Y563333D01*
X294317Y563167D01*
X293900Y562833D01*
X293567Y562250D01*
X293400Y561667D01*
X293483Y561167D01*
X293817Y560583D01*
X294317Y560167D01*
X294983Y560000D01*
X295483Y560083D01*
X296067Y560417D01*
X296400Y560750D01*
G01X299250Y562250D02*
X301917D01*
X301667Y562833D01*
X301250Y563167D01*
X300667Y563333D01*
X300083Y563250D01*
X299583Y563000D01*
X299250Y562417D01*
X299083Y561917D01*
Y561417D01*
X299250Y560917D01*
X299667Y560417D01*
X300167Y560083D01*
X300750Y560000D01*
X301333Y560167D01*
X301917Y560667D01*
G01X307600Y565000D02*
Y560000D01*
G01Y560750D02*
X307267Y560333D01*
X306767Y560083D01*
X306183Y560000D01*
X305517Y560167D01*
X305017Y560583D01*
X304683Y561083D01*
X304600Y561667D01*
X304683Y562250D01*
X305017Y562750D01*
X305517Y563167D01*
X306183Y563333D01*
X306767Y563250D01*
X307183Y563083D01*
X307600Y562750D01*
G01X315633Y560000D02*
Y565000D01*
X317633D01*
X318300Y564750D01*
X318800Y564167D01*
X318967Y563500D01*
X318800Y562833D01*
X318383Y562333D01*
X317633Y562083D01*
X315633D01*
G01X322900Y565000D02*
Y560000D01*
G01X320983Y565000D02*
X324817D01*
G01X326750Y560000D02*
Y565000D01*
G01X330250D02*
Y560000D01*
G01Y562500D02*
X326750D01*
G01X333683Y558333D02*
X332850Y559167D01*
X332433Y560000D01*
Y563333D01*
X332850Y564167D01*
X333683Y565000D01*
G01X338283Y560000D02*
Y565000D01*
G01Y562583D02*
X338700Y563000D01*
X339117Y563250D01*
X339783Y563333D01*
X340283Y563250D01*
X340867Y562917D01*
X341117Y562417D01*
Y560000D01*
G01X345300D02*
X344800Y560083D01*
X344300Y560417D01*
X343967Y561000D01*
X343800Y561667D01*
X343967Y562333D01*
X344300Y562917D01*
X344800Y563250D01*
X345300Y563333D01*
X345800Y563250D01*
X346300Y562917D01*
X346633Y562333D01*
X346717Y561667D01*
X346633Y561000D01*
X346300Y560417D01*
X345800Y560083D01*
X345300Y560000D01*
G01X350900D02*
Y565000D01*
G01X355250Y562250D02*
X357917D01*
X357667Y562833D01*
X357250Y563167D01*
X356667Y563333D01*
X356083Y563250D01*
X355583Y563000D01*
X355250Y562417D01*
X355083Y561917D01*
Y561417D01*
X355250Y560917D01*
X355667Y560417D01*
X356167Y560083D01*
X356750Y560000D01*
X357333Y560167D01*
X357917Y560667D01*
G01X366450Y560583D02*
X366867Y560250D01*
X367450Y560000D01*
X367950D01*
X368450Y560167D01*
X368783Y560417D01*
X368950Y560750D01*
X368867Y561250D01*
X368533Y561500D01*
X367033Y562000D01*
X366700Y562583D01*
X366867Y563000D01*
X367200Y563250D01*
X367700Y563333D01*
X368200Y563250D01*
X368700Y563000D01*
G01X373300Y563333D02*
Y560000D01*
G01Y564667D02*
X373133Y564750D01*
Y564917D01*
X373300Y565000D01*
X373467Y564917D01*
Y564750D01*
X373300Y564667D01*
G01X377650Y563333D02*
X380150D01*
X377650Y560000D01*
X380150D01*
G01X383250Y562250D02*
X385917D01*
X385667Y562833D01*
X385250Y563167D01*
X384667Y563333D01*
X384083Y563250D01*
X383583Y563000D01*
X383250Y562417D01*
X383083Y561917D01*
Y561417D01*
X383250Y560917D01*
X383667Y560417D01*
X384167Y560083D01*
X384750Y560000D01*
X385333Y560167D01*
X385917Y560667D01*
G01X388433Y560000D02*
X391767Y561667D01*
X388433Y563333D01*
G01X394617Y560917D02*
X396783D01*
G01Y562417D02*
X394617D01*
G01X401300Y560000D02*
Y565000D01*
X400300Y564000D01*
G01Y560000D02*
X402300D01*
G01X405317Y562083D02*
X405900Y562667D01*
X406400Y563000D01*
X407067Y563167D01*
X407650Y563000D01*
X408067Y562667D01*
X408400Y562167D01*
X408483Y561583D01*
X408400Y561083D01*
X408067Y560583D01*
X407567Y560167D01*
X406983Y560000D01*
X406317Y560167D01*
X405733Y560667D01*
X405400Y561417D01*
X405317Y562250D01*
X405483Y563333D01*
X405733Y563917D01*
X406150Y564500D01*
X406733Y564917D01*
X407317Y565000D01*
X407900Y564833D01*
X408317Y564417D01*
G01X415600Y560000D02*
Y563333D01*
G01Y562417D02*
X415850Y562833D01*
X416267Y563167D01*
X416850Y563333D01*
X417433Y563167D01*
X417850Y562833D01*
X418100Y562417D01*
Y560000D01*
G01Y562417D02*
X418350Y562833D01*
X418767Y563167D01*
X419350Y563333D01*
X419933Y563167D01*
X420350Y562833D01*
X420600Y562333D01*
Y560000D01*
G01X423700Y563333D02*
Y560000D01*
G01Y564667D02*
X423533Y564750D01*
Y564917D01*
X423700Y565000D01*
X423867Y564917D01*
Y564750D01*
X423700Y564667D01*
G01X429300Y560000D02*
Y565000D01*
G01X435317Y558333D02*
X436150Y559167D01*
X436567Y560000D01*
Y563333D01*
X436150Y564167D01*
X435317Y565000D01*
G01X273000Y609000D02*
Y604000D01*
G01X271083Y609000D02*
X274917D01*
G01X277183Y604000D02*
Y609000D01*
G01Y606583D02*
X277600Y607000D01*
X278017Y607250D01*
X278683Y607333D01*
X279183Y607250D01*
X279767Y606917D01*
X280017Y606417D01*
Y604000D01*
G01X282950Y606250D02*
X285617D01*
X285367Y606833D01*
X284950Y607167D01*
X284367Y607333D01*
X283783Y607250D01*
X283283Y607000D01*
X282950Y606417D01*
X282783Y605917D01*
Y605417D01*
X282950Y604917D01*
X283367Y604417D01*
X283867Y604083D01*
X284450Y604000D01*
X285033Y604167D01*
X285617Y604667D01*
G01X288633Y604000D02*
Y607333D01*
G01Y606667D02*
X289050Y607000D01*
X289467Y607250D01*
X290050Y607333D01*
X290467Y607250D01*
X290967Y607000D01*
G01X292900Y604000D02*
Y607333D01*
G01Y606417D02*
X293150Y606833D01*
X293567Y607167D01*
X294150Y607333D01*
X294733Y607167D01*
X295150Y606833D01*
X295400Y606417D01*
Y604000D01*
G01Y606417D02*
X295650Y606833D01*
X296067Y607167D01*
X296650Y607333D01*
X297233Y607167D01*
X297650Y606833D01*
X297900Y606333D01*
Y604000D01*
G01X302500D02*
Y607333D01*
G01Y606750D02*
X302167Y607083D01*
X301667Y607250D01*
X301083Y607333D01*
X300500Y607167D01*
X300000Y606833D01*
X299667Y606333D01*
X299500Y605667D01*
X299667Y605000D01*
X300000Y604500D01*
X300500Y604167D01*
X301083Y604000D01*
X301667Y604083D01*
X302167Y604333D01*
X302500Y604667D01*
G01X306600Y604000D02*
Y609000D01*
G01X316300Y602333D02*
Y607333D01*
G01Y606583D02*
X316717Y607000D01*
X317133Y607250D01*
X317800Y607333D01*
X318383Y607250D01*
X318967Y606833D01*
X319217Y606250D01*
X319300Y605667D01*
X319217Y605083D01*
X318967Y604500D01*
X318467Y604167D01*
X317800Y604000D01*
X317217Y604083D01*
X316633Y604333D01*
X316300Y604667D01*
G01X324900Y604000D02*
Y607333D01*
G01Y606750D02*
X324567Y607083D01*
X324067Y607250D01*
X323483Y607333D01*
X322900Y607167D01*
X322400Y606833D01*
X322067Y606333D01*
X321900Y605667D01*
X322067Y605000D01*
X322400Y604500D01*
X322900Y604167D01*
X323483Y604000D01*
X324067Y604083D01*
X324567Y604333D01*
X324900Y604667D01*
G01X330500Y609000D02*
Y604000D01*
G01Y604750D02*
X330167Y604333D01*
X329667Y604083D01*
X329083Y604000D01*
X328417Y604167D01*
X327917Y604583D01*
X327583Y605083D01*
X327500Y605667D01*
X327583Y606250D01*
X327917Y606750D01*
X328417Y607167D01*
X329083Y607333D01*
X329667Y607250D01*
X330083Y607083D01*
X330500Y606750D01*
G01X341533Y606917D02*
X340950Y607250D01*
X340450Y607333D01*
X339783Y607167D01*
X339283Y606833D01*
X338950Y606250D01*
X338867Y605667D01*
X338950Y605083D01*
X339283Y604583D01*
X339783Y604167D01*
X340450Y604000D01*
X341033Y604167D01*
X341533Y604500D01*
G01X347300Y604000D02*
Y607333D01*
G01Y606750D02*
X346967Y607083D01*
X346467Y607250D01*
X345883Y607333D01*
X345300Y607167D01*
X344800Y606833D01*
X344467Y606333D01*
X344300Y605667D01*
X344467Y605000D01*
X344800Y604500D01*
X345300Y604167D01*
X345883Y604000D01*
X346467Y604083D01*
X346967Y604333D01*
X347300Y604667D01*
G01X349983Y604000D02*
Y607333D01*
G01Y606500D02*
X350317Y606917D01*
X350817Y607250D01*
X351483Y607333D01*
X352067Y607250D01*
X352567Y606917D01*
X352817Y606333D01*
Y604000D01*
G01X363933Y606917D02*
X363350Y607250D01*
X362850Y607333D01*
X362183Y607167D01*
X361683Y606833D01*
X361350Y606250D01*
X361267Y605667D01*
X361350Y605083D01*
X361683Y604583D01*
X362183Y604167D01*
X362850Y604000D01*
X363433Y604167D01*
X363933Y604500D01*
G01X366783Y604000D02*
Y609000D01*
G01Y606583D02*
X367200Y607000D01*
X367617Y607250D01*
X368283Y607333D01*
X368783Y607250D01*
X369367Y606917D01*
X369617Y606417D01*
Y604000D01*
G01X375300D02*
Y607333D01*
G01Y606750D02*
X374967Y607083D01*
X374467Y607250D01*
X373883Y607333D01*
X373300Y607167D01*
X372800Y606833D01*
X372467Y606333D01*
X372300Y605667D01*
X372467Y605000D01*
X372800Y604500D01*
X373300Y604167D01*
X373883Y604000D01*
X374467Y604083D01*
X374967Y604333D01*
X375300Y604667D01*
G01X377983Y604000D02*
Y607333D01*
G01Y606500D02*
X378317Y606917D01*
X378817Y607250D01*
X379483Y607333D01*
X380067Y607250D01*
X380567Y606917D01*
X380817Y606333D01*
Y604000D01*
G01X383833Y602750D02*
X384417Y602417D01*
X385083Y602333D01*
X385667Y602417D01*
X386167Y602833D01*
X386500Y603417D01*
Y607333D01*
G01Y606667D02*
X386167Y607000D01*
X385667Y607250D01*
X385083Y607333D01*
X384417Y607167D01*
X384000Y606833D01*
X383667Y606250D01*
X383500Y605667D01*
X383583Y605167D01*
X383917Y604583D01*
X384417Y604167D01*
X385083Y604000D01*
X385583Y604083D01*
X386167Y604417D01*
X386500Y604750D01*
G01X389350Y606250D02*
X392017D01*
X391767Y606833D01*
X391350Y607167D01*
X390767Y607333D01*
X390183Y607250D01*
X389683Y607000D01*
X389350Y606417D01*
X389183Y605917D01*
Y605417D01*
X389350Y604917D01*
X389767Y604417D01*
X390267Y604083D01*
X390850Y604000D01*
X391433Y604167D01*
X392017Y604667D01*
G01X401800Y607333D02*
Y604000D01*
G01Y608667D02*
X401633Y608750D01*
Y608917D01*
X401800Y609000D01*
X401967Y608917D01*
Y608750D01*
X401800Y608667D01*
G01X405983Y604000D02*
Y607333D01*
G01Y606500D02*
X406317Y606917D01*
X406817Y607250D01*
X407483Y607333D01*
X408067Y607250D01*
X408567Y606917D01*
X408817Y606333D01*
Y604000D01*
G01X413000Y609000D02*
Y604000D01*
G01X411833Y607333D02*
X414167D01*
G01X418600Y604000D02*
X418100Y604083D01*
X417600Y604417D01*
X417267Y605000D01*
X417100Y605667D01*
X417267Y606333D01*
X417600Y606917D01*
X418100Y607250D01*
X418600Y607333D01*
X419100Y607250D01*
X419600Y606917D01*
X419933Y606333D01*
X420017Y605667D01*
X419933Y605000D01*
X419600Y604417D01*
X419100Y604083D01*
X418600Y604000D01*
G01X429300D02*
Y608250D01*
X429467Y608667D01*
X429800Y608917D01*
X430300Y609000D01*
X430800Y608833D01*
X431050Y608417D01*
G01X430050Y607000D02*
X428383D01*
G01X433983Y607333D02*
Y605000D01*
X434317Y604417D01*
X434817Y604083D01*
X435400Y604000D01*
X435983Y604083D01*
X436483Y604417D01*
X436817Y605000D01*
G01Y604000D02*
Y607333D01*
G01X441000Y604000D02*
Y609000D01*
G01X446600Y604000D02*
Y609000D01*
G01X459133Y606917D02*
X458550Y607250D01*
X458050Y607333D01*
X457383Y607167D01*
X456883Y606833D01*
X456550Y606250D01*
X456467Y605667D01*
X456550Y605083D01*
X456883Y604583D01*
X457383Y604167D01*
X458050Y604000D01*
X458633Y604167D01*
X459133Y604500D01*
G01X463400Y604000D02*
X462900Y604083D01*
X462400Y604417D01*
X462067Y605000D01*
X461900Y605667D01*
X462067Y606333D01*
X462400Y606917D01*
X462900Y607250D01*
X463400Y607333D01*
X463900Y607250D01*
X464400Y606917D01*
X464733Y606333D01*
X464817Y605667D01*
X464733Y605000D01*
X464400Y604417D01*
X463900Y604083D01*
X463400Y604000D01*
G01X467583D02*
Y607333D01*
G01Y606500D02*
X467917Y606917D01*
X468417Y607250D01*
X469083Y607333D01*
X469667Y607250D01*
X470167Y606917D01*
X470417Y606333D01*
Y604000D01*
G01X474600Y609000D02*
Y604000D01*
G01X473433Y607333D02*
X475767D01*
G01X481700Y604000D02*
Y607333D01*
G01Y606750D02*
X481367Y607083D01*
X480867Y607250D01*
X480283Y607333D01*
X479700Y607167D01*
X479200Y606833D01*
X478867Y606333D01*
X478700Y605667D01*
X478867Y605000D01*
X479200Y604500D01*
X479700Y604167D01*
X480283Y604000D01*
X480867Y604083D01*
X481367Y604333D01*
X481700Y604667D01*
G01X487133Y606917D02*
X486550Y607250D01*
X486050Y607333D01*
X485383Y607167D01*
X484883Y606833D01*
X484550Y606250D01*
X484467Y605667D01*
X484550Y605083D01*
X484883Y604583D01*
X485383Y604167D01*
X486050Y604000D01*
X486633Y604167D01*
X487133Y604500D01*
G01X491400Y609000D02*
Y604000D01*
G01X490233Y607333D02*
X492567D01*
G01X270417Y588500D02*
X272500Y593500D01*
X274583Y588500D01*
G01X273833Y590250D02*
X271167D01*
G01X276683Y588500D02*
Y591833D01*
G01Y591000D02*
X277017Y591417D01*
X277517Y591750D01*
X278183Y591833D01*
X278767Y591750D01*
X279267Y591417D01*
X279517Y590833D01*
Y588500D01*
G01X281950Y587000D02*
X282450Y586833D01*
X283117Y587000D01*
X283533Y587333D01*
X283867Y587750D01*
X284367Y589083D01*
X285450Y591833D01*
G01X282783D02*
X284367Y589083D01*
G01X293483Y588500D02*
Y593500D01*
G01Y591083D02*
X293900Y591500D01*
X294317Y591750D01*
X294983Y591833D01*
X295483Y591750D01*
X296067Y591417D01*
X296317Y590917D01*
Y588500D01*
G01X300500D02*
X300000Y588583D01*
X299500Y588917D01*
X299167Y589500D01*
X299000Y590167D01*
X299167Y590833D01*
X299500Y591417D01*
X300000Y591750D01*
X300500Y591833D01*
X301000Y591750D01*
X301500Y591417D01*
X301833Y590833D01*
X301917Y590167D01*
X301833Y589500D01*
X301500Y588917D01*
X301000Y588583D01*
X300500Y588500D01*
G01X306100D02*
Y593500D01*
G01X310450Y590750D02*
X313117D01*
X312867Y591333D01*
X312450Y591667D01*
X311867Y591833D01*
X311283Y591750D01*
X310783Y591500D01*
X310450Y590917D01*
X310283Y590417D01*
Y589917D01*
X310450Y589417D01*
X310867Y588917D01*
X311367Y588583D01*
X311950Y588500D01*
X312533Y588667D01*
X313117Y589167D01*
G01X322900Y593500D02*
Y588500D01*
G01X321733Y591833D02*
X324067D01*
G01X328500Y588500D02*
X328000Y588583D01*
X327500Y588917D01*
X327167Y589500D01*
X327000Y590167D01*
X327167Y590833D01*
X327500Y591417D01*
X328000Y591750D01*
X328500Y591833D01*
X329000Y591750D01*
X329500Y591417D01*
X329833Y590833D01*
X329917Y590167D01*
X329833Y589500D01*
X329500Y588917D01*
X329000Y588583D01*
X328500Y588500D01*
G01X338283D02*
Y593500D01*
G01Y591083D02*
X338700Y591500D01*
X339117Y591750D01*
X339783Y591833D01*
X340283Y591750D01*
X340867Y591417D01*
X341117Y590917D01*
Y588500D01*
G01X345300D02*
X344800Y588583D01*
X344300Y588917D01*
X343967Y589500D01*
X343800Y590167D01*
X343967Y590833D01*
X344300Y591417D01*
X344800Y591750D01*
X345300Y591833D01*
X345800Y591750D01*
X346300Y591417D01*
X346633Y590833D01*
X346717Y590167D01*
X346633Y589500D01*
X346300Y588917D01*
X345800Y588583D01*
X345300Y588500D01*
G01X350900D02*
Y593500D01*
G01X355250Y590750D02*
X357917D01*
X357667Y591333D01*
X357250Y591667D01*
X356667Y591833D01*
X356083Y591750D01*
X355583Y591500D01*
X355250Y590917D01*
X355083Y590417D01*
Y589917D01*
X355250Y589417D01*
X355667Y588917D01*
X356167Y588583D01*
X356750Y588500D01*
X357333Y588667D01*
X357917Y589167D01*
G01X270917Y619000D02*
X273000Y624000D01*
X275083Y619000D01*
G01X274333Y620750D02*
X271667D01*
G01X277183Y619000D02*
Y622333D01*
G01Y621500D02*
X277517Y621917D01*
X278017Y622250D01*
X278683Y622333D01*
X279267Y622250D01*
X279767Y621917D01*
X280017Y621333D01*
Y619000D01*
G01X284200Y624000D02*
Y619000D01*
G01X283033Y622333D02*
X285367D01*
G01X289800D02*
Y619000D01*
G01Y623667D02*
X289633Y623750D01*
Y623917D01*
X289800Y624000D01*
X289967Y623917D01*
Y623750D01*
X289800Y623667D01*
G01X294317Y620667D02*
X296483D01*
G01X299500Y617333D02*
Y622333D01*
G01Y621583D02*
X299917Y622000D01*
X300333Y622250D01*
X301000Y622333D01*
X301583Y622250D01*
X302167Y621833D01*
X302417Y621250D01*
X302500Y620667D01*
X302417Y620083D01*
X302167Y619500D01*
X301667Y619167D01*
X301000Y619000D01*
X300417Y619083D01*
X299833Y619333D01*
X299500Y619667D01*
G01X308100Y619000D02*
Y622333D01*
G01Y621750D02*
X307767Y622083D01*
X307267Y622250D01*
X306683Y622333D01*
X306100Y622167D01*
X305600Y621833D01*
X305267Y621333D01*
X305100Y620667D01*
X305267Y620000D01*
X305600Y619500D01*
X306100Y619167D01*
X306683Y619000D01*
X307267Y619083D01*
X307767Y619333D01*
X308100Y619667D01*
G01X313700Y624000D02*
Y619000D01*
G01Y619750D02*
X313367Y619333D01*
X312867Y619083D01*
X312283Y619000D01*
X311617Y619167D01*
X311117Y619583D01*
X310783Y620083D01*
X310700Y620667D01*
X310783Y621250D01*
X311117Y621750D01*
X311617Y622167D01*
X312283Y622333D01*
X312867Y622250D01*
X313283Y622083D01*
X313700Y621750D01*
G01X322150Y619583D02*
X322567Y619250D01*
X323150Y619000D01*
X323650D01*
X324150Y619167D01*
X324483Y619417D01*
X324650Y619750D01*
X324567Y620250D01*
X324233Y620500D01*
X322733Y621000D01*
X322400Y621583D01*
X322567Y622000D01*
X322900Y622250D01*
X323400Y622333D01*
X323900Y622250D01*
X324400Y622000D01*
G01X329000Y622333D02*
Y619000D01*
G01Y623667D02*
X328833Y623750D01*
Y623917D01*
X329000Y624000D01*
X329167Y623917D01*
Y623750D01*
X329000Y623667D01*
G01X333350Y622333D02*
X335850D01*
X333350Y619000D01*
X335850D01*
G01X338950Y621250D02*
X341617D01*
X341367Y621833D01*
X340950Y622167D01*
X340367Y622333D01*
X339783Y622250D01*
X339283Y622000D01*
X338950Y621417D01*
X338783Y620917D01*
Y620417D01*
X338950Y619917D01*
X339367Y619417D01*
X339867Y619083D01*
X340450Y619000D01*
X341033Y619167D01*
X341617Y619667D01*
G01X269717Y637573D02*
X270717Y634240D01*
X271800Y637573D01*
X272883Y634240D01*
X273883Y637573D01*
G01X277400D02*
Y634240D01*
G01Y638907D02*
X277233Y638990D01*
Y639157D01*
X277400Y639240D01*
X277567Y639157D01*
Y638990D01*
X277400Y638907D01*
G01X283000Y639240D02*
Y634240D01*
G01X281833Y637573D02*
X284167D01*
G01X287183Y634240D02*
Y639240D01*
G01Y636823D02*
X287600Y637240D01*
X288017Y637490D01*
X288683Y637573D01*
X289183Y637490D01*
X289767Y637157D01*
X290017Y636657D01*
Y634240D01*
G01X294200D02*
X293700Y634323D01*
X293200Y634657D01*
X292867Y635240D01*
X292700Y635907D01*
X292867Y636573D01*
X293200Y637157D01*
X293700Y637490D01*
X294200Y637573D01*
X294700Y637490D01*
X295200Y637157D01*
X295533Y636573D01*
X295617Y635907D01*
X295533Y635240D01*
X295200Y634657D01*
X294700Y634323D01*
X294200Y634240D01*
G01X298383Y637573D02*
Y635240D01*
X298717Y634657D01*
X299217Y634323D01*
X299800Y634240D01*
X300383Y634323D01*
X300883Y634657D01*
X301217Y635240D01*
G01Y634240D02*
Y637573D01*
G01X305400Y639240D02*
Y634240D01*
G01X304233Y637573D02*
X306567D01*
G01X317933Y637157D02*
X317350Y637490D01*
X316850Y637573D01*
X316183Y637407D01*
X315683Y637073D01*
X315350Y636490D01*
X315267Y635907D01*
X315350Y635323D01*
X315683Y634823D01*
X316183Y634407D01*
X316850Y634240D01*
X317433Y634407D01*
X317933Y634740D01*
G01X322200Y634240D02*
X321700Y634323D01*
X321200Y634657D01*
X320867Y635240D01*
X320700Y635907D01*
X320867Y636573D01*
X321200Y637157D01*
X321700Y637490D01*
X322200Y637573D01*
X322700Y637490D01*
X323200Y637157D01*
X323533Y636573D01*
X323617Y635907D01*
X323533Y635240D01*
X323200Y634657D01*
X322700Y634323D01*
X322200Y634240D01*
G01X326383D02*
Y637573D01*
G01Y636740D02*
X326717Y637157D01*
X327217Y637490D01*
X327883Y637573D01*
X328467Y637490D01*
X328967Y637157D01*
X329217Y636573D01*
Y634240D01*
G01X331983D02*
Y637573D01*
G01Y636740D02*
X332317Y637157D01*
X332817Y637490D01*
X333483Y637573D01*
X334067Y637490D01*
X334567Y637157D01*
X334817Y636573D01*
Y634240D01*
G01X337750Y636490D02*
X340417D01*
X340167Y637073D01*
X339750Y637407D01*
X339167Y637573D01*
X338583Y637490D01*
X338083Y637240D01*
X337750Y636657D01*
X337583Y636157D01*
Y635657D01*
X337750Y635157D01*
X338167Y634657D01*
X338667Y634323D01*
X339250Y634240D01*
X339833Y634407D01*
X340417Y634907D01*
G01X345933Y637157D02*
X345350Y637490D01*
X344850Y637573D01*
X344183Y637407D01*
X343683Y637073D01*
X343350Y636490D01*
X343267Y635907D01*
X343350Y635323D01*
X343683Y634823D01*
X344183Y634407D01*
X344850Y634240D01*
X345433Y634407D01*
X345933Y634740D01*
G01X350200Y639240D02*
Y634240D01*
G01X349033Y637573D02*
X351367D01*
G01X355800D02*
Y634240D01*
G01Y638907D02*
X355633Y638990D01*
Y639157D01*
X355800Y639240D01*
X355967Y639157D01*
Y638990D01*
X355800Y638907D01*
G01X359983Y634240D02*
Y637573D01*
G01Y636740D02*
X360317Y637157D01*
X360817Y637490D01*
X361483Y637573D01*
X362067Y637490D01*
X362567Y637157D01*
X362817Y636573D01*
Y634240D01*
G01X365833Y632990D02*
X366417Y632657D01*
X367083Y632573D01*
X367667Y632657D01*
X368167Y633073D01*
X368500Y633657D01*
Y637573D01*
G01Y636907D02*
X368167Y637240D01*
X367667Y637490D01*
X367083Y637573D01*
X366417Y637407D01*
X366000Y637073D01*
X365667Y636490D01*
X365500Y635907D01*
X365583Y635407D01*
X365917Y634823D01*
X366417Y634407D01*
X367083Y634240D01*
X367583Y634323D01*
X368167Y634657D01*
X368500Y634990D01*
G01X378200Y639240D02*
Y634240D01*
G01X377033Y637573D02*
X379367D01*
G01X383800Y634240D02*
X383300Y634323D01*
X382800Y634657D01*
X382467Y635240D01*
X382300Y635907D01*
X382467Y636573D01*
X382800Y637157D01*
X383300Y637490D01*
X383800Y637573D01*
X384300Y637490D01*
X384800Y637157D01*
X385133Y636573D01*
X385217Y635907D01*
X385133Y635240D01*
X384800Y634657D01*
X384300Y634323D01*
X383800Y634240D01*
G01X395000D02*
X394500Y634323D01*
X394000Y634657D01*
X393667Y635240D01*
X393500Y635907D01*
X393667Y636573D01*
X394000Y637157D01*
X394500Y637490D01*
X395000Y637573D01*
X395500Y637490D01*
X396000Y637157D01*
X396333Y636573D01*
X396417Y635907D01*
X396333Y635240D01*
X396000Y634657D01*
X395500Y634323D01*
X395000Y634240D01*
G01X400600Y639240D02*
Y634240D01*
G01X399433Y637573D02*
X401767D01*
G01X404783Y634240D02*
Y639240D01*
G01Y636823D02*
X405200Y637240D01*
X405617Y637490D01*
X406283Y637573D01*
X406783Y637490D01*
X407367Y637157D01*
X407617Y636657D01*
Y634240D01*
G01X410550Y636490D02*
X413217D01*
X412967Y637073D01*
X412550Y637407D01*
X411967Y637573D01*
X411383Y637490D01*
X410883Y637240D01*
X410550Y636657D01*
X410383Y636157D01*
Y635657D01*
X410550Y635157D01*
X410967Y634657D01*
X411467Y634323D01*
X412050Y634240D01*
X412633Y634407D01*
X413217Y634907D01*
G01X416233Y634240D02*
Y637573D01*
G01Y636907D02*
X416650Y637240D01*
X417067Y637490D01*
X417650Y637573D01*
X418067Y637490D01*
X418567Y637240D01*
G01X428600Y634240D02*
Y639240D01*
G01X435700Y634240D02*
Y637573D01*
G01Y636990D02*
X435367Y637323D01*
X434867Y637490D01*
X434283Y637573D01*
X433700Y637407D01*
X433200Y637073D01*
X432867Y636573D01*
X432700Y635907D01*
X432867Y635240D01*
X433200Y634740D01*
X433700Y634407D01*
X434283Y634240D01*
X434867Y634323D01*
X435367Y634573D01*
X435700Y634907D01*
G01X438050Y632740D02*
X438550Y632573D01*
X439217Y632740D01*
X439633Y633073D01*
X439967Y633490D01*
X440467Y634823D01*
X441550Y637573D01*
G01X438883D02*
X440467Y634823D01*
G01X444150Y636490D02*
X446817D01*
X446567Y637073D01*
X446150Y637407D01*
X445567Y637573D01*
X444983Y637490D01*
X444483Y637240D01*
X444150Y636657D01*
X443983Y636157D01*
Y635657D01*
X444150Y635157D01*
X444567Y634657D01*
X445067Y634323D01*
X445650Y634240D01*
X446233Y634407D01*
X446817Y634907D01*
G01X449833Y634240D02*
Y637573D01*
G01Y636907D02*
X450250Y637240D01*
X450667Y637490D01*
X451250Y637573D01*
X451667Y637490D01*
X452167Y637240D01*
G01X455350Y634823D02*
X455767Y634490D01*
X456350Y634240D01*
X456850D01*
X457350Y634407D01*
X457683Y634657D01*
X457850Y634990D01*
X457767Y635490D01*
X457433Y635740D01*
X455933Y636240D01*
X455600Y636823D01*
X455767Y637240D01*
X456100Y637490D01*
X456600Y637573D01*
X457100Y637490D01*
X457600Y637240D01*
G01X462617Y632573D02*
X463450Y633407D01*
X463867Y634240D01*
Y637573D01*
X463450Y638407D01*
X462617Y639240D01*
G01X270257Y644950D02*
Y649950D01*
X271923D01*
X272590Y649700D01*
X273090Y649367D01*
X273507Y648867D01*
X273840Y648283D01*
X273923Y647450D01*
X273840Y646617D01*
X273507Y646033D01*
X273090Y645533D01*
X272590Y645200D01*
X271923Y644950D01*
X270257D01*
G01X276440Y647200D02*
X279107D01*
X278857Y647783D01*
X278440Y648117D01*
X277857Y648283D01*
X277273Y648200D01*
X276773Y647950D01*
X276440Y647367D01*
X276273Y646867D01*
Y646367D01*
X276440Y645867D01*
X276857Y645367D01*
X277357Y645033D01*
X277940Y644950D01*
X278523Y645117D01*
X279107Y645617D01*
G01X283290Y644950D02*
Y649950D01*
G01X287640Y647200D02*
X290307D01*
X290057Y647783D01*
X289640Y648117D01*
X289057Y648283D01*
X288473Y648200D01*
X287973Y647950D01*
X287640Y647367D01*
X287473Y646867D01*
Y646367D01*
X287640Y645867D01*
X288057Y645367D01*
X288557Y645033D01*
X289140Y644950D01*
X289723Y645117D01*
X290307Y645617D01*
G01X294490Y649950D02*
Y644950D01*
G01X293323Y648283D02*
X295657D01*
G01X298840Y647200D02*
X301507D01*
X301257Y647783D01*
X300840Y648117D01*
X300257Y648283D01*
X299673Y648200D01*
X299173Y647950D01*
X298840Y647367D01*
X298673Y646867D01*
Y646367D01*
X298840Y645867D01*
X299257Y645367D01*
X299757Y645033D01*
X300340Y644950D01*
X300923Y645117D01*
X301507Y645617D01*
G01X309873Y644950D02*
Y648283D01*
G01Y647450D02*
X310207Y647867D01*
X310707Y648200D01*
X311373Y648283D01*
X311957Y648200D01*
X312457Y647867D01*
X312707Y647283D01*
Y644950D01*
G01X316890D02*
X316390Y645033D01*
X315890Y645367D01*
X315557Y645950D01*
X315390Y646617D01*
X315557Y647283D01*
X315890Y647867D01*
X316390Y648200D01*
X316890Y648283D01*
X317390Y648200D01*
X317890Y647867D01*
X318223Y647283D01*
X318307Y646617D01*
X318223Y645950D01*
X317890Y645367D01*
X317390Y645033D01*
X316890Y644950D01*
G01X321073D02*
Y648283D01*
G01Y647450D02*
X321407Y647867D01*
X321907Y648200D01*
X322573Y648283D01*
X323157Y648200D01*
X323657Y647867D01*
X323907Y647283D01*
Y644950D01*
G01X327007Y646617D02*
X329173D01*
G01X333190Y644950D02*
Y649200D01*
X333357Y649617D01*
X333690Y649867D01*
X334190Y649950D01*
X334690Y649783D01*
X334940Y649367D01*
G01X333940Y647950D02*
X332273D01*
G01X337873Y648283D02*
Y645950D01*
X338207Y645367D01*
X338707Y645033D01*
X339290Y644950D01*
X339873Y645033D01*
X340373Y645367D01*
X340707Y645950D01*
G01Y644950D02*
Y648283D01*
G01X343473Y644950D02*
Y648283D01*
G01Y647450D02*
X343807Y647867D01*
X344307Y648200D01*
X344973Y648283D01*
X345557Y648200D01*
X346057Y647867D01*
X346307Y647283D01*
Y644950D01*
G01X351823Y647867D02*
X351240Y648200D01*
X350740Y648283D01*
X350073Y648117D01*
X349573Y647783D01*
X349240Y647200D01*
X349157Y646617D01*
X349240Y646033D01*
X349573Y645533D01*
X350073Y645117D01*
X350740Y644950D01*
X351323Y645117D01*
X351823Y645450D01*
G01X356090Y649950D02*
Y644950D01*
G01X354923Y648283D02*
X357257D01*
G01X361690D02*
Y644950D01*
G01Y649617D02*
X361523Y649700D01*
Y649867D01*
X361690Y649950D01*
X361857Y649867D01*
Y649700D01*
X361690Y649617D01*
G01X367290Y644950D02*
X366790Y645033D01*
X366290Y645367D01*
X365957Y645950D01*
X365790Y646617D01*
X365957Y647283D01*
X366290Y647867D01*
X366790Y648200D01*
X367290Y648283D01*
X367790Y648200D01*
X368290Y647867D01*
X368623Y647283D01*
X368707Y646617D01*
X368623Y645950D01*
X368290Y645367D01*
X367790Y645033D01*
X367290Y644950D01*
G01X371473D02*
Y648283D01*
G01Y647450D02*
X371807Y647867D01*
X372307Y648200D01*
X372973Y648283D01*
X373557Y648200D01*
X374057Y647867D01*
X374307Y647283D01*
Y644950D01*
G01X379990D02*
Y648283D01*
G01Y647700D02*
X379657Y648033D01*
X379157Y648200D01*
X378573Y648283D01*
X377990Y648117D01*
X377490Y647783D01*
X377157Y647283D01*
X376990Y646617D01*
X377157Y645950D01*
X377490Y645450D01*
X377990Y645117D01*
X378573Y644950D01*
X379157Y645033D01*
X379657Y645283D01*
X379990Y645617D01*
G01X384090Y644950D02*
Y649950D01*
G01X393790Y643283D02*
Y648283D01*
G01Y647533D02*
X394207Y647950D01*
X394623Y648200D01*
X395290Y648283D01*
X395873Y648200D01*
X396457Y647783D01*
X396707Y647200D01*
X396790Y646617D01*
X396707Y646033D01*
X396457Y645450D01*
X395957Y645117D01*
X395290Y644950D01*
X394707Y645033D01*
X394123Y645283D01*
X393790Y645617D01*
G01X402390Y644950D02*
Y648283D01*
G01Y647700D02*
X402057Y648033D01*
X401557Y648200D01*
X400973Y648283D01*
X400390Y648117D01*
X399890Y647783D01*
X399557Y647283D01*
X399390Y646617D01*
X399557Y645950D01*
X399890Y645450D01*
X400390Y645117D01*
X400973Y644950D01*
X401557Y645033D01*
X402057Y645283D01*
X402390Y645617D01*
G01X407990Y649950D02*
Y644950D01*
G01Y645700D02*
X407657Y645283D01*
X407157Y645033D01*
X406573Y644950D01*
X405907Y645117D01*
X405407Y645533D01*
X405073Y646033D01*
X404990Y646617D01*
X405073Y647200D01*
X405407Y647700D01*
X405907Y648117D01*
X406573Y648283D01*
X407157Y648200D01*
X407573Y648033D01*
X407990Y647700D01*
G01X417690Y648283D02*
Y644950D01*
G01Y649617D02*
X417523Y649700D01*
Y649867D01*
X417690Y649950D01*
X417857Y649867D01*
Y649700D01*
X417690Y649617D01*
G01X421873Y644950D02*
Y648283D01*
G01Y647450D02*
X422207Y647867D01*
X422707Y648200D01*
X423373Y648283D01*
X423957Y648200D01*
X424457Y647867D01*
X424707Y647283D01*
Y644950D01*
G01X435990D02*
Y648283D01*
G01Y647700D02*
X435657Y648033D01*
X435157Y648200D01*
X434573Y648283D01*
X433990Y648117D01*
X433490Y647783D01*
X433157Y647283D01*
X432990Y646617D01*
X433157Y645950D01*
X433490Y645450D01*
X433990Y645117D01*
X434573Y644950D01*
X435157Y645033D01*
X435657Y645283D01*
X435990Y645617D01*
G01X440090Y644950D02*
Y649950D01*
G01X445690Y644950D02*
Y649950D01*
G01X455390Y643283D02*
Y648283D01*
G01Y647533D02*
X455807Y647950D01*
X456223Y648200D01*
X456890Y648283D01*
X457473Y648200D01*
X458057Y647783D01*
X458307Y647200D01*
X458390Y646617D01*
X458307Y646033D01*
X458057Y645450D01*
X457557Y645117D01*
X456890Y644950D01*
X456307Y645033D01*
X455723Y645283D01*
X455390Y645617D01*
G01X461323Y644950D02*
Y648283D01*
G01Y647617D02*
X461740Y647950D01*
X462157Y648200D01*
X462740Y648283D01*
X463157Y648200D01*
X463657Y647950D01*
G01X468090Y644950D02*
X467590Y645033D01*
X467090Y645367D01*
X466757Y645950D01*
X466590Y646617D01*
X466757Y647283D01*
X467090Y647867D01*
X467590Y648200D01*
X468090Y648283D01*
X468590Y648200D01*
X469090Y647867D01*
X469423Y647283D01*
X469507Y646617D01*
X469423Y645950D01*
X469090Y645367D01*
X468590Y645033D01*
X468090Y644950D01*
G01X475190Y649950D02*
Y644950D01*
G01Y645700D02*
X474857Y645283D01*
X474357Y645033D01*
X473773Y644950D01*
X473107Y645117D01*
X472607Y645533D01*
X472273Y646033D01*
X472190Y646617D01*
X472273Y647200D01*
X472607Y647700D01*
X473107Y648117D01*
X473773Y648283D01*
X474357Y648200D01*
X474773Y648033D01*
X475190Y647700D01*
G01X477873Y648283D02*
Y645950D01*
X478207Y645367D01*
X478707Y645033D01*
X479290Y644950D01*
X479873Y645033D01*
X480373Y645367D01*
X480707Y645950D01*
G01Y644950D02*
Y648283D01*
G01X486223Y647867D02*
X485640Y648200D01*
X485140Y648283D01*
X484473Y648117D01*
X483973Y647783D01*
X483640Y647200D01*
X483557Y646617D01*
X483640Y646033D01*
X483973Y645533D01*
X484473Y645117D01*
X485140Y644950D01*
X485723Y645117D01*
X486223Y645450D01*
G01X490490Y649950D02*
Y644950D01*
G01X489323Y648283D02*
X491657D01*
G01X494840Y645533D02*
X495257Y645200D01*
X495840Y644950D01*
X496340D01*
X496840Y645117D01*
X497173Y645367D01*
X497340Y645700D01*
X497257Y646200D01*
X496923Y646450D01*
X495423Y646950D01*
X495090Y647533D01*
X495257Y647950D01*
X495590Y648200D01*
X496090Y648283D01*
X496590Y648200D01*
X497090Y647950D01*
G01X501690Y644783D02*
X501523Y644867D01*
Y645033D01*
X501690Y645117D01*
X501857Y645033D01*
Y644867D01*
X501690Y644783D01*
G01X506873Y643283D02*
X506040Y644117D01*
X505623Y644950D01*
Y648283D01*
X506040Y649117D01*
X506873Y649950D01*
G01X511890D02*
X513890D01*
G01X512890D02*
Y644950D01*
G01X511890D02*
X513890D01*
G01X517240Y645533D02*
X517657Y645200D01*
X518240Y644950D01*
X518740D01*
X519240Y645117D01*
X519573Y645367D01*
X519740Y645700D01*
X519657Y646200D01*
X519323Y646450D01*
X517823Y646950D01*
X517490Y647533D01*
X517657Y647950D01*
X517990Y648200D01*
X518490Y648283D01*
X518990Y648200D01*
X519490Y647950D01*
G01X524090Y644950D02*
X523590Y645033D01*
X523090Y645367D01*
X522757Y645950D01*
X522590Y646617D01*
X522757Y647283D01*
X523090Y647867D01*
X523590Y648200D01*
X524090Y648283D01*
X524590Y648200D01*
X525090Y647867D01*
X525423Y647283D01*
X525507Y646617D01*
X525423Y645950D01*
X525090Y645367D01*
X524590Y645033D01*
X524090Y644950D01*
G01X529690D02*
Y649950D01*
G01X536790Y644950D02*
Y648283D01*
G01Y647700D02*
X536457Y648033D01*
X535957Y648200D01*
X535373Y648283D01*
X534790Y648117D01*
X534290Y647783D01*
X533957Y647283D01*
X533790Y646617D01*
X533957Y645950D01*
X534290Y645450D01*
X534790Y645117D01*
X535373Y644950D01*
X535957Y645033D01*
X536457Y645283D01*
X536790Y645617D01*
G01X540890Y649950D02*
Y644950D01*
G01X539723Y648283D02*
X542057D01*
G01X545240Y647200D02*
X547907D01*
X547657Y647783D01*
X547240Y648117D01*
X546657Y648283D01*
X546073Y648200D01*
X545573Y647950D01*
X545240Y647367D01*
X545073Y646867D01*
Y646367D01*
X545240Y645867D01*
X545657Y645367D01*
X546157Y645033D01*
X546740Y644950D01*
X547323Y645117D01*
X547907Y645617D01*
G01X556190Y643283D02*
Y648283D01*
G01Y647533D02*
X556607Y647950D01*
X557023Y648200D01*
X557690Y648283D01*
X558273Y648200D01*
X558857Y647783D01*
X559107Y647200D01*
X559190Y646617D01*
X559107Y646033D01*
X558857Y645450D01*
X558357Y645117D01*
X557690Y644950D01*
X557107Y645033D01*
X556523Y645283D01*
X556190Y645617D01*
G01X564790Y644950D02*
Y648283D01*
G01Y647700D02*
X564457Y648033D01*
X563957Y648200D01*
X563373Y648283D01*
X562790Y648117D01*
X562290Y647783D01*
X561957Y647283D01*
X561790Y646617D01*
X561957Y645950D01*
X562290Y645450D01*
X562790Y645117D01*
X563373Y644950D01*
X563957Y645033D01*
X564457Y645283D01*
X564790Y645617D01*
G01X570390Y649950D02*
Y644950D01*
G01Y645700D02*
X570057Y645283D01*
X569557Y645033D01*
X568973Y644950D01*
X568307Y645117D01*
X567807Y645533D01*
X567473Y646033D01*
X567390Y646617D01*
X567473Y647200D01*
X567807Y647700D01*
X568307Y648117D01*
X568973Y648283D01*
X569557Y648200D01*
X569973Y648033D01*
X570390Y647700D01*
G01X322623Y303963D02*
X322890Y304163D01*
X323090Y304497D01*
X323223Y304963D01*
X323090Y305363D01*
X322823Y305630D01*
X322357Y305830D01*
X320557D01*
Y301830D01*
X322757D01*
X323223Y302097D01*
X323490Y302497D01*
X323623Y302963D01*
X323490Y303430D01*
X323090Y303830D01*
X322623Y303963D01*
X320557D01*
G01X320423Y351330D02*
X322090Y355330D01*
X323757Y351330D01*
G01X323157Y352730D02*
X321023D01*
G01X361117Y328537D02*
X360717Y328737D01*
X360250Y328870D01*
X359717D01*
X359117Y328670D01*
X358650Y328337D01*
X358317Y327937D01*
X358050Y327270D01*
X357983Y326670D01*
X358117Y326070D01*
X358317Y325670D01*
X358717Y325270D01*
X359183Y325003D01*
X359650Y324870D01*
X360117D01*
X360583Y325003D01*
X360983Y325203D01*
X361317Y325470D01*
G01X395000Y364500D02*
Y175500D01*
G01X402977Y229887D02*
X403310Y230137D01*
X403560Y230553D01*
X403727Y231137D01*
X403560Y231637D01*
X403227Y231970D01*
X402643Y232220D01*
X400393D01*
Y227220D01*
X403143D01*
X403727Y227553D01*
X404060Y228053D01*
X404227Y228637D01*
X404060Y229220D01*
X403560Y229720D01*
X402977Y229887D01*
X400393D01*
G01X406493Y230553D02*
Y228220D01*
X406827Y227637D01*
X407327Y227303D01*
X407910Y227220D01*
X408493Y227303D01*
X408993Y227637D01*
X409327Y228220D01*
G01Y227220D02*
Y230553D01*
G01X411010Y227220D02*
Y230553D01*
G01Y229637D02*
X411260Y230053D01*
X411677Y230387D01*
X412260Y230553D01*
X412843Y230387D01*
X413260Y230053D01*
X413510Y229637D01*
Y227220D01*
G01Y229637D02*
X413760Y230053D01*
X414177Y230387D01*
X414760Y230553D01*
X415343Y230387D01*
X415760Y230053D01*
X416010Y229553D01*
Y227220D01*
G01X417610Y225553D02*
Y230553D01*
G01Y229803D02*
X418027Y230220D01*
X418443Y230470D01*
X419110Y230553D01*
X419693Y230470D01*
X420277Y230053D01*
X420527Y229470D01*
X420610Y228887D01*
X420527Y228303D01*
X420277Y227720D01*
X419777Y227387D01*
X419110Y227220D01*
X418527Y227303D01*
X417943Y227553D01*
X417610Y227887D01*
G01X401520Y268213D02*
X403020Y264880D01*
X404520Y268213D01*
G01X408620D02*
Y264880D01*
G01Y269547D02*
X408453Y269630D01*
Y269797D01*
X408620Y269880D01*
X408787Y269797D01*
Y269630D01*
X408620Y269547D01*
G01X415720Y264880D02*
Y268213D01*
G01Y267630D02*
X415387Y267963D01*
X414887Y268130D01*
X414303Y268213D01*
X413720Y268047D01*
X413220Y267713D01*
X412887Y267213D01*
X412720Y266547D01*
X412887Y265880D01*
X413220Y265380D01*
X413720Y265047D01*
X414303Y264880D01*
X414887Y264963D01*
X415387Y265213D01*
X415720Y265547D01*
G01X401067Y277360D02*
Y282360D01*
X402733D01*
X403400Y282110D01*
X403900Y281777D01*
X404317Y281277D01*
X404650Y280693D01*
X404733Y279860D01*
X404650Y279027D01*
X404317Y278443D01*
X403900Y277943D01*
X403400Y277610D01*
X402733Y277360D01*
X401067D01*
G01X408500Y280693D02*
Y277360D01*
G01Y282027D02*
X408333Y282110D01*
Y282277D01*
X408500Y282360D01*
X408667Y282277D01*
Y282110D01*
X408500Y282027D01*
G01X411600Y277360D02*
Y280693D01*
G01Y279777D02*
X411850Y280193D01*
X412267Y280527D01*
X412850Y280693D01*
X413433Y280527D01*
X413850Y280193D01*
X414100Y279777D01*
Y277360D01*
G01Y279777D02*
X414350Y280193D01*
X414767Y280527D01*
X415350Y280693D01*
X415933Y280527D01*
X416350Y280193D01*
X416600Y279693D01*
Y277360D01*
G01X418200Y275693D02*
Y280693D01*
G01Y279943D02*
X418617Y280360D01*
X419033Y280610D01*
X419700Y280693D01*
X420283Y280610D01*
X420867Y280193D01*
X421117Y279610D01*
X421200Y279027D01*
X421117Y278443D01*
X420867Y277860D01*
X420367Y277527D01*
X419700Y277360D01*
X419117Y277443D01*
X418533Y277693D01*
X418200Y278027D01*
G01X425300Y277360D02*
Y282360D01*
G01X429650Y279610D02*
X432317D01*
X432067Y280193D01*
X431650Y280527D01*
X431067Y280693D01*
X430483Y280610D01*
X429983Y280360D01*
X429650Y279777D01*
X429483Y279277D01*
Y278777D01*
X429650Y278277D01*
X430067Y277777D01*
X430567Y277443D01*
X431150Y277360D01*
X431733Y277527D01*
X432317Y278027D01*
G01X441600Y277360D02*
Y281610D01*
X441767Y282027D01*
X442100Y282277D01*
X442600Y282360D01*
X443100Y282193D01*
X443350Y281777D01*
G01X442350Y280360D02*
X440683D01*
G01X447700Y277360D02*
X447200Y277443D01*
X446700Y277777D01*
X446367Y278360D01*
X446200Y279027D01*
X446367Y279693D01*
X446700Y280277D01*
X447200Y280610D01*
X447700Y280693D01*
X448200Y280610D01*
X448700Y280277D01*
X449033Y279693D01*
X449117Y279027D01*
X449033Y278360D01*
X448700Y277777D01*
X448200Y277443D01*
X447700Y277360D01*
G01X452133D02*
Y280693D01*
G01Y280027D02*
X452550Y280360D01*
X452967Y280610D01*
X453550Y280693D01*
X453967Y280610D01*
X454467Y280360D01*
G01X464500Y277360D02*
X464000Y277443D01*
X463500Y277777D01*
X463167Y278360D01*
X463000Y279027D01*
X463167Y279693D01*
X463500Y280277D01*
X464000Y280610D01*
X464500Y280693D01*
X465000Y280610D01*
X465500Y280277D01*
X465833Y279693D01*
X465917Y279027D01*
X465833Y278360D01*
X465500Y277777D01*
X465000Y277443D01*
X464500Y277360D01*
G01X468683Y280693D02*
Y278360D01*
X469017Y277777D01*
X469517Y277443D01*
X470100Y277360D01*
X470683Y277443D01*
X471183Y277777D01*
X471517Y278360D01*
G01Y277360D02*
Y280693D01*
G01X475700Y282360D02*
Y277360D01*
G01X474533Y280693D02*
X476867D01*
G01X480050Y279610D02*
X482717D01*
X482467Y280193D01*
X482050Y280527D01*
X481467Y280693D01*
X480883Y280610D01*
X480383Y280360D01*
X480050Y279777D01*
X479883Y279277D01*
Y278777D01*
X480050Y278277D01*
X480467Y277777D01*
X480967Y277443D01*
X481550Y277360D01*
X482133Y277527D01*
X482717Y278027D01*
G01X485733Y277360D02*
Y280693D01*
G01Y280027D02*
X486150Y280360D01*
X486567Y280610D01*
X487150Y280693D01*
X487567Y280610D01*
X488067Y280360D01*
G01X499600Y277360D02*
Y280693D01*
G01Y280110D02*
X499267Y280443D01*
X498767Y280610D01*
X498183Y280693D01*
X497600Y280527D01*
X497100Y280193D01*
X496767Y279693D01*
X496600Y279027D01*
X496767Y278360D01*
X497100Y277860D01*
X497600Y277527D01*
X498183Y277360D01*
X498767Y277443D01*
X499267Y277693D01*
X499600Y278027D01*
G01X502283Y277360D02*
Y280693D01*
G01Y279860D02*
X502617Y280277D01*
X503117Y280610D01*
X503783Y280693D01*
X504367Y280610D01*
X504867Y280277D01*
X505117Y279693D01*
Y277360D01*
G01X510800Y282360D02*
Y277360D01*
G01Y278110D02*
X510467Y277693D01*
X509967Y277443D01*
X509383Y277360D01*
X508717Y277527D01*
X508217Y277943D01*
X507883Y278443D01*
X507800Y279027D01*
X507883Y279610D01*
X508217Y280110D01*
X508717Y280527D01*
X509383Y280693D01*
X509967Y280610D01*
X510383Y280443D01*
X510800Y280110D01*
G01X520500Y280693D02*
Y277360D01*
G01Y282027D02*
X520333Y282110D01*
Y282277D01*
X520500Y282360D01*
X520667Y282277D01*
Y282110D01*
X520500Y282027D01*
G01X524683Y277360D02*
Y280693D01*
G01Y279860D02*
X525017Y280277D01*
X525517Y280610D01*
X526183Y280693D01*
X526767Y280610D01*
X527267Y280277D01*
X527517Y279693D01*
Y277360D01*
G01X530283D02*
Y280693D01*
G01Y279860D02*
X530617Y280277D01*
X531117Y280610D01*
X531783Y280693D01*
X532367Y280610D01*
X532867Y280277D01*
X533117Y279693D01*
Y277360D01*
G01X536050Y279610D02*
X538717D01*
X538467Y280193D01*
X538050Y280527D01*
X537467Y280693D01*
X536883Y280610D01*
X536383Y280360D01*
X536050Y279777D01*
X535883Y279277D01*
Y278777D01*
X536050Y278277D01*
X536467Y277777D01*
X536967Y277443D01*
X537550Y277360D01*
X538133Y277527D01*
X538717Y278027D01*
G01X541733Y277360D02*
Y280693D01*
G01Y280027D02*
X542150Y280360D01*
X542567Y280610D01*
X543150Y280693D01*
X543567Y280610D01*
X544067Y280360D01*
G01X554100Y277360D02*
Y282360D01*
G01X561200Y277360D02*
Y280693D01*
G01Y280110D02*
X560867Y280443D01*
X560367Y280610D01*
X559783Y280693D01*
X559200Y280527D01*
X558700Y280193D01*
X558367Y279693D01*
X558200Y279027D01*
X558367Y278360D01*
X558700Y277860D01*
X559200Y277527D01*
X559783Y277360D01*
X560367Y277443D01*
X560867Y277693D01*
X561200Y278027D01*
G01X564050Y277943D02*
X564467Y277610D01*
X565050Y277360D01*
X565550D01*
X566050Y277527D01*
X566383Y277777D01*
X566550Y278110D01*
X566467Y278610D01*
X566133Y278860D01*
X564633Y279360D01*
X564300Y279943D01*
X564467Y280360D01*
X564800Y280610D01*
X565300Y280693D01*
X565800Y280610D01*
X566300Y280360D01*
G01X569650Y279610D02*
X572317D01*
X572067Y280193D01*
X571650Y280527D01*
X571067Y280693D01*
X570483Y280610D01*
X569983Y280360D01*
X569650Y279777D01*
X569483Y279277D01*
Y278777D01*
X569650Y278277D01*
X570067Y277777D01*
X570567Y277443D01*
X571150Y277360D01*
X571733Y277527D01*
X572317Y278027D01*
G01X575333Y277360D02*
Y280693D01*
G01Y280027D02*
X575750Y280360D01*
X576167Y280610D01*
X576750Y280693D01*
X577167Y280610D01*
X577667Y280360D01*
G01X395000Y305500D02*
X694500D01*
G01X401777Y331927D02*
X402110Y332177D01*
X402360Y332593D01*
X402527Y333177D01*
X402360Y333677D01*
X402027Y334010D01*
X401443Y334260D01*
X399193D01*
Y329260D01*
X401943D01*
X402527Y329593D01*
X402860Y330093D01*
X403027Y330677D01*
X402860Y331260D01*
X402360Y331760D01*
X401777Y331927D01*
X399193D01*
G01X405210Y329093D02*
X408210Y334260D01*
G01X410227Y329260D02*
X412310Y334260D01*
X414393Y329260D01*
G01X413643Y331010D02*
X410977D01*
G01X395000Y337500D02*
X694500D01*
G01X400633Y358960D02*
Y353960D01*
X403967D01*
G01X409400D02*
Y357293D01*
G01Y356710D02*
X409067Y357043D01*
X408567Y357210D01*
X407983Y357293D01*
X407400Y357127D01*
X406900Y356793D01*
X406567Y356293D01*
X406400Y355627D01*
X406567Y354960D01*
X406900Y354460D01*
X407400Y354127D01*
X407983Y353960D01*
X408567Y354043D01*
X409067Y354293D01*
X409400Y354627D01*
G01X412250Y354543D02*
X412667Y354210D01*
X413250Y353960D01*
X413750D01*
X414250Y354127D01*
X414583Y354377D01*
X414750Y354710D01*
X414667Y355210D01*
X414333Y355460D01*
X412833Y355960D01*
X412500Y356543D01*
X412667Y356960D01*
X413000Y357210D01*
X413500Y357293D01*
X414000Y357210D01*
X414500Y356960D01*
G01X417850Y356210D02*
X420517D01*
X420267Y356793D01*
X419850Y357127D01*
X419267Y357293D01*
X418683Y357210D01*
X418183Y356960D01*
X417850Y356377D01*
X417683Y355877D01*
Y355377D01*
X417850Y354877D01*
X418267Y354377D01*
X418767Y354043D01*
X419350Y353960D01*
X419933Y354127D01*
X420517Y354627D01*
G01X423533Y353960D02*
Y357293D01*
G01Y356627D02*
X423950Y356960D01*
X424367Y357210D01*
X424950Y357293D01*
X425367Y357210D01*
X425867Y356960D01*
G01X434400Y357293D02*
X435900Y353960D01*
X437400Y357293D01*
G01X441500D02*
Y353960D01*
G01Y358627D02*
X441333Y358710D01*
Y358877D01*
X441500Y358960D01*
X441667Y358877D01*
Y358710D01*
X441500Y358627D01*
G01X448600Y353960D02*
Y357293D01*
G01Y356710D02*
X448267Y357043D01*
X447767Y357210D01*
X447183Y357293D01*
X446600Y357127D01*
X446100Y356793D01*
X445767Y356293D01*
X445600Y355627D01*
X445767Y354960D01*
X446100Y354460D01*
X446600Y354127D01*
X447183Y353960D01*
X447767Y354043D01*
X448267Y354293D01*
X448600Y354627D01*
G01X457050Y354543D02*
X457467Y354210D01*
X458050Y353960D01*
X458550D01*
X459050Y354127D01*
X459383Y354377D01*
X459550Y354710D01*
X459467Y355210D01*
X459133Y355460D01*
X457633Y355960D01*
X457300Y356543D01*
X457467Y356960D01*
X457800Y357210D01*
X458300Y357293D01*
X458800Y357210D01*
X459300Y356960D01*
G01X463900Y357293D02*
Y353960D01*
G01Y358627D02*
X463733Y358710D01*
Y358877D01*
X463900Y358960D01*
X464067Y358877D01*
Y358710D01*
X463900Y358627D01*
G01X468250Y357293D02*
X470750D01*
X468250Y353960D01*
X470750D01*
G01X473850Y356210D02*
X476517D01*
X476267Y356793D01*
X475850Y357127D01*
X475267Y357293D01*
X474683Y357210D01*
X474183Y356960D01*
X473850Y356377D01*
X473683Y355877D01*
Y355377D01*
X473850Y354877D01*
X474267Y354377D01*
X474767Y354043D01*
X475350Y353960D01*
X475933Y354127D01*
X476517Y354627D01*
G01X484217Y357293D02*
X485217Y353960D01*
X486300Y357293D01*
X487383Y353960D01*
X488383Y357293D01*
G01X491900D02*
Y353960D01*
G01Y358627D02*
X491733Y358710D01*
Y358877D01*
X491900Y358960D01*
X492067Y358877D01*
Y358710D01*
X491900Y358627D01*
G01X497500Y358960D02*
Y353960D01*
G01X496333Y357293D02*
X498667D01*
G01X501683Y353960D02*
Y358960D01*
G01Y356543D02*
X502100Y356960D01*
X502517Y357210D01*
X503183Y357293D01*
X503683Y357210D01*
X504267Y356877D01*
X504517Y356377D01*
Y353960D01*
G01X508700D02*
X508200Y354043D01*
X507700Y354377D01*
X507367Y354960D01*
X507200Y355627D01*
X507367Y356293D01*
X507700Y356877D01*
X508200Y357210D01*
X508700Y357293D01*
X509200Y357210D01*
X509700Y356877D01*
X510033Y356293D01*
X510117Y355627D01*
X510033Y354960D01*
X509700Y354377D01*
X509200Y354043D01*
X508700Y353960D01*
G01X512883Y357293D02*
Y354960D01*
X513217Y354377D01*
X513717Y354043D01*
X514300Y353960D01*
X514883Y354043D01*
X515383Y354377D01*
X515717Y354960D01*
G01Y353960D02*
Y357293D01*
G01X519900Y358960D02*
Y353960D01*
G01X518733Y357293D02*
X521067D01*
G01X529600Y352293D02*
Y357293D01*
G01Y356543D02*
X530017Y356960D01*
X530433Y357210D01*
X531100Y357293D01*
X531683Y357210D01*
X532267Y356793D01*
X532517Y356210D01*
X532600Y355627D01*
X532517Y355043D01*
X532267Y354460D01*
X531767Y354127D01*
X531100Y353960D01*
X530517Y354043D01*
X529933Y354293D01*
X529600Y354627D01*
G01X536700Y353960D02*
Y358960D01*
G01X543800Y353960D02*
Y357293D01*
G01Y356710D02*
X543467Y357043D01*
X542967Y357210D01*
X542383Y357293D01*
X541800Y357127D01*
X541300Y356793D01*
X540967Y356293D01*
X540800Y355627D01*
X540967Y354960D01*
X541300Y354460D01*
X541800Y354127D01*
X542383Y353960D01*
X542967Y354043D01*
X543467Y354293D01*
X543800Y354627D01*
G01X547900Y358960D02*
Y353960D01*
G01X546733Y357293D02*
X549067D01*
G01X553500D02*
Y353960D01*
G01Y358627D02*
X553333Y358710D01*
Y358877D01*
X553500Y358960D01*
X553667Y358877D01*
Y358710D01*
X553500Y358627D01*
G01X557683Y353960D02*
Y357293D01*
G01Y356460D02*
X558017Y356877D01*
X558517Y357210D01*
X559183Y357293D01*
X559767Y357210D01*
X560267Y356877D01*
X560517Y356293D01*
Y353960D01*
G01X563533Y352710D02*
X564117Y352377D01*
X564783Y352293D01*
X565367Y352377D01*
X565867Y352793D01*
X566200Y353377D01*
Y357293D01*
G01Y356627D02*
X565867Y356960D01*
X565367Y357210D01*
X564783Y357293D01*
X564117Y357127D01*
X563700Y356793D01*
X563367Y356210D01*
X563200Y355627D01*
X563283Y355127D01*
X563617Y354543D01*
X564117Y354127D01*
X564783Y353960D01*
X565283Y354043D01*
X565867Y354377D01*
X566200Y354710D01*
G01X575483Y352293D02*
X574650Y353127D01*
X574233Y353960D01*
Y357293D01*
X574650Y358127D01*
X575483Y358960D01*
G01X582167Y356627D02*
X582500Y356877D01*
X582750Y357293D01*
X582917Y357877D01*
X582750Y358377D01*
X582417Y358710D01*
X581833Y358960D01*
X579583D01*
Y353960D01*
X582333D01*
X582917Y354293D01*
X583250Y354793D01*
X583417Y355377D01*
X583250Y355960D01*
X582750Y356460D01*
X582167Y356627D01*
X579583D01*
G01X587517Y352293D02*
X588350Y353127D01*
X588767Y353960D01*
Y357293D01*
X588350Y358127D01*
X587517Y358960D01*
G01X401827Y295540D02*
X403910Y300540D01*
X405993Y295540D01*
G01X405243Y297290D02*
X402577D01*
G01X408093Y295540D02*
Y298873D01*
G01Y298040D02*
X408427Y298457D01*
X408927Y298790D01*
X409593Y298873D01*
X410177Y298790D01*
X410677Y298457D01*
X410927Y297873D01*
Y295540D01*
G01X413943Y294290D02*
X414527Y293957D01*
X415193Y293873D01*
X415777Y293957D01*
X416277Y294373D01*
X416610Y294957D01*
Y298873D01*
G01Y298207D02*
X416277Y298540D01*
X415777Y298790D01*
X415193Y298873D01*
X414527Y298707D01*
X414110Y298373D01*
X413777Y297790D01*
X413610Y297207D01*
X413693Y296707D01*
X414027Y296123D01*
X414527Y295707D01*
X415193Y295540D01*
X415693Y295623D01*
X416277Y295957D01*
X416610Y296290D01*
G01X420710Y295540D02*
Y300540D01*
G01X425060Y297790D02*
X427727D01*
X427477Y298373D01*
X427060Y298707D01*
X426477Y298873D01*
X425893Y298790D01*
X425393Y298540D01*
X425060Y297957D01*
X424893Y297457D01*
Y296957D01*
X425060Y296457D01*
X425477Y295957D01*
X425977Y295623D01*
X426560Y295540D01*
X427143Y295707D01*
X427727Y296207D01*
G01X431493Y293873D02*
X430660Y294707D01*
X430243Y295540D01*
Y298873D01*
X430660Y299707D01*
X431493Y300540D01*
G01X449127Y293873D02*
X449960Y294707D01*
X450377Y295540D01*
Y298873D01*
X449960Y299707D01*
X449127Y300540D01*
G01X404500Y666833D02*
Y663500D01*
G01Y668167D02*
X404333Y668250D01*
Y668417D01*
X404500Y668500D01*
X404667Y668417D01*
Y668250D01*
X404500Y668167D01*
G01X410100Y668500D02*
Y663500D01*
G01X408933Y666833D02*
X411267D01*
G01X414450Y665750D02*
X417117D01*
X416867Y666333D01*
X416450Y666667D01*
X415867Y666833D01*
X415283Y666750D01*
X414783Y666500D01*
X414450Y665917D01*
X414283Y665417D01*
Y664917D01*
X414450Y664417D01*
X414867Y663917D01*
X415367Y663583D01*
X415950Y663500D01*
X416533Y663667D01*
X417117Y664167D01*
G01X418800Y663500D02*
Y666833D01*
G01Y665917D02*
X419050Y666333D01*
X419467Y666667D01*
X420050Y666833D01*
X420633Y666667D01*
X421050Y666333D01*
X421300Y665917D01*
Y663500D01*
G01Y665917D02*
X421550Y666333D01*
X421967Y666667D01*
X422550Y666833D01*
X423133Y666667D01*
X423550Y666333D01*
X423800Y665833D01*
Y663500D01*
G01X444197Y299927D02*
X443797Y300127D01*
X443330Y300260D01*
X442797D01*
X442197Y300060D01*
X441730Y299727D01*
X441397Y299327D01*
X441130Y298660D01*
X441063Y298060D01*
X441197Y297460D01*
X441397Y297060D01*
X441797Y296660D01*
X442263Y296393D01*
X442730Y296260D01*
X443197D01*
X443663Y296393D01*
X444063Y296593D01*
X444397Y296860D01*
G01X595500Y-69500D02*
Y438000D01*
G01X602120Y310470D02*
Y313803D01*
G01Y312887D02*
X602370Y313303D01*
X602787Y313637D01*
X603370Y313803D01*
X603953Y313637D01*
X604370Y313303D01*
X604620Y312887D01*
Y310470D01*
G01Y312887D02*
X604870Y313303D01*
X605287Y313637D01*
X605870Y313803D01*
X606453Y313637D01*
X606870Y313303D01*
X607120Y312803D01*
Y310470D01*
G01X608803Y313803D02*
Y311470D01*
X609137Y310887D01*
X609637Y310553D01*
X610220Y310470D01*
X610803Y310553D01*
X611303Y310887D01*
X611637Y311470D01*
G01Y310470D02*
Y313803D01*
G01X614570Y311053D02*
X614987Y310720D01*
X615570Y310470D01*
X616070D01*
X616570Y310637D01*
X616903Y310887D01*
X617070Y311220D01*
X616987Y311720D01*
X616653Y311970D01*
X615153Y312470D01*
X614820Y313053D01*
X614987Y313470D01*
X615320Y313720D01*
X615820Y313803D01*
X616320Y313720D01*
X616820Y313470D01*
G01X621420Y315470D02*
Y310470D01*
G01X620253Y313803D02*
X622587D01*
G01X628687Y310470D02*
X625353Y312137D01*
X628687Y313803D01*
G01X630537Y310470D02*
X632620Y315470D01*
X634703Y310470D01*
G01X633953Y312220D02*
X631287D01*
G01X645320Y315470D02*
Y310470D01*
G01Y311220D02*
X644987Y310803D01*
X644487Y310553D01*
X643903Y310470D01*
X643237Y310637D01*
X642737Y311053D01*
X642403Y311553D01*
X642320Y312137D01*
X642403Y312720D01*
X642737Y313220D01*
X643237Y313637D01*
X643903Y313803D01*
X644487Y313720D01*
X644903Y313553D01*
X645320Y313220D01*
G01X649420Y313803D02*
Y310470D01*
G01Y315137D02*
X649253Y315220D01*
Y315387D01*
X649420Y315470D01*
X649587Y315387D01*
Y315220D01*
X649420Y315137D01*
G01X656520Y310470D02*
Y313803D01*
G01Y313220D02*
X656187Y313553D01*
X655687Y313720D01*
X655103Y313803D01*
X654520Y313637D01*
X654020Y313303D01*
X653687Y312803D01*
X653520Y312137D01*
X653687Y311470D01*
X654020Y310970D01*
X654520Y310637D01*
X655103Y310470D01*
X655687Y310553D01*
X656187Y310803D01*
X656520Y311137D01*
G01X658120Y310470D02*
Y313803D01*
G01Y312887D02*
X658370Y313303D01*
X658787Y313637D01*
X659370Y313803D01*
X659953Y313637D01*
X660370Y313303D01*
X660620Y312887D01*
Y310470D01*
G01Y312887D02*
X660870Y313303D01*
X661287Y313637D01*
X661870Y313803D01*
X662453Y313637D01*
X662870Y313303D01*
X663120Y312803D01*
Y310470D01*
G01X664970Y312720D02*
X667637D01*
X667387Y313303D01*
X666970Y313637D01*
X666387Y313803D01*
X665803Y313720D01*
X665303Y313470D01*
X664970Y312887D01*
X664803Y312387D01*
Y311887D01*
X664970Y311387D01*
X665387Y310887D01*
X665887Y310553D01*
X666470Y310470D01*
X667053Y310637D01*
X667637Y311137D01*
G01X671820Y315470D02*
Y310470D01*
G01X670653Y313803D02*
X672987D01*
G01X676170Y312720D02*
X678837D01*
X678587Y313303D01*
X678170Y313637D01*
X677587Y313803D01*
X677003Y313720D01*
X676503Y313470D01*
X676170Y312887D01*
X676003Y312387D01*
Y311887D01*
X676170Y311387D01*
X676587Y310887D01*
X677087Y310553D01*
X677670Y310470D01*
X678253Y310637D01*
X678837Y311137D01*
G01X681853Y310470D02*
Y313803D01*
G01Y313137D02*
X682270Y313470D01*
X682687Y313720D01*
X683270Y313803D01*
X683687Y313720D01*
X684187Y313470D01*
G01X602700Y319240D02*
Y324240D01*
G01Y321740D02*
X603117Y322240D01*
X603617Y322490D01*
X604117Y322573D01*
X604867Y322407D01*
X605367Y322073D01*
X605700Y321490D01*
Y320823D01*
X605533Y320157D01*
X605200Y319657D01*
X604617Y319323D01*
X604117Y319240D01*
X603617Y319323D01*
X603117Y319573D01*
X602700Y319990D01*
G01X608383Y322573D02*
Y320240D01*
X608717Y319657D01*
X609217Y319323D01*
X609800Y319240D01*
X610383Y319323D01*
X610883Y319657D01*
X611217Y320240D01*
G01Y319240D02*
Y322573D01*
G01X615400Y324240D02*
Y319240D01*
G01X614233Y322573D02*
X616567D01*
G01X627267Y321907D02*
X627600Y322157D01*
X627850Y322573D01*
X628017Y323157D01*
X627850Y323657D01*
X627517Y323990D01*
X626933Y324240D01*
X624683D01*
Y319240D01*
X627433D01*
X628017Y319573D01*
X628350Y320073D01*
X628517Y320657D01*
X628350Y321240D01*
X627850Y321740D01*
X627267Y321907D01*
X624683D01*
G01X639300Y324240D02*
Y319240D01*
G01Y319990D02*
X638967Y319573D01*
X638467Y319323D01*
X637883Y319240D01*
X637217Y319407D01*
X636717Y319823D01*
X636383Y320323D01*
X636300Y320907D01*
X636383Y321490D01*
X636717Y321990D01*
X637217Y322407D01*
X637883Y322573D01*
X638467Y322490D01*
X638883Y322323D01*
X639300Y321990D01*
G01X643400Y322573D02*
Y319240D01*
G01Y323907D02*
X643233Y323990D01*
Y324157D01*
X643400Y324240D01*
X643567Y324157D01*
Y323990D01*
X643400Y323907D01*
G01X650500Y319240D02*
Y322573D01*
G01Y321990D02*
X650167Y322323D01*
X649667Y322490D01*
X649083Y322573D01*
X648500Y322407D01*
X648000Y322073D01*
X647667Y321573D01*
X647500Y320907D01*
X647667Y320240D01*
X648000Y319740D01*
X648500Y319407D01*
X649083Y319240D01*
X649667Y319323D01*
X650167Y319573D01*
X650500Y319907D01*
G01X652100Y319240D02*
Y322573D01*
G01Y321657D02*
X652350Y322073D01*
X652767Y322407D01*
X653350Y322573D01*
X653933Y322407D01*
X654350Y322073D01*
X654600Y321657D01*
Y319240D01*
G01Y321657D02*
X654850Y322073D01*
X655267Y322407D01*
X655850Y322573D01*
X656433Y322407D01*
X656850Y322073D01*
X657100Y321573D01*
Y319240D01*
G01X658950Y321490D02*
X661617D01*
X661367Y322073D01*
X660950Y322407D01*
X660367Y322573D01*
X659783Y322490D01*
X659283Y322240D01*
X658950Y321657D01*
X658783Y321157D01*
Y320657D01*
X658950Y320157D01*
X659367Y319657D01*
X659867Y319323D01*
X660450Y319240D01*
X661033Y319407D01*
X661617Y319907D01*
G01X665800Y324240D02*
Y319240D01*
G01X664633Y322573D02*
X666967D01*
G01X670150Y321490D02*
X672817D01*
X672567Y322073D01*
X672150Y322407D01*
X671567Y322573D01*
X670983Y322490D01*
X670483Y322240D01*
X670150Y321657D01*
X669983Y321157D01*
Y320657D01*
X670150Y320157D01*
X670567Y319657D01*
X671067Y319323D01*
X671650Y319240D01*
X672233Y319407D01*
X672817Y319907D01*
G01X675833Y319240D02*
Y322573D01*
G01Y321907D02*
X676250Y322240D01*
X676667Y322490D01*
X677250Y322573D01*
X677667Y322490D01*
X678167Y322240D01*
G01X603783Y329260D02*
X607117Y330927D01*
X603783Y332593D01*
G01X609967Y330177D02*
X612133D01*
G01Y331677D02*
X609967D01*
G01X616483Y329260D02*
X616650Y330343D01*
X616900Y331260D01*
X617233Y332093D01*
X617650Y333010D01*
X618317Y334260D01*
X614983D01*
G01X622250D02*
X621583Y334093D01*
X621083Y333677D01*
X620750Y333177D01*
X620500Y332510D01*
X620417Y331760D01*
X620500Y331010D01*
X620750Y330343D01*
X621083Y329843D01*
X621583Y329427D01*
X622250Y329260D01*
X622917Y329427D01*
X623417Y329843D01*
X623750Y330343D01*
X624000Y331010D01*
X624083Y331760D01*
X624000Y332510D01*
X623750Y333177D01*
X623417Y333677D01*
X622917Y334093D01*
X622250Y334260D01*
G01X626350Y329093D02*
X629350Y334260D01*
G01X626350D02*
X625850Y334093D01*
X625600Y333843D01*
X625433Y333343D01*
X625600Y332843D01*
X625850Y332593D01*
X626350Y332427D01*
X626850Y332593D01*
X627100Y332843D01*
X627267Y333343D01*
X627100Y333843D01*
X626850Y334093D01*
X626350Y334260D01*
G01X629350Y330927D02*
X628850Y330760D01*
X628600Y330510D01*
X628433Y330010D01*
X628600Y329510D01*
X628850Y329260D01*
X629350Y329093D01*
X629850Y329260D01*
X630100Y329510D01*
X630267Y330010D01*
X630100Y330510D01*
X629850Y330760D01*
X629350Y330927D01*
G01X633283Y328343D02*
X633617Y329427D01*
G01X595500Y679000D02*
Y396000D01*
G01X590417Y860000D02*
X592500Y855000D01*
X594583Y860000D01*
G01X596267Y856000D02*
X596767Y855417D01*
X597433Y855083D01*
X598183Y855000D01*
X598850Y855083D01*
X599517Y855500D01*
X599933Y856000D01*
X600017Y856500D01*
X599850Y857083D01*
X599267Y857500D01*
X598683Y857667D01*
X597933D01*
G01X598683D02*
X599183Y857917D01*
X599600Y858333D01*
X599767Y858833D01*
X599600Y859333D01*
X599183Y859750D01*
X598433Y860000D01*
X597683Y859917D01*
X596933Y859583D01*
G01X603700Y854833D02*
X603533Y854917D01*
Y855083D01*
X603700Y855167D01*
X603867Y855083D01*
Y854917D01*
X603700Y854833D01*
G01X610300Y855000D02*
Y860000D01*
X607217Y856417D01*
X611383D01*
G01X614900Y854833D02*
X614733Y854917D01*
Y855083D01*
X614900Y855167D01*
X615067Y855083D01*
Y854917D01*
X614900Y854833D01*
G01X620500Y855000D02*
Y860000D01*
X619500Y859000D01*
G01Y855000D02*
X621500D01*
G01X641317Y859167D02*
X641817Y859667D01*
X642400Y859917D01*
X643067Y860000D01*
X643900Y859833D01*
X644483Y859417D01*
X644650Y858917D01*
X644567Y858417D01*
X644233Y858000D01*
X642567Y857167D01*
X641817Y856583D01*
X641317Y855750D01*
X641150Y855000D01*
X644650D01*
G01X648500Y860000D02*
X647833Y859833D01*
X647333Y859417D01*
X647000Y858917D01*
X646750Y858250D01*
X646667Y857500D01*
X646750Y856750D01*
X647000Y856083D01*
X647333Y855583D01*
X647833Y855167D01*
X648500Y855000D01*
X649167Y855167D01*
X649667Y855583D01*
X650000Y856083D01*
X650250Y856750D01*
X650333Y857500D01*
X650250Y858250D01*
X650000Y858917D01*
X649667Y859417D01*
X649167Y859833D01*
X648500Y860000D01*
G01X654100Y855000D02*
Y860000D01*
X653100Y859000D01*
G01Y855000D02*
X655100D01*
G01X657867Y855750D02*
X658367Y855333D01*
X658950Y855083D01*
X659700Y855000D01*
X660450Y855167D01*
X661033Y855500D01*
X661450Y856083D01*
X661533Y856750D01*
X661367Y857417D01*
X660950Y857833D01*
X660367Y858167D01*
X659783Y858250D01*
X659200Y858167D01*
X658450Y857833D01*
X658700Y860000D01*
X660950D01*
G01X663800Y854833D02*
X666800Y860000D01*
G01X670900D02*
X670233Y859833D01*
X669733Y859417D01*
X669400Y858917D01*
X669150Y858250D01*
X669067Y857500D01*
X669150Y856750D01*
X669400Y856083D01*
X669733Y855583D01*
X670233Y855167D01*
X670900Y855000D01*
X671567Y855167D01*
X672067Y855583D01*
X672400Y856083D01*
X672650Y856750D01*
X672733Y857500D01*
X672650Y858250D01*
X672400Y858917D01*
X672067Y859417D01*
X671567Y859833D01*
X670900Y860000D01*
G01X674917Y857083D02*
X675500Y857667D01*
X676000Y858000D01*
X676667Y858167D01*
X677250Y858000D01*
X677667Y857667D01*
X678000Y857167D01*
X678083Y856583D01*
X678000Y856083D01*
X677667Y855583D01*
X677167Y855167D01*
X676583Y855000D01*
X675917Y855167D01*
X675333Y855667D01*
X675000Y856417D01*
X674917Y857250D01*
X675083Y858333D01*
X675333Y858917D01*
X675750Y859500D01*
X676333Y859917D01*
X676917Y860000D01*
X677500Y859833D01*
X677917Y859417D01*
G01X605333Y-65000D02*
Y-60000D01*
X607500Y-64167D01*
X609667Y-60000D01*
Y-65000D01*
G01X611683Y-61667D02*
Y-64000D01*
X612017Y-64583D01*
X612517Y-64917D01*
X613100Y-65000D01*
X613683Y-64917D01*
X614183Y-64583D01*
X614517Y-64000D01*
G01Y-65000D02*
Y-61667D01*
G01X617450Y-64417D02*
X617867Y-64750D01*
X618450Y-65000D01*
X618950D01*
X619450Y-64833D01*
X619783Y-64583D01*
X619950Y-64250D01*
X619867Y-63750D01*
X619533Y-63500D01*
X618033Y-63000D01*
X617700Y-62417D01*
X617867Y-62000D01*
X618200Y-61750D01*
X618700Y-61667D01*
X619200Y-61750D01*
X619700Y-62000D01*
G01X624300Y-60000D02*
Y-65000D01*
G01X623133Y-61667D02*
X625467D01*
G01X635000Y-65000D02*
Y-60750D01*
X635167Y-60333D01*
X635500Y-60083D01*
X636000Y-60000D01*
X636500Y-60167D01*
X636750Y-60583D01*
G01X635750Y-62000D02*
X634083D01*
G01X641100Y-65000D02*
X640600Y-64917D01*
X640100Y-64583D01*
X639767Y-64000D01*
X639600Y-63333D01*
X639767Y-62667D01*
X640100Y-62083D01*
X640600Y-61750D01*
X641100Y-61667D01*
X641600Y-61750D01*
X642100Y-62083D01*
X642433Y-62667D01*
X642517Y-63333D01*
X642433Y-64000D01*
X642100Y-64583D01*
X641600Y-64917D01*
X641100Y-65000D01*
G01X646700D02*
Y-60000D01*
G01X652300Y-65000D02*
Y-60000D01*
G01X657900Y-65000D02*
X657400Y-64917D01*
X656900Y-64583D01*
X656567Y-64000D01*
X656400Y-63333D01*
X656567Y-62667D01*
X656900Y-62083D01*
X657400Y-61750D01*
X657900Y-61667D01*
X658400Y-61750D01*
X658900Y-62083D01*
X659233Y-62667D01*
X659317Y-63333D01*
X659233Y-64000D01*
X658900Y-64583D01*
X658400Y-64917D01*
X657900Y-65000D01*
G01X661417Y-61667D02*
X662417Y-65000D01*
X663500Y-61667D01*
X664583Y-65000D01*
X665583Y-61667D01*
G01X607500Y-28500D02*
X606833Y-28667D01*
X606333Y-29083D01*
X606000Y-29583D01*
X605750Y-30250D01*
X605667Y-31000D01*
X605750Y-31750D01*
X606000Y-32417D01*
X606333Y-32917D01*
X606833Y-33333D01*
X607500Y-33500D01*
X608167Y-33333D01*
X608667Y-32917D01*
X609000Y-32417D01*
X609250Y-31750D01*
X609333Y-31000D01*
X609250Y-30250D01*
X609000Y-29583D01*
X608667Y-29083D01*
X608167Y-28667D01*
X607500Y-28500D01*
G01X613100Y-33667D02*
X612933Y-33583D01*
Y-33417D01*
X613100Y-33333D01*
X613267Y-33417D01*
Y-33583D01*
X613100Y-33667D01*
G01X616867Y-32500D02*
X617367Y-33083D01*
X618033Y-33417D01*
X618783Y-33500D01*
X619450Y-33417D01*
X620117Y-33000D01*
X620533Y-32500D01*
X620617Y-32000D01*
X620450Y-31417D01*
X619867Y-31000D01*
X619283Y-30833D01*
X618533D01*
G01X619283D02*
X619783Y-30583D01*
X620200Y-30167D01*
X620367Y-29667D01*
X620200Y-29167D01*
X619783Y-28750D01*
X619033Y-28500D01*
X618283Y-28583D01*
X617533Y-28917D01*
G01X621800Y-31833D02*
X622633Y-30167D01*
X623467D01*
X625133Y-33500D01*
X625967D01*
X626800Y-31833D01*
G01X629900Y-28500D02*
X629233Y-28667D01*
X628733Y-29083D01*
X628400Y-29583D01*
X628150Y-30250D01*
X628067Y-31000D01*
X628150Y-31750D01*
X628400Y-32417D01*
X628733Y-32917D01*
X629233Y-33333D01*
X629900Y-33500D01*
X630567Y-33333D01*
X631067Y-32917D01*
X631400Y-32417D01*
X631650Y-31750D01*
X631733Y-31000D01*
X631650Y-30250D01*
X631400Y-29583D01*
X631067Y-29083D01*
X630567Y-28667D01*
X629900Y-28500D01*
G01X635500Y-33667D02*
X635333Y-33583D01*
Y-33417D01*
X635500Y-33333D01*
X635667Y-33417D01*
Y-33583D01*
X635500Y-33667D01*
G01X640933Y-33500D02*
X641100Y-32417D01*
X641350Y-31500D01*
X641683Y-30667D01*
X642100Y-29750D01*
X642767Y-28500D01*
X639433D01*
G01X644200Y-33500D02*
Y-30167D01*
G01Y-31083D02*
X644450Y-30667D01*
X644867Y-30333D01*
X645450Y-30167D01*
X646033Y-30333D01*
X646450Y-30667D01*
X646700Y-31083D01*
Y-33500D01*
G01Y-31083D02*
X646950Y-30667D01*
X647367Y-30333D01*
X647950Y-30167D01*
X648533Y-30333D01*
X648950Y-30667D01*
X649200Y-31167D01*
Y-33500D01*
G01X652300Y-30167D02*
Y-33500D01*
G01Y-28833D02*
X652133Y-28750D01*
Y-28583D01*
X652300Y-28500D01*
X652467Y-28583D01*
Y-28750D01*
X652300Y-28833D01*
G01X657900Y-33500D02*
Y-28500D01*
G01X609167Y-48500D02*
X605833Y-46833D01*
X609167Y-45167D01*
G01X612017Y-47583D02*
X614183D01*
G01Y-46083D02*
X612017D01*
G01X618700Y-48500D02*
Y-43500D01*
X617700Y-44500D01*
G01Y-48500D02*
X619700D01*
G01X624300Y-48667D02*
X624133Y-48583D01*
Y-48417D01*
X624300Y-48333D01*
X624467Y-48417D01*
Y-48583D01*
X624300Y-48667D01*
G01X630900Y-48500D02*
Y-43500D01*
X627817Y-47083D01*
X631983D01*
G01X633000Y-48500D02*
Y-45167D01*
G01Y-46083D02*
X633250Y-45667D01*
X633667Y-45333D01*
X634250Y-45167D01*
X634833Y-45333D01*
X635250Y-45667D01*
X635500Y-46083D01*
Y-48500D01*
G01Y-46083D02*
X635750Y-45667D01*
X636167Y-45333D01*
X636750Y-45167D01*
X637333Y-45333D01*
X637750Y-45667D01*
X638000Y-46167D01*
Y-48500D01*
G01X641100Y-45167D02*
Y-48500D01*
G01Y-43833D02*
X640933Y-43750D01*
Y-43583D01*
X641100Y-43500D01*
X641267Y-43583D01*
Y-43750D01*
X641100Y-43833D01*
G01X646700Y-48500D02*
Y-43500D01*
G01X607500Y-15000D02*
X606833Y-15167D01*
X606333Y-15583D01*
X606000Y-16083D01*
X605750Y-16750D01*
X605667Y-17500D01*
X605750Y-18250D01*
X606000Y-18917D01*
X606333Y-19417D01*
X606833Y-19833D01*
X607500Y-20000D01*
X608167Y-19833D01*
X608667Y-19417D01*
X609000Y-18917D01*
X609250Y-18250D01*
X609333Y-17500D01*
X609250Y-16750D01*
X609000Y-16083D01*
X608667Y-15583D01*
X608167Y-15167D01*
X607500Y-15000D01*
G01X613100Y-20167D02*
X612933Y-20083D01*
Y-19917D01*
X613100Y-19833D01*
X613267Y-19917D01*
Y-20083D01*
X613100Y-20167D01*
G01X616867Y-19000D02*
X617367Y-19583D01*
X618033Y-19917D01*
X618783Y-20000D01*
X619450Y-19917D01*
X620117Y-19500D01*
X620533Y-19000D01*
X620617Y-18500D01*
X620450Y-17917D01*
X619867Y-17500D01*
X619283Y-17333D01*
X618533D01*
G01X619283D02*
X619783Y-17083D01*
X620200Y-16667D01*
X620367Y-16167D01*
X620200Y-15667D01*
X619783Y-15250D01*
X619033Y-15000D01*
X618283Y-15083D01*
X617533Y-15417D01*
G01X621800Y-18333D02*
X622633Y-16667D01*
X623467D01*
X625133Y-20000D01*
X625967D01*
X626800Y-18333D01*
G01X629900Y-15000D02*
X629233Y-15167D01*
X628733Y-15583D01*
X628400Y-16083D01*
X628150Y-16750D01*
X628067Y-17500D01*
X628150Y-18250D01*
X628400Y-18917D01*
X628733Y-19417D01*
X629233Y-19833D01*
X629900Y-20000D01*
X630567Y-19833D01*
X631067Y-19417D01*
X631400Y-18917D01*
X631650Y-18250D01*
X631733Y-17500D01*
X631650Y-16750D01*
X631400Y-16083D01*
X631067Y-15583D01*
X630567Y-15167D01*
X629900Y-15000D01*
G01X635500Y-20167D02*
X635333Y-20083D01*
Y-19917D01*
X635500Y-19833D01*
X635667Y-19917D01*
Y-20083D01*
X635500Y-20167D01*
G01X640933Y-20000D02*
X641100Y-18917D01*
X641350Y-18000D01*
X641683Y-17167D01*
X642100Y-16250D01*
X642767Y-15000D01*
X639433D01*
G01X644200Y-20000D02*
Y-16667D01*
G01Y-17583D02*
X644450Y-17167D01*
X644867Y-16833D01*
X645450Y-16667D01*
X646033Y-16833D01*
X646450Y-17167D01*
X646700Y-17583D01*
Y-20000D01*
G01Y-17583D02*
X646950Y-17167D01*
X647367Y-16833D01*
X647950Y-16667D01*
X648533Y-16833D01*
X648950Y-17167D01*
X649200Y-17667D01*
Y-20000D01*
G01X652300Y-16667D02*
Y-20000D01*
G01Y-15333D02*
X652133Y-15250D01*
Y-15083D01*
X652300Y-15000D01*
X652467Y-15083D01*
Y-15250D01*
X652300Y-15333D01*
G01X657900Y-20000D02*
Y-15000D01*
G01X606583Y-1833D02*
X608583D01*
G01X607500Y-750D02*
Y-2917D01*
G01X611600Y-3667D02*
X614600Y1500D01*
G01X617617Y-1833D02*
X619783D01*
G01X624300Y-3500D02*
Y1500D01*
X623300Y500D01*
G01Y-3500D02*
X625300D01*
G01X627400D02*
Y-167D01*
G01Y-1083D02*
X627650Y-667D01*
X628067Y-333D01*
X628650Y-167D01*
X629233Y-333D01*
X629650Y-667D01*
X629900Y-1083D01*
Y-3500D01*
G01Y-1083D02*
X630150Y-667D01*
X630567Y-333D01*
X631150Y-167D01*
X631733Y-333D01*
X632150Y-667D01*
X632400Y-1167D01*
Y-3500D01*
G01X635500Y-167D02*
Y-3500D01*
G01Y1167D02*
X635333Y1250D01*
Y1417D01*
X635500Y1500D01*
X635667Y1417D01*
Y1250D01*
X635500Y1167D01*
G01X641100Y-3500D02*
Y1500D01*
G01X606583Y24667D02*
X608583D01*
G01X607500Y25750D02*
Y23583D01*
G01X611600Y22833D02*
X614600Y28000D01*
G01X617617Y24667D02*
X619783D01*
G01X624300Y23000D02*
Y28000D01*
X623300Y27000D01*
G01Y23000D02*
X625300D01*
G01X627400D02*
Y26333D01*
G01Y25417D02*
X627650Y25833D01*
X628067Y26167D01*
X628650Y26333D01*
X629233Y26167D01*
X629650Y25833D01*
X629900Y25417D01*
Y23000D01*
G01Y25417D02*
X630150Y25833D01*
X630567Y26167D01*
X631150Y26333D01*
X631733Y26167D01*
X632150Y25833D01*
X632400Y25333D01*
Y23000D01*
G01X635500Y26333D02*
Y23000D01*
G01Y27667D02*
X635333Y27750D01*
Y27917D01*
X635500Y28000D01*
X635667Y27917D01*
Y27750D01*
X635500Y27667D01*
G01X641100Y23000D02*
Y28000D01*
G01X606583Y13167D02*
X608583D01*
G01X607500Y14250D02*
Y12083D01*
G01X611600Y11333D02*
X614600Y16500D01*
G01X617617Y13167D02*
X619783D01*
G01X622717Y15667D02*
X623217Y16167D01*
X623800Y16417D01*
X624467Y16500D01*
X625300Y16333D01*
X625883Y15917D01*
X626050Y15417D01*
X625967Y14917D01*
X625633Y14500D01*
X623967Y13667D01*
X623217Y13083D01*
X622717Y12250D01*
X622550Y11500D01*
X626050D01*
G01X627400D02*
Y14833D01*
G01Y13917D02*
X627650Y14333D01*
X628067Y14667D01*
X628650Y14833D01*
X629233Y14667D01*
X629650Y14333D01*
X629900Y13917D01*
Y11500D01*
G01Y13917D02*
X630150Y14333D01*
X630567Y14667D01*
X631150Y14833D01*
X631733Y14667D01*
X632150Y14333D01*
X632400Y13833D01*
Y11500D01*
G01X635500Y14833D02*
Y11500D01*
G01Y16167D02*
X635333Y16250D01*
Y16417D01*
X635500Y16500D01*
X635667Y16417D01*
Y16250D01*
X635500Y16167D01*
G01X641100Y11500D02*
Y16500D01*
G01X606583Y68167D02*
X608583D01*
G01X607500Y69250D02*
Y67083D01*
G01X611600Y66333D02*
X614600Y71500D01*
G01X617617Y68167D02*
X619783D01*
G01X624300Y66500D02*
Y71500D01*
X623300Y70500D01*
G01Y66500D02*
X625300D01*
G01X628067Y67250D02*
X628567Y66833D01*
X629150Y66583D01*
X629900Y66500D01*
X630650Y66667D01*
X631233Y67000D01*
X631650Y67583D01*
X631733Y68250D01*
X631567Y68917D01*
X631150Y69333D01*
X630567Y69667D01*
X629983Y69750D01*
X629400Y69667D01*
X628650Y69333D01*
X628900Y71500D01*
X631150D01*
G01X634000Y66333D02*
X637000Y71500D01*
G01X634000D02*
X633500Y71333D01*
X633250Y71083D01*
X633083Y70583D01*
X633250Y70083D01*
X633500Y69833D01*
X634000Y69667D01*
X634500Y69833D01*
X634750Y70083D01*
X634917Y70583D01*
X634750Y71083D01*
X634500Y71333D01*
X634000Y71500D01*
G01X637000Y68167D02*
X636500Y68000D01*
X636250Y67750D01*
X636083Y67250D01*
X636250Y66750D01*
X636500Y66500D01*
X637000Y66333D01*
X637500Y66500D01*
X637750Y66750D01*
X637917Y67250D01*
X637750Y67750D01*
X637500Y68000D01*
X637000Y68167D01*
G01X606583Y48667D02*
X608583D01*
G01X607500Y49750D02*
Y47583D01*
G01X611600Y46833D02*
X614600Y52000D01*
G01X617617Y48667D02*
X619783D01*
G01X622717Y51167D02*
X623217Y51667D01*
X623800Y51917D01*
X624467Y52000D01*
X625300Y51833D01*
X625883Y51417D01*
X626050Y50917D01*
X625967Y50417D01*
X625633Y50000D01*
X623967Y49167D01*
X623217Y48583D01*
X622717Y47750D01*
X622550Y47000D01*
X626050D01*
G01X627400D02*
Y50333D01*
G01Y49417D02*
X627650Y49833D01*
X628067Y50167D01*
X628650Y50333D01*
X629233Y50167D01*
X629650Y49833D01*
X629900Y49417D01*
Y47000D01*
G01Y49417D02*
X630150Y49833D01*
X630567Y50167D01*
X631150Y50333D01*
X631733Y50167D01*
X632150Y49833D01*
X632400Y49333D01*
Y47000D01*
G01X635500Y50333D02*
Y47000D01*
G01Y51667D02*
X635333Y51750D01*
Y51917D01*
X635500Y52000D01*
X635667Y51917D01*
Y51750D01*
X635500Y51667D01*
G01X641100Y47000D02*
Y52000D01*
G01X606583Y83167D02*
X608583D01*
G01X607500Y84250D02*
Y82083D01*
G01X611600Y81333D02*
X614600Y86500D01*
G01X617617Y83167D02*
X619783D01*
G01X624300Y81500D02*
Y86500D01*
X623300Y85500D01*
G01Y81500D02*
X625300D01*
G01X627400D02*
Y84833D01*
G01Y83917D02*
X627650Y84333D01*
X628067Y84667D01*
X628650Y84833D01*
X629233Y84667D01*
X629650Y84333D01*
X629900Y83917D01*
Y81500D01*
G01Y83917D02*
X630150Y84333D01*
X630567Y84667D01*
X631150Y84833D01*
X631733Y84667D01*
X632150Y84333D01*
X632400Y83833D01*
Y81500D01*
G01X635500Y84833D02*
Y81500D01*
G01Y86167D02*
X635333Y86250D01*
Y86417D01*
X635500Y86500D01*
X635667Y86417D01*
Y86250D01*
X635500Y86167D01*
G01X641100Y81500D02*
Y86500D01*
G01X606583Y98167D02*
X608583D01*
G01X607500Y99250D02*
Y97083D01*
G01X611600Y96333D02*
X614600Y101500D01*
G01X617617Y98167D02*
X619783D01*
G01X622717Y100667D02*
X623217Y101167D01*
X623800Y101417D01*
X624467Y101500D01*
X625300Y101333D01*
X625883Y100917D01*
X626050Y100417D01*
X625967Y99917D01*
X625633Y99500D01*
X623967Y98667D01*
X623217Y98083D01*
X622717Y97250D01*
X622550Y96500D01*
X626050D01*
G01X629900Y101500D02*
X629233Y101333D01*
X628733Y100917D01*
X628400Y100417D01*
X628150Y99750D01*
X628067Y99000D01*
X628150Y98250D01*
X628400Y97583D01*
X628733Y97083D01*
X629233Y96667D01*
X629900Y96500D01*
X630567Y96667D01*
X631067Y97083D01*
X631400Y97583D01*
X631650Y98250D01*
X631733Y99000D01*
X631650Y99750D01*
X631400Y100417D01*
X631067Y100917D01*
X630567Y101333D01*
X629900Y101500D01*
G01X634000Y96333D02*
X637000Y101500D01*
G01X634000D02*
X633500Y101333D01*
X633250Y101083D01*
X633083Y100583D01*
X633250Y100083D01*
X633500Y99833D01*
X634000Y99667D01*
X634500Y99833D01*
X634750Y100083D01*
X634917Y100583D01*
X634750Y101083D01*
X634500Y101333D01*
X634000Y101500D01*
G01X637000Y98167D02*
X636500Y98000D01*
X636250Y97750D01*
X636083Y97250D01*
X636250Y96750D01*
X636500Y96500D01*
X637000Y96333D01*
X637500Y96500D01*
X637750Y96750D01*
X637917Y97250D01*
X637750Y97750D01*
X637500Y98000D01*
X637000Y98167D01*
G01X605833Y126500D02*
X609167Y128167D01*
X605833Y129833D01*
G01X612017Y127417D02*
X614183D01*
G01Y128917D02*
X612017D01*
G01X618700Y126500D02*
Y131500D01*
X617700Y130500D01*
G01Y126500D02*
X619700D01*
G01X624300Y126333D02*
X624133Y126417D01*
Y126583D01*
X624300Y126667D01*
X624467Y126583D01*
Y126417D01*
X624300Y126333D01*
G01X629900Y131500D02*
X629233Y131333D01*
X628733Y130917D01*
X628400Y130417D01*
X628150Y129750D01*
X628067Y129000D01*
X628150Y128250D01*
X628400Y127583D01*
X628733Y127083D01*
X629233Y126667D01*
X629900Y126500D01*
X630567Y126667D01*
X631067Y127083D01*
X631400Y127583D01*
X631650Y128250D01*
X631733Y129000D01*
X631650Y129750D01*
X631400Y130417D01*
X631067Y130917D01*
X630567Y131333D01*
X629900Y131500D01*
G01X633000Y126500D02*
Y129833D01*
G01Y128917D02*
X633250Y129333D01*
X633667Y129667D01*
X634250Y129833D01*
X634833Y129667D01*
X635250Y129333D01*
X635500Y128917D01*
Y126500D01*
G01Y128917D02*
X635750Y129333D01*
X636167Y129667D01*
X636750Y129833D01*
X637333Y129667D01*
X637750Y129333D01*
X638000Y128833D01*
Y126500D01*
G01X641100Y129833D02*
Y126500D01*
G01Y131167D02*
X640933Y131250D01*
Y131417D01*
X641100Y131500D01*
X641267Y131417D01*
Y131250D01*
X641100Y131167D01*
G01X646700Y126500D02*
Y131500D01*
G01X606583Y113167D02*
X608583D01*
G01X607500Y114250D02*
Y112083D01*
G01X611600Y111333D02*
X614600Y116500D01*
G01X617617Y113167D02*
X619783D01*
G01X622467Y112500D02*
X622967Y111917D01*
X623633Y111583D01*
X624383Y111500D01*
X625050Y111583D01*
X625717Y112000D01*
X626133Y112500D01*
X626217Y113000D01*
X626050Y113583D01*
X625467Y114000D01*
X624883Y114167D01*
X624133D01*
G01X624883D02*
X625383Y114417D01*
X625800Y114833D01*
X625967Y115333D01*
X625800Y115833D01*
X625383Y116250D01*
X624633Y116500D01*
X623883Y116417D01*
X623133Y116083D01*
G01X627400Y111500D02*
Y114833D01*
G01Y113917D02*
X627650Y114333D01*
X628067Y114667D01*
X628650Y114833D01*
X629233Y114667D01*
X629650Y114333D01*
X629900Y113917D01*
Y111500D01*
G01Y113917D02*
X630150Y114333D01*
X630567Y114667D01*
X631150Y114833D01*
X631733Y114667D01*
X632150Y114333D01*
X632400Y113833D01*
Y111500D01*
G01X635500Y114833D02*
Y111500D01*
G01Y116167D02*
X635333Y116250D01*
Y116417D01*
X635500Y116500D01*
X635667Y116417D01*
Y116250D01*
X635500Y116167D01*
G01X641100Y111500D02*
Y116500D01*
G01X605833Y166500D02*
X609167Y168167D01*
X605833Y169833D01*
G01X612017Y167417D02*
X614183D01*
G01Y168917D02*
X612017D01*
G01X618700Y166500D02*
Y171500D01*
X617700Y170500D01*
G01Y166500D02*
X619700D01*
G01X624300Y166333D02*
X624133Y166417D01*
Y166583D01*
X624300Y166667D01*
X624467Y166583D01*
Y166417D01*
X624300Y166333D01*
G01X628067Y167500D02*
X628567Y166917D01*
X629233Y166583D01*
X629983Y166500D01*
X630650Y166583D01*
X631317Y167000D01*
X631733Y167500D01*
X631817Y168000D01*
X631650Y168583D01*
X631067Y169000D01*
X630483Y169167D01*
X629733D01*
G01X630483D02*
X630983Y169417D01*
X631400Y169833D01*
X631567Y170333D01*
X631400Y170833D01*
X630983Y171250D01*
X630233Y171500D01*
X629483Y171417D01*
X628733Y171083D01*
G01X633000Y166500D02*
Y169833D01*
G01Y168917D02*
X633250Y169333D01*
X633667Y169667D01*
X634250Y169833D01*
X634833Y169667D01*
X635250Y169333D01*
X635500Y168917D01*
Y166500D01*
G01Y168917D02*
X635750Y169333D01*
X636167Y169667D01*
X636750Y169833D01*
X637333Y169667D01*
X637750Y169333D01*
X638000Y168833D01*
Y166500D01*
G01X641100Y169833D02*
Y166500D01*
G01Y171167D02*
X640933Y171250D01*
Y171417D01*
X641100Y171500D01*
X641267Y171417D01*
Y171250D01*
X641100Y171167D01*
G01X646700Y166500D02*
Y171500D01*
G01X605833Y144000D02*
X609167Y145667D01*
X605833Y147333D01*
G01X612017Y144917D02*
X614183D01*
G01Y146417D02*
X612017D01*
G01X618700Y144000D02*
Y149000D01*
X617700Y148000D01*
G01Y144000D02*
X619700D01*
G01X624300Y143833D02*
X624133Y143917D01*
Y144083D01*
X624300Y144167D01*
X624467Y144083D01*
Y143917D01*
X624300Y143833D01*
G01X628067Y144750D02*
X628567Y144333D01*
X629150Y144083D01*
X629900Y144000D01*
X630650Y144167D01*
X631233Y144500D01*
X631650Y145083D01*
X631733Y145750D01*
X631567Y146417D01*
X631150Y146833D01*
X630567Y147167D01*
X629983Y147250D01*
X629400Y147167D01*
X628650Y146833D01*
X628900Y149000D01*
X631150D01*
G01X633000Y144000D02*
Y147333D01*
G01Y146417D02*
X633250Y146833D01*
X633667Y147167D01*
X634250Y147333D01*
X634833Y147167D01*
X635250Y146833D01*
X635500Y146417D01*
Y144000D01*
G01Y146417D02*
X635750Y146833D01*
X636167Y147167D01*
X636750Y147333D01*
X637333Y147167D01*
X637750Y146833D01*
X638000Y146333D01*
Y144000D01*
G01X641100Y147333D02*
Y144000D01*
G01Y148667D02*
X640933Y148750D01*
Y148917D01*
X641100Y149000D01*
X641267Y148917D01*
Y148750D01*
X641100Y148667D01*
G01X646700Y144000D02*
Y149000D01*
G01X612977Y200490D02*
X609643Y202157D01*
X612977Y203823D01*
G01X616910Y205490D02*
X616243Y205323D01*
X615743Y204907D01*
X615410Y204407D01*
X615160Y203740D01*
X615077Y202990D01*
X615160Y202240D01*
X615410Y201573D01*
X615743Y201073D01*
X616243Y200657D01*
X616910Y200490D01*
X617577Y200657D01*
X618077Y201073D01*
X618410Y201573D01*
X618660Y202240D01*
X618743Y202990D01*
X618660Y203740D01*
X618410Y204407D01*
X618077Y204907D01*
X617577Y205323D01*
X616910Y205490D01*
G01X622510Y200323D02*
X622343Y200407D01*
Y200573D01*
X622510Y200657D01*
X622677Y200573D01*
Y200407D01*
X622510Y200323D01*
G01X626277Y201490D02*
X626777Y200907D01*
X627443Y200573D01*
X628193Y200490D01*
X628860Y200573D01*
X629527Y200990D01*
X629943Y201490D01*
X630027Y201990D01*
X629860Y202573D01*
X629277Y202990D01*
X628693Y203157D01*
X627943D01*
G01X628693D02*
X629193Y203407D01*
X629610Y203823D01*
X629777Y204323D01*
X629610Y204823D01*
X629193Y205240D01*
X628443Y205490D01*
X627693Y205407D01*
X626943Y205073D01*
G01X631210Y200490D02*
Y203823D01*
G01Y202907D02*
X631460Y203323D01*
X631877Y203657D01*
X632460Y203823D01*
X633043Y203657D01*
X633460Y203323D01*
X633710Y202907D01*
Y200490D01*
G01Y202907D02*
X633960Y203323D01*
X634377Y203657D01*
X634960Y203823D01*
X635543Y203657D01*
X635960Y203323D01*
X636210Y202823D01*
Y200490D01*
G01X639310Y203823D02*
Y200490D01*
G01Y205157D02*
X639143Y205240D01*
Y205407D01*
X639310Y205490D01*
X639477Y205407D01*
Y205240D01*
X639310Y205157D01*
G01X644910Y200490D02*
Y205490D01*
G01X612377Y255680D02*
X609043Y257347D01*
X612377Y259013D01*
G01X616310Y255680D02*
Y260680D01*
X615310Y259680D01*
G01Y255680D02*
X617310D01*
G01X619410D02*
Y259013D01*
G01Y258097D02*
X619660Y258513D01*
X620077Y258847D01*
X620660Y259013D01*
X621243Y258847D01*
X621660Y258513D01*
X621910Y258097D01*
Y255680D01*
G01Y258097D02*
X622160Y258513D01*
X622577Y258847D01*
X623160Y259013D01*
X623743Y258847D01*
X624160Y258513D01*
X624410Y258013D01*
Y255680D01*
G01X627510Y259013D02*
Y255680D01*
G01Y260347D02*
X627343Y260430D01*
Y260597D01*
X627510Y260680D01*
X627677Y260597D01*
Y260430D01*
X627510Y260347D01*
G01X633110Y255680D02*
Y260680D01*
G01X608397Y295230D02*
X605063Y296897D01*
X608397Y298563D01*
G01X610913Y295813D02*
X611497Y295397D01*
X612163Y295230D01*
X612830Y295397D01*
X613413Y295897D01*
X613830Y296647D01*
X613997Y297397D01*
Y298313D01*
X613830Y299063D01*
X613413Y299730D01*
X612913Y300063D01*
X612330Y300230D01*
X611663Y300063D01*
X611163Y299730D01*
X610830Y299230D01*
X610663Y298563D01*
X610830Y297980D01*
X611247Y297397D01*
X611747Y297063D01*
X612330Y296980D01*
X612997Y297147D01*
X613497Y297563D01*
X613997Y298313D01*
G01X617930Y300230D02*
X617263Y300063D01*
X616763Y299647D01*
X616430Y299147D01*
X616180Y298480D01*
X616097Y297730D01*
X616180Y296980D01*
X616430Y296313D01*
X616763Y295813D01*
X617263Y295397D01*
X617930Y295230D01*
X618597Y295397D01*
X619097Y295813D01*
X619430Y296313D01*
X619680Y296980D01*
X619763Y297730D01*
X619680Y298480D01*
X619430Y299147D01*
X619097Y299647D01*
X618597Y300063D01*
X617930Y300230D01*
G01X630630D02*
Y295230D01*
G01Y295980D02*
X630297Y295563D01*
X629797Y295313D01*
X629213Y295230D01*
X628547Y295397D01*
X628047Y295813D01*
X627713Y296313D01*
X627630Y296897D01*
X627713Y297480D01*
X628047Y297980D01*
X628547Y298397D01*
X629213Y298563D01*
X629797Y298480D01*
X630213Y298313D01*
X630630Y297980D01*
G01X633480Y297480D02*
X636147D01*
X635897Y298063D01*
X635480Y298397D01*
X634897Y298563D01*
X634313Y298480D01*
X633813Y298230D01*
X633480Y297647D01*
X633313Y297147D01*
Y296647D01*
X633480Y296147D01*
X633897Y295647D01*
X634397Y295313D01*
X634980Y295230D01*
X635563Y295397D01*
X636147Y295897D01*
G01X639163Y293980D02*
X639747Y293647D01*
X640413Y293563D01*
X640997Y293647D01*
X641497Y294063D01*
X641830Y294647D01*
Y298563D01*
G01Y297897D02*
X641497Y298230D01*
X640997Y298480D01*
X640413Y298563D01*
X639747Y298397D01*
X639330Y298063D01*
X638997Y297480D01*
X638830Y296897D01*
X638913Y296397D01*
X639247Y295813D01*
X639747Y295397D01*
X640413Y295230D01*
X640913Y295313D01*
X641497Y295647D01*
X641830Y295980D01*
G01X644763Y295230D02*
Y298563D01*
G01Y297897D02*
X645180Y298230D01*
X645597Y298480D01*
X646180Y298563D01*
X646597Y298480D01*
X647097Y298230D01*
G01X650280Y297480D02*
X652947D01*
X652697Y298063D01*
X652280Y298397D01*
X651697Y298563D01*
X651113Y298480D01*
X650613Y298230D01*
X650280Y297647D01*
X650113Y297147D01*
Y296647D01*
X650280Y296147D01*
X650697Y295647D01*
X651197Y295313D01*
X651780Y295230D01*
X652363Y295397D01*
X652947Y295897D01*
G01X655880Y297480D02*
X658547D01*
X658297Y298063D01*
X657880Y298397D01*
X657297Y298563D01*
X656713Y298480D01*
X656213Y298230D01*
X655880Y297647D01*
X655713Y297147D01*
Y296647D01*
X655880Y296147D01*
X656297Y295647D01*
X656797Y295313D01*
X657380Y295230D01*
X657963Y295397D01*
X658547Y295897D01*
G01X605763Y349687D02*
X607763D01*
G01X606680Y350770D02*
Y348603D01*
G01X610780Y347853D02*
X613780Y353020D01*
G01X616797Y349687D02*
X618963D01*
G01X623480Y348020D02*
Y353020D01*
X622480Y352020D01*
G01Y348020D02*
X624480D01*
G01X626580D02*
Y351353D01*
G01Y350437D02*
X626830Y350853D01*
X627247Y351187D01*
X627830Y351353D01*
X628413Y351187D01*
X628830Y350853D01*
X629080Y350437D01*
Y348020D01*
G01Y350437D02*
X629330Y350853D01*
X629747Y351187D01*
X630330Y351353D01*
X630913Y351187D01*
X631330Y350853D01*
X631580Y350353D01*
Y348020D01*
G01X634680Y351353D02*
Y348020D01*
G01Y352687D02*
X634513Y352770D01*
Y352937D01*
X634680Y353020D01*
X634847Y352937D01*
Y352770D01*
X634680Y352687D01*
G01X640280Y348020D02*
Y353020D01*
G01X608333Y393000D02*
Y398000D01*
X610500Y393833D01*
X612667Y398000D01*
Y393000D01*
G01X614683Y396333D02*
Y394000D01*
X615017Y393417D01*
X615517Y393083D01*
X616100Y393000D01*
X616683Y393083D01*
X617183Y393417D01*
X617517Y394000D01*
G01Y393000D02*
Y396333D01*
G01X620450Y393583D02*
X620867Y393250D01*
X621450Y393000D01*
X621950D01*
X622450Y393167D01*
X622783Y393417D01*
X622950Y393750D01*
X622867Y394250D01*
X622533Y394500D01*
X621033Y395000D01*
X620700Y395583D01*
X620867Y396000D01*
X621200Y396250D01*
X621700Y396333D01*
X622200Y396250D01*
X622700Y396000D01*
G01X627300Y398000D02*
Y393000D01*
G01X626133Y396333D02*
X628467D01*
G01X638000Y393000D02*
Y397250D01*
X638167Y397667D01*
X638500Y397917D01*
X639000Y398000D01*
X639500Y397833D01*
X639750Y397417D01*
G01X638750Y396000D02*
X637083D01*
G01X644100Y393000D02*
X643600Y393083D01*
X643100Y393417D01*
X642767Y394000D01*
X642600Y394667D01*
X642767Y395333D01*
X643100Y395917D01*
X643600Y396250D01*
X644100Y396333D01*
X644600Y396250D01*
X645100Y395917D01*
X645433Y395333D01*
X645517Y394667D01*
X645433Y394000D01*
X645100Y393417D01*
X644600Y393083D01*
X644100Y393000D01*
G01X649700D02*
Y398000D01*
G01X655300Y393000D02*
Y398000D01*
G01X660900Y393000D02*
X660400Y393083D01*
X659900Y393417D01*
X659567Y394000D01*
X659400Y394667D01*
X659567Y395333D01*
X659900Y395917D01*
X660400Y396250D01*
X660900Y396333D01*
X661400Y396250D01*
X661900Y395917D01*
X662233Y395333D01*
X662317Y394667D01*
X662233Y394000D01*
X661900Y393417D01*
X661400Y393083D01*
X660900Y393000D01*
G01X664417Y396333D02*
X665417Y393000D01*
X666500Y396333D01*
X667583Y393000D01*
X668583Y396333D01*
G01X605810Y429990D02*
Y434240D01*
X605977Y434657D01*
X606310Y434907D01*
X606810Y434990D01*
X607310Y434823D01*
X607560Y434407D01*
G01X606560Y432990D02*
X604893D01*
G01X611910Y429990D02*
X611410Y430073D01*
X610910Y430407D01*
X610577Y430990D01*
X610410Y431657D01*
X610577Y432323D01*
X610910Y432907D01*
X611410Y433240D01*
X611910Y433323D01*
X612410Y433240D01*
X612910Y432907D01*
X613243Y432323D01*
X613327Y431657D01*
X613243Y430990D01*
X612910Y430407D01*
X612410Y430073D01*
X611910Y429990D01*
G01X617510D02*
Y434990D01*
G01X623110Y429990D02*
Y434990D01*
G01X628710Y429990D02*
X628210Y430073D01*
X627710Y430407D01*
X627377Y430990D01*
X627210Y431657D01*
X627377Y432323D01*
X627710Y432907D01*
X628210Y433240D01*
X628710Y433323D01*
X629210Y433240D01*
X629710Y432907D01*
X630043Y432323D01*
X630127Y431657D01*
X630043Y430990D01*
X629710Y430407D01*
X629210Y430073D01*
X628710Y429990D01*
G01X632227Y433323D02*
X633227Y429990D01*
X634310Y433323D01*
X635393Y429990D01*
X636393Y433323D01*
G01X647010Y434990D02*
Y429990D01*
G01Y430740D02*
X646677Y430323D01*
X646177Y430073D01*
X645593Y429990D01*
X644927Y430157D01*
X644427Y430573D01*
X644093Y431073D01*
X644010Y431657D01*
X644093Y432240D01*
X644427Y432740D01*
X644927Y433157D01*
X645593Y433323D01*
X646177Y433240D01*
X646593Y433073D01*
X647010Y432740D01*
G01X649943Y429990D02*
Y433323D01*
G01Y432657D02*
X650360Y432990D01*
X650777Y433240D01*
X651360Y433323D01*
X651777Y433240D01*
X652277Y432990D01*
G01X658210Y429990D02*
Y433323D01*
G01Y432740D02*
X657877Y433073D01*
X657377Y433240D01*
X656793Y433323D01*
X656210Y433157D01*
X655710Y432823D01*
X655377Y432323D01*
X655210Y431657D01*
X655377Y430990D01*
X655710Y430490D01*
X656210Y430157D01*
X656793Y429990D01*
X657377Y430073D01*
X657877Y430323D01*
X658210Y430657D01*
G01X660227Y433323D02*
X661227Y429990D01*
X662310Y433323D01*
X663393Y429990D01*
X664393Y433323D01*
G01X667910D02*
Y429990D01*
G01Y434657D02*
X667743Y434740D01*
Y434907D01*
X667910Y434990D01*
X668077Y434907D01*
Y434740D01*
X667910Y434657D01*
G01X672093Y429990D02*
Y433323D01*
G01Y432490D02*
X672427Y432907D01*
X672927Y433240D01*
X673593Y433323D01*
X674177Y433240D01*
X674677Y432907D01*
X674927Y432323D01*
Y429990D01*
G01X677943Y428740D02*
X678527Y428407D01*
X679193Y428323D01*
X679777Y428407D01*
X680277Y428823D01*
X680610Y429407D01*
Y433323D01*
G01Y432657D02*
X680277Y432990D01*
X679777Y433240D01*
X679193Y433323D01*
X678527Y433157D01*
X678110Y432823D01*
X677777Y432240D01*
X677610Y431657D01*
X677693Y431157D01*
X678027Y430573D01*
X678527Y430157D01*
X679193Y429990D01*
X679693Y430073D01*
X680277Y430407D01*
X680610Y430740D01*
G01X685127Y428323D02*
X685960Y429157D01*
X686377Y429990D01*
Y433323D01*
X685960Y434157D01*
X685127Y434990D01*
G01X606903Y440587D02*
X608903D01*
G01X607820Y441670D02*
Y439503D01*
G01X611920Y438753D02*
X614920Y443920D01*
G01X617937Y440587D02*
X620103D01*
G01X622787Y439670D02*
X623287Y439253D01*
X623870Y439003D01*
X624620Y438920D01*
X625370Y439087D01*
X625953Y439420D01*
X626370Y440003D01*
X626453Y440670D01*
X626287Y441337D01*
X625870Y441753D01*
X625287Y442087D01*
X624703Y442170D01*
X624120Y442087D01*
X623370Y441753D01*
X623620Y443920D01*
X625870D01*
G01X627720Y438920D02*
Y442253D01*
G01Y441337D02*
X627970Y441753D01*
X628387Y442087D01*
X628970Y442253D01*
X629553Y442087D01*
X629970Y441753D01*
X630220Y441337D01*
Y438920D01*
G01Y441337D02*
X630470Y441753D01*
X630887Y442087D01*
X631470Y442253D01*
X632053Y442087D01*
X632470Y441753D01*
X632720Y441253D01*
Y438920D01*
G01X635820Y442253D02*
Y438920D01*
G01Y443587D02*
X635653Y443670D01*
Y443837D01*
X635820Y443920D01*
X635987Y443837D01*
Y443670D01*
X635820Y443587D01*
G01X641420Y438920D02*
Y443920D01*
G01X606583Y471667D02*
X608583D01*
G01X607500Y472750D02*
Y470583D01*
G01X611600Y469833D02*
X614600Y475000D01*
G01X617617Y471667D02*
X619783D01*
G01X622467Y470750D02*
X622967Y470333D01*
X623550Y470083D01*
X624300Y470000D01*
X625050Y470167D01*
X625633Y470500D01*
X626050Y471083D01*
X626133Y471750D01*
X625967Y472417D01*
X625550Y472833D01*
X624967Y473167D01*
X624383Y473250D01*
X623800Y473167D01*
X623050Y472833D01*
X623300Y475000D01*
X625550D01*
G01X627400Y470000D02*
Y473333D01*
G01Y472417D02*
X627650Y472833D01*
X628067Y473167D01*
X628650Y473333D01*
X629233Y473167D01*
X629650Y472833D01*
X629900Y472417D01*
Y470000D01*
G01Y472417D02*
X630150Y472833D01*
X630567Y473167D01*
X631150Y473333D01*
X631733Y473167D01*
X632150Y472833D01*
X632400Y472333D01*
Y470000D01*
G01X635500Y473333D02*
Y470000D01*
G01Y474667D02*
X635333Y474750D01*
Y474917D01*
X635500Y475000D01*
X635667Y474917D01*
Y474750D01*
X635500Y474667D01*
G01X641100Y470000D02*
Y475000D01*
G01X607500Y452000D02*
Y457000D01*
X606500Y456000D01*
G01Y452000D02*
X608500D01*
G01X613100Y451833D02*
X612933Y451917D01*
Y452083D01*
X613100Y452167D01*
X613267Y452083D01*
Y451917D01*
X613100Y451833D01*
G01X618700Y457000D02*
X618033Y456833D01*
X617533Y456417D01*
X617200Y455917D01*
X616950Y455250D01*
X616867Y454500D01*
X616950Y453750D01*
X617200Y453083D01*
X617533Y452583D01*
X618033Y452167D01*
X618700Y452000D01*
X619367Y452167D01*
X619867Y452583D01*
X620200Y453083D01*
X620450Y453750D01*
X620533Y454500D01*
X620450Y455250D01*
X620200Y455917D01*
X619867Y456417D01*
X619367Y456833D01*
X618700Y457000D01*
G01X621800Y452000D02*
Y455333D01*
G01Y454417D02*
X622050Y454833D01*
X622467Y455167D01*
X623050Y455333D01*
X623633Y455167D01*
X624050Y454833D01*
X624300Y454417D01*
Y452000D01*
G01Y454417D02*
X624550Y454833D01*
X624967Y455167D01*
X625550Y455333D01*
X626133Y455167D01*
X626550Y454833D01*
X626800Y454333D01*
Y452000D01*
G01X629900Y455333D02*
Y452000D01*
G01Y456667D02*
X629733Y456750D01*
Y456917D01*
X629900Y457000D01*
X630067Y456917D01*
Y456750D01*
X629900Y456667D01*
G01X635500Y452000D02*
Y457000D01*
G01X644200Y452000D02*
Y455333D01*
G01Y454417D02*
X644450Y454833D01*
X644867Y455167D01*
X645450Y455333D01*
X646033Y455167D01*
X646450Y454833D01*
X646700Y454417D01*
Y452000D01*
G01Y454417D02*
X646950Y454833D01*
X647367Y455167D01*
X647950Y455333D01*
X648533Y455167D01*
X648950Y454833D01*
X649200Y454333D01*
Y452000D01*
G01X653800D02*
Y455333D01*
G01Y454750D02*
X653467Y455083D01*
X652967Y455250D01*
X652383Y455333D01*
X651800Y455167D01*
X651300Y454833D01*
X650967Y454333D01*
X650800Y453667D01*
X650967Y453000D01*
X651300Y452500D01*
X651800Y452167D01*
X652383Y452000D01*
X652967Y452083D01*
X653467Y452333D01*
X653800Y452667D01*
G01X656650Y455333D02*
X659150Y452000D01*
G01Y455333D02*
X656650Y452000D01*
G01X606583Y486667D02*
X608583D01*
G01X607500Y487750D02*
Y485583D01*
G01X611600Y484833D02*
X614600Y490000D01*
G01X617617Y486667D02*
X619783D01*
G01X622467Y485750D02*
X622967Y485333D01*
X623550Y485083D01*
X624300Y485000D01*
X625050Y485167D01*
X625633Y485500D01*
X626050Y486083D01*
X626133Y486750D01*
X625967Y487417D01*
X625550Y487833D01*
X624967Y488167D01*
X624383Y488250D01*
X623800Y488167D01*
X623050Y487833D01*
X623300Y490000D01*
X625550D01*
G01X627400Y485000D02*
Y488333D01*
G01Y487417D02*
X627650Y487833D01*
X628067Y488167D01*
X628650Y488333D01*
X629233Y488167D01*
X629650Y487833D01*
X629900Y487417D01*
Y485000D01*
G01Y487417D02*
X630150Y487833D01*
X630567Y488167D01*
X631150Y488333D01*
X631733Y488167D01*
X632150Y487833D01*
X632400Y487333D01*
Y485000D01*
G01X635500Y488333D02*
Y485000D01*
G01Y489667D02*
X635333Y489750D01*
Y489917D01*
X635500Y490000D01*
X635667Y489917D01*
Y489750D01*
X635500Y489667D01*
G01X641100Y485000D02*
Y490000D01*
G01X606583Y501667D02*
X608583D01*
G01X607500Y502750D02*
Y500583D01*
G01X611267Y501000D02*
X611767Y500417D01*
X612433Y500083D01*
X613183Y500000D01*
X613850Y500083D01*
X614517Y500500D01*
X614933Y501000D01*
X615017Y501500D01*
X614850Y502083D01*
X614267Y502500D01*
X613683Y502667D01*
X612933D01*
G01X613683D02*
X614183Y502917D01*
X614600Y503333D01*
X614767Y503833D01*
X614600Y504333D01*
X614183Y504750D01*
X613433Y505000D01*
X612683Y504917D01*
X611933Y504583D01*
G01X617200Y499833D02*
X620200Y505000D01*
G01X623217Y501667D02*
X625383D01*
G01X629900Y505000D02*
X629233Y504833D01*
X628733Y504417D01*
X628400Y503917D01*
X628150Y503250D01*
X628067Y502500D01*
X628150Y501750D01*
X628400Y501083D01*
X628733Y500583D01*
X629233Y500167D01*
X629900Y500000D01*
X630567Y500167D01*
X631067Y500583D01*
X631400Y501083D01*
X631650Y501750D01*
X631733Y502500D01*
X631650Y503250D01*
X631400Y503917D01*
X631067Y504417D01*
X630567Y504833D01*
X629900Y505000D01*
G01X633000Y500000D02*
Y503333D01*
G01Y502417D02*
X633250Y502833D01*
X633667Y503167D01*
X634250Y503333D01*
X634833Y503167D01*
X635250Y502833D01*
X635500Y502417D01*
Y500000D01*
G01Y502417D02*
X635750Y502833D01*
X636167Y503167D01*
X636750Y503333D01*
X637333Y503167D01*
X637750Y502833D01*
X638000Y502333D01*
Y500000D01*
G01X641100Y503333D02*
Y500000D01*
G01Y504667D02*
X640933Y504750D01*
Y504917D01*
X641100Y505000D01*
X641267Y504917D01*
Y504750D01*
X641100Y504667D01*
G01X646700Y500000D02*
Y505000D01*
G01X606583Y516667D02*
X608583D01*
G01X607500Y517750D02*
Y515583D01*
G01X611600Y514833D02*
X614600Y520000D01*
G01X617617Y516667D02*
X619783D01*
G01X622717Y519167D02*
X623217Y519667D01*
X623800Y519917D01*
X624467Y520000D01*
X625300Y519833D01*
X625883Y519417D01*
X626050Y518917D01*
X625967Y518417D01*
X625633Y518000D01*
X623967Y517167D01*
X623217Y516583D01*
X622717Y515750D01*
X622550Y515000D01*
X626050D01*
G01X627400D02*
Y518333D01*
G01Y517417D02*
X627650Y517833D01*
X628067Y518167D01*
X628650Y518333D01*
X629233Y518167D01*
X629650Y517833D01*
X629900Y517417D01*
Y515000D01*
G01Y517417D02*
X630150Y517833D01*
X630567Y518167D01*
X631150Y518333D01*
X631733Y518167D01*
X632150Y517833D01*
X632400Y517333D01*
Y515000D01*
G01X635500Y518333D02*
Y515000D01*
G01Y519667D02*
X635333Y519750D01*
Y519917D01*
X635500Y520000D01*
X635667Y519917D01*
Y519750D01*
X635500Y519667D01*
G01X641100Y515000D02*
Y520000D01*
G01X606583Y530167D02*
X608583D01*
G01X607500Y531250D02*
Y529083D01*
G01X611600Y528333D02*
X614600Y533500D01*
G01X617617Y530167D02*
X619783D01*
G01X622467Y529500D02*
X622967Y528917D01*
X623633Y528583D01*
X624383Y528500D01*
X625050Y528583D01*
X625717Y529000D01*
X626133Y529500D01*
X626217Y530000D01*
X626050Y530583D01*
X625467Y531000D01*
X624883Y531167D01*
X624133D01*
G01X624883D02*
X625383Y531417D01*
X625800Y531833D01*
X625967Y532333D01*
X625800Y532833D01*
X625383Y533250D01*
X624633Y533500D01*
X623883Y533417D01*
X623133Y533083D01*
G01X627400Y528500D02*
Y531833D01*
G01Y530917D02*
X627650Y531333D01*
X628067Y531667D01*
X628650Y531833D01*
X629233Y531667D01*
X629650Y531333D01*
X629900Y530917D01*
Y528500D01*
G01Y530917D02*
X630150Y531333D01*
X630567Y531667D01*
X631150Y531833D01*
X631733Y531667D01*
X632150Y531333D01*
X632400Y530833D01*
Y528500D01*
G01X635500Y531833D02*
Y528500D01*
G01Y533167D02*
X635333Y533250D01*
Y533417D01*
X635500Y533500D01*
X635667Y533417D01*
Y533250D01*
X635500Y533167D01*
G01X641100Y528500D02*
Y533500D01*
G01X606583Y546667D02*
X608583D01*
G01X607500Y547750D02*
Y545583D01*
G01X611600Y544833D02*
X614600Y550000D01*
G01X617617Y546667D02*
X619783D01*
G01X622717Y549167D02*
X623217Y549667D01*
X623800Y549917D01*
X624467Y550000D01*
X625300Y549833D01*
X625883Y549417D01*
X626050Y548917D01*
X625967Y548417D01*
X625633Y548000D01*
X623967Y547167D01*
X623217Y546583D01*
X622717Y545750D01*
X622550Y545000D01*
X626050D01*
G01X627400D02*
Y548333D01*
G01Y547417D02*
X627650Y547833D01*
X628067Y548167D01*
X628650Y548333D01*
X629233Y548167D01*
X629650Y547833D01*
X629900Y547417D01*
Y545000D01*
G01Y547417D02*
X630150Y547833D01*
X630567Y548167D01*
X631150Y548333D01*
X631733Y548167D01*
X632150Y547833D01*
X632400Y547333D01*
Y545000D01*
G01X635500Y548333D02*
Y545000D01*
G01Y549667D02*
X635333Y549750D01*
Y549917D01*
X635500Y550000D01*
X635667Y549917D01*
Y549750D01*
X635500Y549667D01*
G01X641100Y545000D02*
Y550000D01*
G01X606583Y561667D02*
X608583D01*
G01X607500Y562750D02*
Y560583D01*
G01X611600Y559833D02*
X614600Y565000D01*
G01X617617Y561667D02*
X619783D01*
G01X622717Y564167D02*
X623217Y564667D01*
X623800Y564917D01*
X624467Y565000D01*
X625300Y564833D01*
X625883Y564417D01*
X626050Y563917D01*
X625967Y563417D01*
X625633Y563000D01*
X623967Y562167D01*
X623217Y561583D01*
X622717Y560750D01*
X622550Y560000D01*
X626050D01*
G01X627400D02*
Y563333D01*
G01Y562417D02*
X627650Y562833D01*
X628067Y563167D01*
X628650Y563333D01*
X629233Y563167D01*
X629650Y562833D01*
X629900Y562417D01*
Y560000D01*
G01Y562417D02*
X630150Y562833D01*
X630567Y563167D01*
X631150Y563333D01*
X631733Y563167D01*
X632150Y562833D01*
X632400Y562333D01*
Y560000D01*
G01X635500Y563333D02*
Y560000D01*
G01Y564667D02*
X635333Y564750D01*
Y564917D01*
X635500Y565000D01*
X635667Y564917D01*
Y564750D01*
X635500Y564667D01*
G01X641100Y560000D02*
Y565000D01*
G01X606583Y575167D02*
X608583D01*
G01X607500Y576250D02*
Y574083D01*
G01X611517Y577667D02*
X612017Y578167D01*
X612600Y578417D01*
X613267Y578500D01*
X614100Y578333D01*
X614683Y577917D01*
X614850Y577417D01*
X614767Y576917D01*
X614433Y576500D01*
X612767Y575667D01*
X612017Y575083D01*
X611517Y574250D01*
X611350Y573500D01*
X614850D01*
G01X617200Y573333D02*
X620200Y578500D01*
G01X623217Y575167D02*
X625383D01*
G01X630900Y573500D02*
Y578500D01*
X627817Y574917D01*
X631983D01*
G01X633000Y573500D02*
Y576833D01*
G01Y575917D02*
X633250Y576333D01*
X633667Y576667D01*
X634250Y576833D01*
X634833Y576667D01*
X635250Y576333D01*
X635500Y575917D01*
Y573500D01*
G01Y575917D02*
X635750Y576333D01*
X636167Y576667D01*
X636750Y576833D01*
X637333Y576667D01*
X637750Y576333D01*
X638000Y575833D01*
Y573500D01*
G01X641100Y576833D02*
Y573500D01*
G01Y578167D02*
X640933Y578250D01*
Y578417D01*
X641100Y578500D01*
X641267Y578417D01*
Y578250D01*
X641100Y578167D01*
G01X646700Y573500D02*
Y578500D01*
G01X606583Y591667D02*
X608583D01*
G01X607500Y592750D02*
Y590583D01*
G01X611600Y589833D02*
X614600Y595000D01*
G01X617617Y591667D02*
X619783D01*
G01X622467Y591000D02*
X622967Y590417D01*
X623633Y590083D01*
X624383Y590000D01*
X625050Y590083D01*
X625717Y590500D01*
X626133Y591000D01*
X626217Y591500D01*
X626050Y592083D01*
X625467Y592500D01*
X624883Y592667D01*
X624133D01*
G01X624883D02*
X625383Y592917D01*
X625800Y593333D01*
X625967Y593833D01*
X625800Y594333D01*
X625383Y594750D01*
X624633Y595000D01*
X623883Y594917D01*
X623133Y594583D01*
G01X627400Y590000D02*
Y593333D01*
G01Y592417D02*
X627650Y592833D01*
X628067Y593167D01*
X628650Y593333D01*
X629233Y593167D01*
X629650Y592833D01*
X629900Y592417D01*
Y590000D01*
G01Y592417D02*
X630150Y592833D01*
X630567Y593167D01*
X631150Y593333D01*
X631733Y593167D01*
X632150Y592833D01*
X632400Y592333D01*
Y590000D01*
G01X635500Y593333D02*
Y590000D01*
G01Y594667D02*
X635333Y594750D01*
Y594917D01*
X635500Y595000D01*
X635667Y594917D01*
Y594750D01*
X635500Y594667D01*
G01X641100Y590000D02*
Y595000D01*
G01X605417Y603500D02*
X607500Y608500D01*
X609583Y603500D01*
G01X608833Y605250D02*
X606167D01*
G01X613100Y603500D02*
Y608500D01*
G01X618700Y603500D02*
Y608500D01*
G01X624300Y603500D02*
X623800Y603583D01*
X623300Y603917D01*
X622967Y604500D01*
X622800Y605167D01*
X622967Y605833D01*
X623300Y606417D01*
X623800Y606750D01*
X624300Y606833D01*
X624800Y606750D01*
X625300Y606417D01*
X625633Y605833D01*
X625717Y605167D01*
X625633Y604500D01*
X625300Y603917D01*
X624800Y603583D01*
X624300Y603500D01*
G01X627817Y606833D02*
X628817Y603500D01*
X629900Y606833D01*
X630983Y603500D01*
X631983Y606833D01*
G01X605353Y638700D02*
Y643700D01*
X607520Y639533D01*
X609687Y643700D01*
Y638700D01*
G01X611703Y642033D02*
Y639700D01*
X612037Y639117D01*
X612537Y638783D01*
X613120Y638700D01*
X613703Y638783D01*
X614203Y639117D01*
X614537Y639700D01*
G01Y638700D02*
Y642033D01*
G01X617470Y639283D02*
X617887Y638950D01*
X618470Y638700D01*
X618970D01*
X619470Y638867D01*
X619803Y639117D01*
X619970Y639450D01*
X619887Y639950D01*
X619553Y640200D01*
X618053Y640700D01*
X617720Y641283D01*
X617887Y641700D01*
X618220Y641950D01*
X618720Y642033D01*
X619220Y641950D01*
X619720Y641700D01*
G01X624320Y643700D02*
Y638700D01*
G01X623153Y642033D02*
X625487D01*
G01X635020Y638700D02*
Y642950D01*
X635187Y643367D01*
X635520Y643617D01*
X636020Y643700D01*
X636520Y643533D01*
X636770Y643117D01*
G01X635770Y641700D02*
X634103D01*
G01X641120Y638700D02*
X640620Y638783D01*
X640120Y639117D01*
X639787Y639700D01*
X639620Y640367D01*
X639787Y641033D01*
X640120Y641617D01*
X640620Y641950D01*
X641120Y642033D01*
X641620Y641950D01*
X642120Y641617D01*
X642453Y641033D01*
X642537Y640367D01*
X642453Y639700D01*
X642120Y639117D01*
X641620Y638783D01*
X641120Y638700D01*
G01X646720D02*
Y643700D01*
G01X652320Y638700D02*
Y643700D01*
G01X657920Y638700D02*
X657420Y638783D01*
X656920Y639117D01*
X656587Y639700D01*
X656420Y640367D01*
X656587Y641033D01*
X656920Y641617D01*
X657420Y641950D01*
X657920Y642033D01*
X658420Y641950D01*
X658920Y641617D01*
X659253Y641033D01*
X659337Y640367D01*
X659253Y639700D01*
X658920Y639117D01*
X658420Y638783D01*
X657920Y638700D01*
G01X661437Y642033D02*
X662437Y638700D01*
X663520Y642033D01*
X664603Y638700D01*
X665603Y642033D01*
G01X606583Y620167D02*
X608583D01*
G01X607500Y621250D02*
Y619083D01*
G01X611600Y618333D02*
X614600Y623500D01*
G01X617617Y620167D02*
X619783D01*
G01X622717Y622667D02*
X623217Y623167D01*
X623800Y623417D01*
X624467Y623500D01*
X625300Y623333D01*
X625883Y622917D01*
X626050Y622417D01*
X625967Y621917D01*
X625633Y621500D01*
X623967Y620667D01*
X623217Y620083D01*
X622717Y619250D01*
X622550Y618500D01*
X626050D01*
G01X627400D02*
Y621833D01*
G01Y620917D02*
X627650Y621333D01*
X628067Y621667D01*
X628650Y621833D01*
X629233Y621667D01*
X629650Y621333D01*
X629900Y620917D01*
Y618500D01*
G01Y620917D02*
X630150Y621333D01*
X630567Y621667D01*
X631150Y621833D01*
X631733Y621667D01*
X632150Y621333D01*
X632400Y620833D01*
Y618500D01*
G01X635500Y621833D02*
Y618500D01*
G01Y623167D02*
X635333Y623250D01*
Y623417D01*
X635500Y623500D01*
X635667Y623417D01*
Y623250D01*
X635500Y623167D01*
G01X641100Y618500D02*
Y623500D01*
G01X617500Y668500D02*
Y663500D01*
G01X615583Y668500D02*
X619417D01*
G01X623100Y663500D02*
X622600Y663583D01*
X622100Y663917D01*
X621767Y664500D01*
X621600Y665167D01*
X621767Y665833D01*
X622100Y666417D01*
X622600Y666750D01*
X623100Y666833D01*
X623600Y666750D01*
X624100Y666417D01*
X624433Y665833D01*
X624517Y665167D01*
X624433Y664500D01*
X624100Y663917D01*
X623600Y663583D01*
X623100Y663500D01*
G01X628700D02*
Y668500D01*
G01X633050Y665750D02*
X635717D01*
X635467Y666333D01*
X635050Y666667D01*
X634467Y666833D01*
X633883Y666750D01*
X633383Y666500D01*
X633050Y665917D01*
X632883Y665417D01*
Y664917D01*
X633050Y664417D01*
X633467Y663917D01*
X633967Y663583D01*
X634550Y663500D01*
X635133Y663667D01*
X635717Y664167D01*
G01X638733Y663500D02*
Y666833D01*
G01Y666167D02*
X639150Y666500D01*
X639567Y666750D01*
X640150Y666833D01*
X640567Y666750D01*
X641067Y666500D01*
G01X647000Y663500D02*
Y666833D01*
G01Y666250D02*
X646667Y666583D01*
X646167Y666750D01*
X645583Y666833D01*
X645000Y666667D01*
X644500Y666333D01*
X644167Y665833D01*
X644000Y665167D01*
X644167Y664500D01*
X644500Y664000D01*
X645000Y663667D01*
X645583Y663500D01*
X646167Y663583D01*
X646667Y663833D01*
X647000Y664167D01*
G01X649683Y663500D02*
Y666833D01*
G01Y666000D02*
X650017Y666417D01*
X650517Y666750D01*
X651183Y666833D01*
X651767Y666750D01*
X652267Y666417D01*
X652517Y665833D01*
Y663500D01*
G01X658033Y666417D02*
X657450Y666750D01*
X656950Y666833D01*
X656283Y666667D01*
X655783Y666333D01*
X655450Y665750D01*
X655367Y665167D01*
X655450Y664583D01*
X655783Y664083D01*
X656283Y663667D01*
X656950Y663500D01*
X657533Y663667D01*
X658033Y664000D01*
G01X661050Y665750D02*
X663717D01*
X663467Y666333D01*
X663050Y666667D01*
X662467Y666833D01*
X661883Y666750D01*
X661383Y666500D01*
X661050Y665917D01*
X660883Y665417D01*
Y664917D01*
X661050Y664417D01*
X661467Y663917D01*
X661967Y663583D01*
X662550Y663500D01*
X663133Y663667D01*
X663717Y664167D01*
G01X650853Y438153D02*
X650020Y438987D01*
X649603Y439820D01*
Y443153D01*
X650020Y443987D01*
X650853Y444820D01*
G01X656870Y439820D02*
X656370Y439903D01*
X655870Y440237D01*
X655537Y440820D01*
X655370Y441487D01*
X655537Y442153D01*
X655870Y442737D01*
X656370Y443070D01*
X656870Y443153D01*
X657370Y443070D01*
X657870Y442737D01*
X658203Y442153D01*
X658287Y441487D01*
X658203Y440820D01*
X657870Y440237D01*
X657370Y439903D01*
X656870Y439820D01*
G01X661303D02*
Y443153D01*
G01Y442487D02*
X661720Y442820D01*
X662137Y443070D01*
X662720Y443153D01*
X663137Y443070D01*
X663637Y442820D01*
G01X694500Y716000D02*
Y-69500D01*
G01X736937Y-65320D02*
X737437Y-65737D01*
X738020Y-65987D01*
X738770Y-66070D01*
X739520Y-65903D01*
X740103Y-65570D01*
X740520Y-64987D01*
X740603Y-64320D01*
X740437Y-63653D01*
X740020Y-63237D01*
X739437Y-62903D01*
X738853Y-62820D01*
X738270Y-62903D01*
X737520Y-63237D01*
X737770Y-61070D01*
X740020D01*
G01X744370Y-66237D02*
X744203Y-66153D01*
Y-65987D01*
X744370Y-65903D01*
X744537Y-65987D01*
Y-66153D01*
X744370Y-66237D01*
G01X749970Y-66070D02*
Y-61070D01*
X748970Y-62070D01*
G01Y-66070D02*
X750970D01*
G01X760170Y-61070D02*
X762170D01*
G01X761170D02*
Y-66070D01*
G01X760170D02*
X762170D01*
G01X766270D02*
Y-61820D01*
X766437Y-61403D01*
X766770Y-61153D01*
X767270Y-61070D01*
X767770Y-61237D01*
X768020Y-61653D01*
G01X767020Y-63070D02*
X765353D01*
G01X778470Y-63570D02*
X780137D01*
Y-65070D01*
X779637Y-65570D01*
X779053Y-65903D01*
X778220Y-66070D01*
X777387Y-65903D01*
X776803Y-65570D01*
X776303Y-65070D01*
X775970Y-64487D01*
X775803Y-63820D01*
Y-63237D01*
X775970Y-62737D01*
X776303Y-62153D01*
X776803Y-61653D01*
X777303Y-61320D01*
X777970Y-61070D01*
X778553D01*
X779220Y-61237D01*
X779720Y-61570D01*
G01X782320Y-63820D02*
X784987D01*
X784737Y-63237D01*
X784320Y-62903D01*
X783737Y-62737D01*
X783153Y-62820D01*
X782653Y-63070D01*
X782320Y-63653D01*
X782153Y-64153D01*
Y-64653D01*
X782320Y-65153D01*
X782737Y-65653D01*
X783237Y-65987D01*
X783820Y-66070D01*
X784403Y-65903D01*
X784987Y-65403D01*
G01X788003Y-66070D02*
Y-62737D01*
G01Y-63403D02*
X788420Y-63070D01*
X788837Y-62820D01*
X789420Y-62737D01*
X789837Y-62820D01*
X790337Y-63070D01*
G01X793270Y-66070D02*
Y-61070D01*
G01Y-63570D02*
X793687Y-63070D01*
X794187Y-62820D01*
X794687Y-62737D01*
X795437Y-62903D01*
X795937Y-63237D01*
X796270Y-63820D01*
Y-64487D01*
X796103Y-65153D01*
X795770Y-65653D01*
X795187Y-65987D01*
X794687Y-66070D01*
X794187Y-65987D01*
X793687Y-65737D01*
X793270Y-65320D01*
G01X799120Y-63820D02*
X801787D01*
X801537Y-63237D01*
X801120Y-62903D01*
X800537Y-62737D01*
X799953Y-62820D01*
X799453Y-63070D01*
X799120Y-63653D01*
X798953Y-64153D01*
Y-64653D01*
X799120Y-65153D01*
X799537Y-65653D01*
X800037Y-65987D01*
X800620Y-66070D01*
X801203Y-65903D01*
X801787Y-65403D01*
G01X804803Y-66070D02*
Y-62737D01*
G01Y-63403D02*
X805220Y-63070D01*
X805637Y-62820D01*
X806220Y-62737D01*
X806637Y-62820D01*
X807137Y-63070D01*
G01X815753Y-66070D02*
Y-61070D01*
G01Y-63487D02*
X816170Y-63070D01*
X816587Y-62820D01*
X817253Y-62737D01*
X817753Y-62820D01*
X818337Y-63153D01*
X818587Y-63653D01*
Y-66070D01*
G01X824270D02*
Y-62737D01*
G01Y-63320D02*
X823937Y-62987D01*
X823437Y-62820D01*
X822853Y-62737D01*
X822270Y-62903D01*
X821770Y-63237D01*
X821437Y-63737D01*
X821270Y-64403D01*
X821437Y-65070D01*
X821770Y-65570D01*
X822270Y-65903D01*
X822853Y-66070D01*
X823437Y-65987D01*
X823937Y-65737D01*
X824270Y-65403D01*
G01X827120Y-65487D02*
X827537Y-65820D01*
X828120Y-66070D01*
X828620D01*
X829120Y-65903D01*
X829453Y-65653D01*
X829620Y-65320D01*
X829537Y-64820D01*
X829203Y-64570D01*
X827703Y-64070D01*
X827370Y-63487D01*
X827537Y-63070D01*
X827870Y-62820D01*
X828370Y-62737D01*
X828870Y-62820D01*
X829370Y-63070D01*
G01X839570Y-61070D02*
Y-66070D01*
G01X838403Y-62737D02*
X840737D01*
G01X843753Y-66070D02*
Y-61070D01*
G01Y-63487D02*
X844170Y-63070D01*
X844587Y-62820D01*
X845253Y-62737D01*
X845753Y-62820D01*
X846337Y-63153D01*
X846587Y-63653D01*
Y-66070D01*
G01X850770Y-62737D02*
Y-66070D01*
G01Y-61403D02*
X850603Y-61320D01*
Y-61153D01*
X850770Y-61070D01*
X850937Y-61153D01*
Y-61320D01*
X850770Y-61403D01*
G01X855120Y-65487D02*
X855537Y-65820D01*
X856120Y-66070D01*
X856620D01*
X857120Y-65903D01*
X857453Y-65653D01*
X857620Y-65320D01*
X857537Y-64820D01*
X857203Y-64570D01*
X855703Y-64070D01*
X855370Y-63487D01*
X855537Y-63070D01*
X855870Y-62820D01*
X856370Y-62737D01*
X856870Y-62820D01*
X857370Y-63070D01*
G01X866153Y-66070D02*
Y-61070D01*
G01X868820Y-62737D02*
X866153Y-64653D01*
G01X867237Y-63903D02*
X868987Y-66070D01*
G01X873170Y-62737D02*
Y-66070D01*
G01Y-61403D02*
X873003Y-61320D01*
Y-61153D01*
X873170Y-61070D01*
X873337Y-61153D01*
Y-61320D01*
X873170Y-61403D01*
G01X877353Y-66070D02*
Y-62737D01*
G01Y-63570D02*
X877687Y-63153D01*
X878187Y-62820D01*
X878853Y-62737D01*
X879437Y-62820D01*
X879937Y-63153D01*
X880187Y-63737D01*
Y-66070D01*
G01X885870Y-61070D02*
Y-66070D01*
G01Y-65320D02*
X885537Y-65737D01*
X885037Y-65987D01*
X884453Y-66070D01*
X883787Y-65903D01*
X883287Y-65487D01*
X882953Y-64987D01*
X882870Y-64403D01*
X882953Y-63820D01*
X883287Y-63320D01*
X883787Y-62903D01*
X884453Y-62737D01*
X885037Y-62820D01*
X885453Y-62987D01*
X885870Y-63320D01*
G01X895570Y-66070D02*
X895070Y-65987D01*
X894570Y-65653D01*
X894237Y-65070D01*
X894070Y-64403D01*
X894237Y-63737D01*
X894570Y-63153D01*
X895070Y-62820D01*
X895570Y-62737D01*
X896070Y-62820D01*
X896570Y-63153D01*
X896903Y-63737D01*
X896987Y-64403D01*
X896903Y-65070D01*
X896570Y-65653D01*
X896070Y-65987D01*
X895570Y-66070D01*
G01X900670D02*
Y-61820D01*
X900837Y-61403D01*
X901170Y-61153D01*
X901670Y-61070D01*
X902170Y-61237D01*
X902420Y-61653D01*
G01X901420Y-63070D02*
X899753D01*
G01X913870Y-61070D02*
Y-66070D01*
G01Y-65320D02*
X913537Y-65737D01*
X913037Y-65987D01*
X912453Y-66070D01*
X911787Y-65903D01*
X911287Y-65487D01*
X910953Y-64987D01*
X910870Y-64403D01*
X910953Y-63820D01*
X911287Y-63320D01*
X911787Y-62903D01*
X912453Y-62737D01*
X913037Y-62820D01*
X913453Y-62987D01*
X913870Y-63320D01*
G01X916720Y-63820D02*
X919387D01*
X919137Y-63237D01*
X918720Y-62903D01*
X918137Y-62737D01*
X917553Y-62820D01*
X917053Y-63070D01*
X916720Y-63653D01*
X916553Y-64153D01*
Y-64653D01*
X916720Y-65153D01*
X917137Y-65653D01*
X917637Y-65987D01*
X918220Y-66070D01*
X918803Y-65903D01*
X919387Y-65403D01*
G01X922320Y-65487D02*
X922737Y-65820D01*
X923320Y-66070D01*
X923820D01*
X924320Y-65903D01*
X924653Y-65653D01*
X924820Y-65320D01*
X924737Y-64820D01*
X924403Y-64570D01*
X922903Y-64070D01*
X922570Y-63487D01*
X922737Y-63070D01*
X923070Y-62820D01*
X923570Y-62737D01*
X924070Y-62820D01*
X924570Y-63070D01*
G01X929170Y-62737D02*
Y-66070D01*
G01Y-61403D02*
X929003Y-61320D01*
Y-61153D01*
X929170Y-61070D01*
X929337Y-61153D01*
Y-61320D01*
X929170Y-61403D01*
G01X933603Y-67320D02*
X934187Y-67653D01*
X934853Y-67737D01*
X935437Y-67653D01*
X935937Y-67237D01*
X936270Y-66653D01*
Y-62737D01*
G01Y-63403D02*
X935937Y-63070D01*
X935437Y-62820D01*
X934853Y-62737D01*
X934187Y-62903D01*
X933770Y-63237D01*
X933437Y-63820D01*
X933270Y-64403D01*
X933353Y-64903D01*
X933687Y-65487D01*
X934187Y-65903D01*
X934853Y-66070D01*
X935353Y-65987D01*
X935937Y-65653D01*
X936270Y-65320D01*
G01X938953Y-66070D02*
Y-62737D01*
G01Y-63570D02*
X939287Y-63153D01*
X939787Y-62820D01*
X940453Y-62737D01*
X941037Y-62820D01*
X941537Y-63153D01*
X941787Y-63737D01*
Y-66070D01*
G01X945803Y-66987D02*
X946137Y-65903D01*
G01X955670Y-67737D02*
Y-62737D01*
G01Y-63487D02*
X956087Y-63070D01*
X956503Y-62820D01*
X957170Y-62737D01*
X957753Y-62820D01*
X958337Y-63237D01*
X958587Y-63820D01*
X958670Y-64403D01*
X958587Y-64987D01*
X958337Y-65570D01*
X957837Y-65903D01*
X957170Y-66070D01*
X956587Y-65987D01*
X956003Y-65737D01*
X955670Y-65403D01*
G01X962770Y-66070D02*
Y-61070D01*
G01X967120Y-63820D02*
X969787D01*
X969537Y-63237D01*
X969120Y-62903D01*
X968537Y-62737D01*
X967953Y-62820D01*
X967453Y-63070D01*
X967120Y-63653D01*
X966953Y-64153D01*
Y-64653D01*
X967120Y-65153D01*
X967537Y-65653D01*
X968037Y-65987D01*
X968620Y-66070D01*
X969203Y-65903D01*
X969787Y-65403D01*
G01X975470Y-66070D02*
Y-62737D01*
G01Y-63320D02*
X975137Y-62987D01*
X974637Y-62820D01*
X974053Y-62737D01*
X973470Y-62903D01*
X972970Y-63237D01*
X972637Y-63737D01*
X972470Y-64403D01*
X972637Y-65070D01*
X972970Y-65570D01*
X973470Y-65903D01*
X974053Y-66070D01*
X974637Y-65987D01*
X975137Y-65737D01*
X975470Y-65403D01*
G01X978320Y-65487D02*
X978737Y-65820D01*
X979320Y-66070D01*
X979820D01*
X980320Y-65903D01*
X980653Y-65653D01*
X980820Y-65320D01*
X980737Y-64820D01*
X980403Y-64570D01*
X978903Y-64070D01*
X978570Y-63487D01*
X978737Y-63070D01*
X979070Y-62820D01*
X979570Y-62737D01*
X980070Y-62820D01*
X980570Y-63070D01*
G01X983920Y-63820D02*
X986587D01*
X986337Y-63237D01*
X985920Y-62903D01*
X985337Y-62737D01*
X984753Y-62820D01*
X984253Y-63070D01*
X983920Y-63653D01*
X983753Y-64153D01*
Y-64653D01*
X983920Y-65153D01*
X984337Y-65653D01*
X984837Y-65987D01*
X985420Y-66070D01*
X986003Y-65903D01*
X986587Y-65403D01*
G01X995870Y-66070D02*
Y-61820D01*
X996037Y-61403D01*
X996370Y-61153D01*
X996870Y-61070D01*
X997370Y-61237D01*
X997620Y-61653D01*
G01X996620Y-63070D02*
X994953D01*
G01X1001970Y-66070D02*
X1001470Y-65987D01*
X1000970Y-65653D01*
X1000637Y-65070D01*
X1000470Y-64403D01*
X1000637Y-63737D01*
X1000970Y-63153D01*
X1001470Y-62820D01*
X1001970Y-62737D01*
X1002470Y-62820D01*
X1002970Y-63153D01*
X1003303Y-63737D01*
X1003387Y-64403D01*
X1003303Y-65070D01*
X1002970Y-65653D01*
X1002470Y-65987D01*
X1001970Y-66070D01*
G01X1007570D02*
Y-61070D01*
G01X1013170Y-66070D02*
Y-61070D01*
G01X1018770Y-66070D02*
X1018270Y-65987D01*
X1017770Y-65653D01*
X1017437Y-65070D01*
X1017270Y-64403D01*
X1017437Y-63737D01*
X1017770Y-63153D01*
X1018270Y-62820D01*
X1018770Y-62737D01*
X1019270Y-62820D01*
X1019770Y-63153D01*
X1020103Y-63737D01*
X1020187Y-64403D01*
X1020103Y-65070D01*
X1019770Y-65653D01*
X1019270Y-65987D01*
X1018770Y-66070D01*
G01X1022287Y-62737D02*
X1023287Y-66070D01*
X1024370Y-62737D01*
X1025453Y-66070D01*
X1026453Y-62737D01*
G01X1029970Y-66237D02*
X1029803Y-66153D01*
Y-65987D01*
X1029970Y-65903D01*
X1030137Y-65987D01*
Y-66153D01*
X1029970Y-66237D01*
G01X1040170Y-61070D02*
X1042170D01*
G01X1041170D02*
Y-66070D01*
G01X1040170D02*
X1042170D01*
G01X1046270D02*
Y-61820D01*
X1046437Y-61403D01*
X1046770Y-61153D01*
X1047270Y-61070D01*
X1047770Y-61237D01*
X1048020Y-61653D01*
G01X1047020Y-63070D02*
X1045353D01*
G01X1056553Y-66070D02*
Y-62737D01*
G01Y-63570D02*
X1056887Y-63153D01*
X1057387Y-62820D01*
X1058053Y-62737D01*
X1058637Y-62820D01*
X1059137Y-63153D01*
X1059387Y-63737D01*
Y-66070D01*
G01X1063570D02*
X1063070Y-65987D01*
X1062570Y-65653D01*
X1062237Y-65070D01*
X1062070Y-64403D01*
X1062237Y-63737D01*
X1062570Y-63153D01*
X1063070Y-62820D01*
X1063570Y-62737D01*
X1064070Y-62820D01*
X1064570Y-63153D01*
X1064903Y-63737D01*
X1064987Y-64403D01*
X1064903Y-65070D01*
X1064570Y-65653D01*
X1064070Y-65987D01*
X1063570Y-66070D01*
G01X1069170Y-61070D02*
Y-66070D01*
G01X1068003Y-62737D02*
X1070337D01*
G01X1074603Y-66987D02*
X1074937Y-65903D01*
G01X1084470Y-67737D02*
Y-62737D01*
G01Y-63487D02*
X1084887Y-63070D01*
X1085303Y-62820D01*
X1085970Y-62737D01*
X1086553Y-62820D01*
X1087137Y-63237D01*
X1087387Y-63820D01*
X1087470Y-64403D01*
X1087387Y-64987D01*
X1087137Y-65570D01*
X1086637Y-65903D01*
X1085970Y-66070D01*
X1085387Y-65987D01*
X1084803Y-65737D01*
X1084470Y-65403D01*
G01X1091570Y-66070D02*
Y-61070D01*
G01X1095920Y-63820D02*
X1098587D01*
X1098337Y-63237D01*
X1097920Y-62903D01*
X1097337Y-62737D01*
X1096753Y-62820D01*
X1096253Y-63070D01*
X1095920Y-63653D01*
X1095753Y-64153D01*
Y-64653D01*
X1095920Y-65153D01*
X1096337Y-65653D01*
X1096837Y-65987D01*
X1097420Y-66070D01*
X1098003Y-65903D01*
X1098587Y-65403D01*
G01X1104270Y-66070D02*
Y-62737D01*
G01Y-63320D02*
X1103937Y-62987D01*
X1103437Y-62820D01*
X1102853Y-62737D01*
X1102270Y-62903D01*
X1101770Y-63237D01*
X1101437Y-63737D01*
X1101270Y-64403D01*
X1101437Y-65070D01*
X1101770Y-65570D01*
X1102270Y-65903D01*
X1102853Y-66070D01*
X1103437Y-65987D01*
X1103937Y-65737D01*
X1104270Y-65403D01*
G01X1107120Y-65487D02*
X1107537Y-65820D01*
X1108120Y-66070D01*
X1108620D01*
X1109120Y-65903D01*
X1109453Y-65653D01*
X1109620Y-65320D01*
X1109537Y-64820D01*
X1109203Y-64570D01*
X1107703Y-64070D01*
X1107370Y-63487D01*
X1107537Y-63070D01*
X1107870Y-62820D01*
X1108370Y-62737D01*
X1108870Y-62820D01*
X1109370Y-63070D01*
G01X1112720Y-63820D02*
X1115387D01*
X1115137Y-63237D01*
X1114720Y-62903D01*
X1114137Y-62737D01*
X1113553Y-62820D01*
X1113053Y-63070D01*
X1112720Y-63653D01*
X1112553Y-64153D01*
Y-64653D01*
X1112720Y-65153D01*
X1113137Y-65653D01*
X1113637Y-65987D01*
X1114220Y-66070D01*
X1114803Y-65903D01*
X1115387Y-65403D01*
G01X1125170Y-62737D02*
Y-66070D01*
G01Y-61403D02*
X1125003Y-61320D01*
Y-61153D01*
X1125170Y-61070D01*
X1125337Y-61153D01*
Y-61320D01*
X1125170Y-61403D01*
G01X1132270Y-67737D02*
Y-62737D01*
G01Y-63487D02*
X1131853Y-63070D01*
X1131353Y-62820D01*
X1130770Y-62737D01*
X1130270Y-62820D01*
X1129687Y-63237D01*
X1129353Y-63820D01*
X1129270Y-64403D01*
X1129353Y-64987D01*
X1129687Y-65570D01*
X1130270Y-65987D01*
X1130770Y-66070D01*
X1131353Y-65987D01*
X1131853Y-65737D01*
X1132270Y-65320D01*
G01X1134953Y-66070D02*
Y-62737D01*
G01Y-63570D02*
X1135287Y-63153D01*
X1135787Y-62820D01*
X1136453Y-62737D01*
X1137037Y-62820D01*
X1137537Y-63153D01*
X1137787Y-63737D01*
Y-66070D01*
G01X1141970D02*
X1141470Y-65987D01*
X1140970Y-65653D01*
X1140637Y-65070D01*
X1140470Y-64403D01*
X1140637Y-63737D01*
X1140970Y-63153D01*
X1141470Y-62820D01*
X1141970Y-62737D01*
X1142470Y-62820D01*
X1142970Y-63153D01*
X1143303Y-63737D01*
X1143387Y-64403D01*
X1143303Y-65070D01*
X1142970Y-65653D01*
X1142470Y-65987D01*
X1141970Y-66070D01*
G01X1146403D02*
Y-62737D01*
G01Y-63403D02*
X1146820Y-63070D01*
X1147237Y-62820D01*
X1147820Y-62737D01*
X1148237Y-62820D01*
X1148737Y-63070D01*
G01X1151920Y-63820D02*
X1154587D01*
X1154337Y-63237D01*
X1153920Y-62903D01*
X1153337Y-62737D01*
X1152753Y-62820D01*
X1152253Y-63070D01*
X1151920Y-63653D01*
X1151753Y-64153D01*
Y-64653D01*
X1151920Y-65153D01*
X1152337Y-65653D01*
X1152837Y-65987D01*
X1153420Y-66070D01*
X1154003Y-65903D01*
X1154587Y-65403D01*
G01X1164370Y-61070D02*
Y-66070D01*
G01X1163203Y-62737D02*
X1165537D01*
G01X1168553Y-66070D02*
Y-61070D01*
G01Y-63487D02*
X1168970Y-63070D01*
X1169387Y-62820D01*
X1170053Y-62737D01*
X1170553Y-62820D01*
X1171137Y-63153D01*
X1171387Y-63653D01*
Y-66070D01*
G01X1175570Y-62737D02*
Y-66070D01*
G01Y-61403D02*
X1175403Y-61320D01*
Y-61153D01*
X1175570Y-61070D01*
X1175737Y-61153D01*
Y-61320D01*
X1175570Y-61403D01*
G01X1179920Y-65487D02*
X1180337Y-65820D01*
X1180920Y-66070D01*
X1181420D01*
X1181920Y-65903D01*
X1182253Y-65653D01*
X1182420Y-65320D01*
X1182337Y-64820D01*
X1182003Y-64570D01*
X1180503Y-64070D01*
X1180170Y-63487D01*
X1180337Y-63070D01*
X1180670Y-62820D01*
X1181170Y-62737D01*
X1181670Y-62820D01*
X1182170Y-63070D01*
G01X1191203Y-66070D02*
Y-62737D01*
G01Y-63403D02*
X1191620Y-63070D01*
X1192037Y-62820D01*
X1192620Y-62737D01*
X1193037Y-62820D01*
X1193537Y-63070D01*
G01X1196720Y-63820D02*
X1199387D01*
X1199137Y-63237D01*
X1198720Y-62903D01*
X1198137Y-62737D01*
X1197553Y-62820D01*
X1197053Y-63070D01*
X1196720Y-63653D01*
X1196553Y-64153D01*
Y-64653D01*
X1196720Y-65153D01*
X1197137Y-65653D01*
X1197637Y-65987D01*
X1198220Y-66070D01*
X1198803Y-65903D01*
X1199387Y-65403D01*
G01X1205070Y-67737D02*
Y-62737D01*
G01Y-63487D02*
X1204653Y-63070D01*
X1204153Y-62820D01*
X1203570Y-62737D01*
X1203070Y-62820D01*
X1202487Y-63237D01*
X1202153Y-63820D01*
X1202070Y-64403D01*
X1202153Y-64987D01*
X1202487Y-65570D01*
X1203070Y-65987D01*
X1203570Y-66070D01*
X1204153Y-65987D01*
X1204653Y-65737D01*
X1205070Y-65320D01*
G01X1207753Y-62737D02*
Y-65070D01*
X1208087Y-65653D01*
X1208587Y-65987D01*
X1209170Y-66070D01*
X1209753Y-65987D01*
X1210253Y-65653D01*
X1210587Y-65070D01*
G01Y-66070D02*
Y-62737D01*
G01X1213520Y-63820D02*
X1216187D01*
X1215937Y-63237D01*
X1215520Y-62903D01*
X1214937Y-62737D01*
X1214353Y-62820D01*
X1213853Y-63070D01*
X1213520Y-63653D01*
X1213353Y-64153D01*
Y-64653D01*
X1213520Y-65153D01*
X1213937Y-65653D01*
X1214437Y-65987D01*
X1215020Y-66070D01*
X1215603Y-65903D01*
X1216187Y-65403D01*
G01X1219120Y-65487D02*
X1219537Y-65820D01*
X1220120Y-66070D01*
X1220620D01*
X1221120Y-65903D01*
X1221453Y-65653D01*
X1221620Y-65320D01*
X1221537Y-64820D01*
X1221203Y-64570D01*
X1219703Y-64070D01*
X1219370Y-63487D01*
X1219537Y-63070D01*
X1219870Y-62820D01*
X1220370Y-62737D01*
X1220870Y-62820D01*
X1221370Y-63070D01*
G01X1225970Y-61070D02*
Y-66070D01*
G01X1224803Y-62737D02*
X1227137D01*
G01X1231570Y-66237D02*
X1231403Y-66153D01*
Y-65987D01*
X1231570Y-65903D01*
X1231737Y-65987D01*
Y-66153D01*
X1231570Y-66237D01*
G01X713000Y850500D02*
Y-73000D01*
X1343000D01*
Y782000D01*
X713000D01*
G01X722667Y-38250D02*
X723167Y-38667D01*
X723750Y-38917D01*
X724500Y-39000D01*
X725250Y-38833D01*
X725833Y-38500D01*
X726250Y-37917D01*
X726333Y-37250D01*
X726167Y-36583D01*
X725750Y-36167D01*
X725167Y-35833D01*
X724583Y-35750D01*
X724000Y-35833D01*
X723250Y-36167D01*
X723500Y-34000D01*
X725750D01*
G01X730100Y-39167D02*
X729933Y-39083D01*
Y-38917D01*
X730100Y-38833D01*
X730267Y-38917D01*
Y-39083D01*
X730100Y-39167D01*
G01X739633Y-39000D02*
Y-34000D01*
X741717D01*
X742383Y-34250D01*
X742800Y-34583D01*
X742967Y-35250D01*
X742800Y-35917D01*
X742300Y-36333D01*
X741717Y-36583D01*
X739633D01*
G01X741717D02*
X742967Y-39000D01*
G01X745650Y-36750D02*
X748317D01*
X748067Y-36167D01*
X747650Y-35833D01*
X747067Y-35667D01*
X746483Y-35750D01*
X745983Y-36000D01*
X745650Y-36583D01*
X745483Y-37083D01*
Y-37583D01*
X745650Y-38083D01*
X746067Y-38583D01*
X746567Y-38917D01*
X747150Y-39000D01*
X747733Y-38833D01*
X748317Y-38333D01*
G01X750000Y-39000D02*
Y-35667D01*
G01Y-36583D02*
X750250Y-36167D01*
X750667Y-35833D01*
X751250Y-35667D01*
X751833Y-35833D01*
X752250Y-36167D01*
X752500Y-36583D01*
Y-39000D01*
G01Y-36583D02*
X752750Y-36167D01*
X753167Y-35833D01*
X753750Y-35667D01*
X754333Y-35833D01*
X754750Y-36167D01*
X755000Y-36667D01*
Y-39000D01*
G01X759600D02*
Y-35667D01*
G01Y-36250D02*
X759267Y-35917D01*
X758767Y-35750D01*
X758183Y-35667D01*
X757600Y-35833D01*
X757100Y-36167D01*
X756767Y-36667D01*
X756600Y-37333D01*
X756767Y-38000D01*
X757100Y-38500D01*
X757600Y-38833D01*
X758183Y-39000D01*
X758767Y-38917D01*
X759267Y-38667D01*
X759600Y-38333D01*
G01X762533Y-39000D02*
Y-35667D01*
G01Y-36333D02*
X762950Y-36000D01*
X763367Y-35750D01*
X763950Y-35667D01*
X764367Y-35750D01*
X764867Y-36000D01*
G01X767883Y-39000D02*
Y-34000D01*
G01X770550Y-35667D02*
X767883Y-37583D01*
G01X768967Y-36833D02*
X770717Y-39000D01*
G01X773067Y-39167D02*
X776733Y-35500D01*
G01X774900Y-34833D02*
Y-39833D01*
G01X776733Y-39167D02*
X773067Y-35500D01*
G01X772400Y-37333D02*
X777400D01*
G01X713000Y-53000D02*
X1343000D01*
G01X713000Y-23000D02*
X1343000D01*
G01X713000Y85500D02*
X1343000D01*
G01X713000Y335500D02*
X1343000D01*
G01X721407Y374673D02*
X725073Y378340D01*
G01X723240Y379007D02*
Y374007D01*
G01X725073Y374673D02*
X721407Y378340D01*
G01X720740Y376507D02*
X725740D01*
G01X728423Y373173D02*
X727590Y374007D01*
X727173Y374840D01*
Y378173D01*
X727590Y379007D01*
X728423Y379840D01*
G01X732607Y375590D02*
X733107Y375173D01*
X733690Y374923D01*
X734440Y374840D01*
X735190Y375007D01*
X735773Y375340D01*
X736190Y375923D01*
X736273Y376590D01*
X736107Y377257D01*
X735690Y377673D01*
X735107Y378007D01*
X734523Y378090D01*
X733940Y378007D01*
X733190Y377673D01*
X733440Y379840D01*
X735690D01*
G01X740040Y374673D02*
X739873Y374757D01*
Y374923D01*
X740040Y375007D01*
X740207Y374923D01*
Y374757D01*
X740040Y374673D01*
G01X745640Y374840D02*
Y379840D01*
X744640Y378840D01*
G01Y374840D02*
X746640D01*
G01X751657Y373173D02*
X752490Y374007D01*
X752907Y374840D01*
Y378173D01*
X752490Y379007D01*
X751657Y379840D01*
G01X725500Y349500D02*
Y354500D01*
X722417Y350917D01*
X726583D01*
G01X730100Y349333D02*
X729933Y349417D01*
Y349583D01*
X730100Y349667D01*
X730267Y349583D01*
Y349417D01*
X730100Y349333D01*
G01X739800Y349500D02*
Y354500D01*
G01Y352000D02*
X740217Y352500D01*
X740717Y352750D01*
X741217Y352833D01*
X741967Y352667D01*
X742467Y352333D01*
X742800Y351750D01*
Y351083D01*
X742633Y350417D01*
X742300Y349917D01*
X741717Y349583D01*
X741217Y349500D01*
X740717Y349583D01*
X740217Y349833D01*
X739800Y350250D01*
G01X748400Y349500D02*
Y352833D01*
G01Y352250D02*
X748067Y352583D01*
X747567Y352750D01*
X746983Y352833D01*
X746400Y352667D01*
X745900Y352333D01*
X745567Y351833D01*
X745400Y351167D01*
X745567Y350500D01*
X745900Y350000D01*
X746400Y349667D01*
X746983Y349500D01*
X747567Y349583D01*
X748067Y349833D01*
X748400Y350167D01*
G01X753833Y352417D02*
X753250Y352750D01*
X752750Y352833D01*
X752083Y352667D01*
X751583Y352333D01*
X751250Y351750D01*
X751167Y351167D01*
X751250Y350583D01*
X751583Y350083D01*
X752083Y349667D01*
X752750Y349500D01*
X753333Y349667D01*
X753833Y350000D01*
G01X756683Y349500D02*
Y354500D01*
G01X759350Y352833D02*
X756683Y350917D01*
G01X757767Y351667D02*
X759517Y349500D01*
G01X765200Y354500D02*
Y349500D01*
G01Y350250D02*
X764867Y349833D01*
X764367Y349583D01*
X763783Y349500D01*
X763117Y349667D01*
X762617Y350083D01*
X762283Y350583D01*
X762200Y351167D01*
X762283Y351750D01*
X762617Y352250D01*
X763117Y352667D01*
X763783Y352833D01*
X764367Y352750D01*
X764783Y352583D01*
X765200Y352250D01*
G01X768133Y349500D02*
Y352833D01*
G01Y352167D02*
X768550Y352500D01*
X768967Y352750D01*
X769550Y352833D01*
X769967Y352750D01*
X770467Y352500D01*
G01X774900Y352833D02*
Y349500D01*
G01Y354167D02*
X774733Y354250D01*
Y354417D01*
X774900Y354500D01*
X775067Y354417D01*
Y354250D01*
X774900Y354167D01*
G01X780500Y349500D02*
Y354500D01*
G01X786100Y349500D02*
Y354500D01*
G01X798800Y349500D02*
Y352833D01*
G01Y352250D02*
X798467Y352583D01*
X797967Y352750D01*
X797383Y352833D01*
X796800Y352667D01*
X796300Y352333D01*
X795967Y351833D01*
X795800Y351167D01*
X795967Y350500D01*
X796300Y350000D01*
X796800Y349667D01*
X797383Y349500D01*
X797967Y349583D01*
X798467Y349833D01*
X798800Y350167D01*
G01X801483Y349500D02*
Y352833D01*
G01Y352000D02*
X801817Y352417D01*
X802317Y352750D01*
X802983Y352833D01*
X803567Y352750D01*
X804067Y352417D01*
X804317Y351833D01*
Y349500D01*
G01X810000Y354500D02*
Y349500D01*
G01Y350250D02*
X809667Y349833D01*
X809167Y349583D01*
X808583Y349500D01*
X807917Y349667D01*
X807417Y350083D01*
X807083Y350583D01*
X807000Y351167D01*
X807083Y351750D01*
X807417Y352250D01*
X807917Y352667D01*
X808583Y352833D01*
X809167Y352750D01*
X809583Y352583D01*
X810000Y352250D01*
G01X818450Y350083D02*
X818867Y349750D01*
X819450Y349500D01*
X819950D01*
X820450Y349667D01*
X820783Y349917D01*
X820950Y350250D01*
X820867Y350750D01*
X820533Y351000D01*
X819033Y351500D01*
X818700Y352083D01*
X818867Y352500D01*
X819200Y352750D01*
X819700Y352833D01*
X820200Y352750D01*
X820700Y352500D01*
G01X826800Y347833D02*
Y352833D01*
G01Y352083D02*
X826383Y352500D01*
X825883Y352750D01*
X825300Y352833D01*
X824800Y352750D01*
X824217Y352333D01*
X823883Y351750D01*
X823800Y351167D01*
X823883Y350583D01*
X824217Y350000D01*
X824800Y349583D01*
X825300Y349500D01*
X825883Y349583D01*
X826383Y349833D01*
X826800Y350250D01*
G01X829483Y352833D02*
Y350500D01*
X829817Y349917D01*
X830317Y349583D01*
X830900Y349500D01*
X831483Y349583D01*
X831983Y349917D01*
X832317Y350500D01*
G01Y349500D02*
Y352833D01*
G01X838000Y349500D02*
Y352833D01*
G01Y352250D02*
X837667Y352583D01*
X837167Y352750D01*
X836583Y352833D01*
X836000Y352667D01*
X835500Y352333D01*
X835167Y351833D01*
X835000Y351167D01*
X835167Y350500D01*
X835500Y350000D01*
X836000Y349667D01*
X836583Y349500D01*
X837167Y349583D01*
X837667Y349833D01*
X838000Y350167D01*
G01X840933Y349500D02*
Y352833D01*
G01Y352167D02*
X841350Y352500D01*
X841767Y352750D01*
X842350Y352833D01*
X842767Y352750D01*
X843267Y352500D01*
G01X846450Y351750D02*
X849117D01*
X848867Y352333D01*
X848450Y352667D01*
X847867Y352833D01*
X847283Y352750D01*
X846783Y352500D01*
X846450Y351917D01*
X846283Y351417D01*
Y350917D01*
X846450Y350417D01*
X846867Y349917D01*
X847367Y349583D01*
X847950Y349500D01*
X848533Y349667D01*
X849117Y350167D01*
G01X857483Y349500D02*
Y354500D01*
G01Y352083D02*
X857900Y352500D01*
X858317Y352750D01*
X858983Y352833D01*
X859483Y352750D01*
X860067Y352417D01*
X860317Y351917D01*
Y349500D01*
G01X864500D02*
X864000Y349583D01*
X863500Y349917D01*
X863167Y350500D01*
X863000Y351167D01*
X863167Y351833D01*
X863500Y352417D01*
X864000Y352750D01*
X864500Y352833D01*
X865000Y352750D01*
X865500Y352417D01*
X865833Y351833D01*
X865917Y351167D01*
X865833Y350500D01*
X865500Y349917D01*
X865000Y349583D01*
X864500Y349500D01*
G01X870100D02*
Y354500D01*
G01X874450Y351750D02*
X877117D01*
X876867Y352333D01*
X876450Y352667D01*
X875867Y352833D01*
X875283Y352750D01*
X874783Y352500D01*
X874450Y351917D01*
X874283Y351417D01*
Y350917D01*
X874450Y350417D01*
X874867Y349917D01*
X875367Y349583D01*
X875950Y349500D01*
X876533Y349667D01*
X877117Y350167D01*
G01X881300Y349333D02*
X881133Y349417D01*
Y349583D01*
X881300Y349667D01*
X881467Y349583D01*
Y349417D01*
X881300Y349333D01*
G01Y351583D02*
X881133Y351667D01*
Y351833D01*
X881300Y351917D01*
X881467Y351833D01*
Y351667D01*
X881300Y351583D01*
G01X713000Y365500D02*
X1343000D01*
G01X721107Y408303D02*
X724773Y411970D01*
G01X722940Y412637D02*
Y407637D01*
G01X724773Y408303D02*
X721107Y411970D01*
G01X720440Y410137D02*
X725440D01*
G01X728123Y406803D02*
X727290Y407637D01*
X726873Y408470D01*
Y411803D01*
X727290Y412637D01*
X728123Y413470D01*
G01X732307Y409220D02*
X732807Y408803D01*
X733390Y408553D01*
X734140Y408470D01*
X734890Y408637D01*
X735473Y408970D01*
X735890Y409553D01*
X735973Y410220D01*
X735807Y410887D01*
X735390Y411303D01*
X734807Y411637D01*
X734223Y411720D01*
X733640Y411637D01*
X732890Y411303D01*
X733140Y413470D01*
X735390D01*
G01X739740Y408303D02*
X739573Y408387D01*
Y408553D01*
X739740Y408637D01*
X739907Y408553D01*
Y408387D01*
X739740Y408303D01*
G01X745340Y408470D02*
Y413470D01*
X744340Y412470D01*
G01Y408470D02*
X746340D01*
G01X751357Y406803D02*
X752190Y407637D01*
X752607Y408470D01*
Y411803D01*
X752190Y412637D01*
X751357Y413470D01*
G01X721217Y391740D02*
X723300Y386740D01*
X725383Y391740D01*
G01X728900Y390073D02*
Y386740D01*
G01Y391407D02*
X728733Y391490D01*
Y391657D01*
X728900Y391740D01*
X729067Y391657D01*
Y391490D01*
X728900Y391407D01*
G01X736000Y386740D02*
Y390073D01*
G01Y389490D02*
X735667Y389823D01*
X735167Y389990D01*
X734583Y390073D01*
X734000Y389907D01*
X733500Y389573D01*
X733167Y389073D01*
X733000Y388407D01*
X733167Y387740D01*
X733500Y387240D01*
X734000Y386907D01*
X734583Y386740D01*
X735167Y386823D01*
X735667Y387073D01*
X736000Y387407D01*
G01X744700Y391740D02*
X746700D01*
G01X745700D02*
Y386740D01*
G01X744700D02*
X746700D01*
G01X749883D02*
Y390073D01*
G01Y389240D02*
X750217Y389657D01*
X750717Y389990D01*
X751383Y390073D01*
X751967Y389990D01*
X752467Y389657D01*
X752717Y389073D01*
Y386740D01*
G01X760833D02*
Y391740D01*
X762833D01*
X763500Y391490D01*
X764000Y390907D01*
X764167Y390240D01*
X764000Y389573D01*
X763583Y389073D01*
X762833Y388823D01*
X760833D01*
G01X769600Y386740D02*
Y390073D01*
G01Y389490D02*
X769267Y389823D01*
X768767Y389990D01*
X768183Y390073D01*
X767600Y389907D01*
X767100Y389573D01*
X766767Y389073D01*
X766600Y388407D01*
X766767Y387740D01*
X767100Y387240D01*
X767600Y386907D01*
X768183Y386740D01*
X768767Y386823D01*
X769267Y387073D01*
X769600Y387407D01*
G01X775200Y391740D02*
Y386740D01*
G01Y387490D02*
X774867Y387073D01*
X774367Y386823D01*
X773783Y386740D01*
X773117Y386907D01*
X772617Y387323D01*
X772283Y387823D01*
X772200Y388407D01*
X772283Y388990D01*
X772617Y389490D01*
X773117Y389907D01*
X773783Y390073D01*
X774367Y389990D01*
X774783Y389823D01*
X775200Y389490D01*
G01X778883Y385073D02*
X778050Y385907D01*
X777633Y386740D01*
Y390073D01*
X778050Y390907D01*
X778883Y391740D01*
G01X782817D02*
X784900Y386740D01*
X786983Y391740D01*
G01X789500D02*
X791500D01*
G01X790500D02*
Y386740D01*
G01X789500D02*
X791500D01*
G01X794433D02*
Y391740D01*
X796433D01*
X797100Y391490D01*
X797600Y390907D01*
X797767Y390240D01*
X797600Y389573D01*
X797183Y389073D01*
X796433Y388823D01*
X794433D01*
G01X802117Y385073D02*
X802950Y385907D01*
X803367Y386740D01*
Y390073D01*
X802950Y390907D01*
X802117Y391740D01*
G01X713000Y400500D02*
X1343000D01*
G01X720917Y424500D02*
X723000Y419500D01*
X725083Y424500D01*
G01X728600Y422833D02*
Y419500D01*
G01Y424167D02*
X728433Y424250D01*
Y424417D01*
X728600Y424500D01*
X728767Y424417D01*
Y424250D01*
X728600Y424167D01*
G01X735700Y419500D02*
Y422833D01*
G01Y422250D02*
X735367Y422583D01*
X734867Y422750D01*
X734283Y422833D01*
X733700Y422667D01*
X733200Y422333D01*
X732867Y421833D01*
X732700Y421167D01*
X732867Y420500D01*
X733200Y420000D01*
X733700Y419667D01*
X734283Y419500D01*
X734867Y419583D01*
X735367Y419833D01*
X735700Y420167D01*
G01X745400Y419500D02*
X744733Y419583D01*
X744150Y419917D01*
X743650Y420417D01*
X743317Y421000D01*
X743150Y421667D01*
Y422333D01*
X743317Y423000D01*
X743650Y423583D01*
X744150Y424083D01*
X744733Y424417D01*
X745400Y424500D01*
X746067Y424417D01*
X746650Y424083D01*
X747150Y423583D01*
X747483Y423000D01*
X747650Y422333D01*
Y421667D01*
X747483Y421000D01*
X747150Y420417D01*
X746650Y419917D01*
X746067Y419583D01*
X745400Y419500D01*
G01X749583D02*
Y422833D01*
G01Y422000D02*
X749917Y422417D01*
X750417Y422750D01*
X751083Y422833D01*
X751667Y422750D01*
X752167Y422417D01*
X752417Y421833D01*
Y419500D01*
G01X760533D02*
Y424500D01*
X762533D01*
X763200Y424250D01*
X763700Y423667D01*
X763867Y423000D01*
X763700Y422333D01*
X763283Y421833D01*
X762533Y421583D01*
X760533D01*
G01X769300Y419500D02*
Y422833D01*
G01Y422250D02*
X768967Y422583D01*
X768467Y422750D01*
X767883Y422833D01*
X767300Y422667D01*
X766800Y422333D01*
X766467Y421833D01*
X766300Y421167D01*
X766467Y420500D01*
X766800Y420000D01*
X767300Y419667D01*
X767883Y419500D01*
X768467Y419583D01*
X768967Y419833D01*
X769300Y420167D01*
G01X774900Y424500D02*
Y419500D01*
G01Y420250D02*
X774567Y419833D01*
X774067Y419583D01*
X773483Y419500D01*
X772817Y419667D01*
X772317Y420083D01*
X771983Y420583D01*
X771900Y421167D01*
X771983Y421750D01*
X772317Y422250D01*
X772817Y422667D01*
X773483Y422833D01*
X774067Y422750D01*
X774483Y422583D01*
X774900Y422250D01*
G01X778583Y417833D02*
X777750Y418667D01*
X777333Y419500D01*
Y422833D01*
X777750Y423667D01*
X778583Y424500D01*
G01X782517D02*
X784600Y419500D01*
X786683Y424500D01*
G01X790200Y419500D02*
X789533Y419583D01*
X788950Y419917D01*
X788450Y420417D01*
X788117Y421000D01*
X787950Y421667D01*
Y422333D01*
X788117Y423000D01*
X788450Y423583D01*
X788950Y424083D01*
X789533Y424417D01*
X790200Y424500D01*
X790867Y424417D01*
X791450Y424083D01*
X791950Y423583D01*
X792283Y423000D01*
X792450Y422333D01*
Y421667D01*
X792283Y421000D01*
X791950Y420417D01*
X791450Y419917D01*
X790867Y419583D01*
X790200Y419500D01*
G01X794133D02*
Y424500D01*
X796133D01*
X796800Y424250D01*
X797300Y423667D01*
X797467Y423000D01*
X797300Y422333D01*
X796883Y421833D01*
X796133Y421583D01*
X794133D01*
G01X801817Y417833D02*
X802650Y418667D01*
X803067Y419500D01*
Y422833D01*
X802650Y423667D01*
X801817Y424500D01*
G01X723667Y443167D02*
X724000Y443417D01*
X724250Y443833D01*
X724417Y444417D01*
X724250Y444917D01*
X723917Y445250D01*
X723333Y445500D01*
X721083D01*
Y440500D01*
X723833D01*
X724417Y440833D01*
X724750Y441333D01*
X724917Y441917D01*
X724750Y442500D01*
X724250Y443000D01*
X723667Y443167D01*
X721083D01*
G01X727183Y443833D02*
Y441500D01*
X727517Y440917D01*
X728017Y440583D01*
X728600Y440500D01*
X729183Y440583D01*
X729683Y440917D01*
X730017Y441500D01*
G01Y440500D02*
Y443833D01*
G01X733033Y440500D02*
Y443833D01*
G01Y443167D02*
X733450Y443500D01*
X733867Y443750D01*
X734450Y443833D01*
X734867Y443750D01*
X735367Y443500D01*
G01X739800Y443833D02*
Y440500D01*
G01Y445167D02*
X739633Y445250D01*
Y445417D01*
X739800Y445500D01*
X739967Y445417D01*
Y445250D01*
X739800Y445167D01*
G01X744150Y442750D02*
X746817D01*
X746567Y443333D01*
X746150Y443667D01*
X745567Y443833D01*
X744983Y443750D01*
X744483Y443500D01*
X744150Y442917D01*
X743983Y442417D01*
Y441917D01*
X744150Y441417D01*
X744567Y440917D01*
X745067Y440583D01*
X745650Y440500D01*
X746233Y440667D01*
X746817Y441167D01*
G01X752500Y445500D02*
Y440500D01*
G01Y441250D02*
X752167Y440833D01*
X751667Y440583D01*
X751083Y440500D01*
X750417Y440667D01*
X749917Y441083D01*
X749583Y441583D01*
X749500Y442167D01*
X749583Y442750D01*
X749917Y443250D01*
X750417Y443667D01*
X751083Y443833D01*
X751667Y443750D01*
X752083Y443583D01*
X752500Y443250D01*
G01X760783Y440500D02*
Y445500D01*
G01Y443083D02*
X761200Y443500D01*
X761617Y443750D01*
X762283Y443833D01*
X762783Y443750D01*
X763367Y443417D01*
X763617Y442917D01*
Y440500D01*
G01X767800D02*
X767300Y440583D01*
X766800Y440917D01*
X766467Y441500D01*
X766300Y442167D01*
X766467Y442833D01*
X766800Y443417D01*
X767300Y443750D01*
X767800Y443833D01*
X768300Y443750D01*
X768800Y443417D01*
X769133Y442833D01*
X769217Y442167D01*
X769133Y441500D01*
X768800Y440917D01*
X768300Y440583D01*
X767800Y440500D01*
G01X773400D02*
Y445500D01*
G01X777750Y442750D02*
X780417D01*
X780167Y443333D01*
X779750Y443667D01*
X779167Y443833D01*
X778583Y443750D01*
X778083Y443500D01*
X777750Y442917D01*
X777583Y442417D01*
Y441917D01*
X777750Y441417D01*
X778167Y440917D01*
X778667Y440583D01*
X779250Y440500D01*
X779833Y440667D01*
X780417Y441167D01*
G01X713000Y435500D02*
X1343000D01*
G01X721417Y461500D02*
Y466500D01*
X724583D01*
G01X723417Y464083D02*
X721417D01*
G01X727183Y464833D02*
Y462500D01*
X727517Y461917D01*
X728017Y461583D01*
X728600Y461500D01*
X729183Y461583D01*
X729683Y461917D01*
X730017Y462500D01*
G01Y461500D02*
Y464833D01*
G01X734200Y461500D02*
Y466500D01*
G01X739800Y461500D02*
Y466500D01*
G01X749500Y459833D02*
Y464833D01*
G01Y464083D02*
X749917Y464500D01*
X750333Y464750D01*
X751000Y464833D01*
X751583Y464750D01*
X752167Y464333D01*
X752417Y463750D01*
X752500Y463167D01*
X752417Y462583D01*
X752167Y462000D01*
X751667Y461667D01*
X751000Y461500D01*
X750417Y461583D01*
X749833Y461833D01*
X749500Y462167D01*
G01X756600Y461500D02*
Y466500D01*
G01X760783Y464833D02*
Y462500D01*
X761117Y461917D01*
X761617Y461583D01*
X762200Y461500D01*
X762783Y461583D01*
X763283Y461917D01*
X763617Y462500D01*
G01Y461500D02*
Y464833D01*
G01X766633Y460250D02*
X767217Y459917D01*
X767883Y459833D01*
X768467Y459917D01*
X768967Y460333D01*
X769300Y460917D01*
Y464833D01*
G01Y464167D02*
X768967Y464500D01*
X768467Y464750D01*
X767883Y464833D01*
X767217Y464667D01*
X766800Y464333D01*
X766467Y463750D01*
X766300Y463167D01*
X766383Y462667D01*
X766717Y462083D01*
X767217Y461667D01*
X767883Y461500D01*
X768383Y461583D01*
X768967Y461917D01*
X769300Y462250D01*
G01X772233Y460250D02*
X772817Y459917D01*
X773483Y459833D01*
X774067Y459917D01*
X774567Y460333D01*
X774900Y460917D01*
Y464833D01*
G01Y464167D02*
X774567Y464500D01*
X774067Y464750D01*
X773483Y464833D01*
X772817Y464667D01*
X772400Y464333D01*
X772067Y463750D01*
X771900Y463167D01*
X771983Y462667D01*
X772317Y462083D01*
X772817Y461667D01*
X773483Y461500D01*
X773983Y461583D01*
X774567Y461917D01*
X774900Y462250D01*
G01X779000Y464833D02*
Y461500D01*
G01Y466167D02*
X778833Y466250D01*
Y466417D01*
X779000Y466500D01*
X779167Y466417D01*
Y466250D01*
X779000Y466167D01*
G01X783183Y461500D02*
Y464833D01*
G01Y464000D02*
X783517Y464417D01*
X784017Y464750D01*
X784683Y464833D01*
X785267Y464750D01*
X785767Y464417D01*
X786017Y463833D01*
Y461500D01*
G01X789033Y460250D02*
X789617Y459917D01*
X790283Y459833D01*
X790867Y459917D01*
X791367Y460333D01*
X791700Y460917D01*
Y464833D01*
G01Y464167D02*
X791367Y464500D01*
X790867Y464750D01*
X790283Y464833D01*
X789617Y464667D01*
X789200Y464333D01*
X788867Y463750D01*
X788700Y463167D01*
X788783Y462667D01*
X789117Y462083D01*
X789617Y461667D01*
X790283Y461500D01*
X790783Y461583D01*
X791367Y461917D01*
X791700Y462250D01*
G01X713000Y450500D02*
X1343000D01*
G01X713000Y477500D02*
X1343000D01*
G01X721250Y530000D02*
Y535000D01*
G01X724750D02*
Y530000D01*
G01Y532500D02*
X721250D01*
G01X730100Y530000D02*
Y533333D01*
G01Y532750D02*
X729767Y533083D01*
X729267Y533250D01*
X728683Y533333D01*
X728100Y533167D01*
X727600Y532833D01*
X727267Y532333D01*
X727100Y531667D01*
X727267Y531000D01*
X727600Y530500D01*
X728100Y530167D01*
X728683Y530000D01*
X729267Y530083D01*
X729767Y530333D01*
X730100Y530667D01*
G01X734200Y530000D02*
Y535000D01*
G01X739300Y530000D02*
Y534250D01*
X739467Y534667D01*
X739800Y534917D01*
X740300Y535000D01*
X740800Y534833D01*
X741050Y534417D01*
G01X740050Y533000D02*
X738383D01*
G01X749333Y530000D02*
Y535000D01*
X751333D01*
X752000Y534750D01*
X752500Y534167D01*
X752667Y533500D01*
X752500Y532833D01*
X752083Y532333D01*
X751333Y532083D01*
X749333D01*
G01X756600Y530000D02*
Y535000D01*
G01X760783Y533333D02*
Y531000D01*
X761117Y530417D01*
X761617Y530083D01*
X762200Y530000D01*
X762783Y530083D01*
X763283Y530417D01*
X763617Y531000D01*
G01Y530000D02*
Y533333D01*
G01X766633Y528750D02*
X767217Y528417D01*
X767883Y528333D01*
X768467Y528417D01*
X768967Y528833D01*
X769300Y529417D01*
Y533333D01*
G01Y532667D02*
X768967Y533000D01*
X768467Y533250D01*
X767883Y533333D01*
X767217Y533167D01*
X766800Y532833D01*
X766467Y532250D01*
X766300Y531667D01*
X766383Y531167D01*
X766717Y530583D01*
X767217Y530167D01*
X767883Y530000D01*
X768383Y530083D01*
X768967Y530417D01*
X769300Y530750D01*
G01X772233Y528750D02*
X772817Y528417D01*
X773483Y528333D01*
X774067Y528417D01*
X774567Y528833D01*
X774900Y529417D01*
Y533333D01*
G01Y532667D02*
X774567Y533000D01*
X774067Y533250D01*
X773483Y533333D01*
X772817Y533167D01*
X772400Y532833D01*
X772067Y532250D01*
X771900Y531667D01*
X771983Y531167D01*
X772317Y530583D01*
X772817Y530167D01*
X773483Y530000D01*
X773983Y530083D01*
X774567Y530417D01*
X774900Y530750D01*
G01X779000Y533333D02*
Y530000D01*
G01Y534667D02*
X778833Y534750D01*
Y534917D01*
X779000Y535000D01*
X779167Y534917D01*
Y534750D01*
X779000Y534667D01*
G01X783183Y530000D02*
Y533333D01*
G01Y532500D02*
X783517Y532917D01*
X784017Y533250D01*
X784683Y533333D01*
X785267Y533250D01*
X785767Y532917D01*
X786017Y532333D01*
Y530000D01*
G01X789033Y528750D02*
X789617Y528417D01*
X790283Y528333D01*
X790867Y528417D01*
X791367Y528833D01*
X791700Y529417D01*
Y533333D01*
G01Y532667D02*
X791367Y533000D01*
X790867Y533250D01*
X790283Y533333D01*
X789617Y533167D01*
X789200Y532833D01*
X788867Y532250D01*
X788700Y531667D01*
X788783Y531167D01*
X789117Y530583D01*
X789617Y530167D01*
X790283Y530000D01*
X790783Y530083D01*
X791367Y530417D01*
X791700Y530750D01*
G01X713000Y579500D02*
X1343000D01*
G01X722833Y589000D02*
Y594000D01*
X724833D01*
X725500Y593750D01*
X726000Y593167D01*
X726167Y592500D01*
X726000Y591833D01*
X725583Y591333D01*
X724833Y591083D01*
X722833D01*
G01X730100Y589000D02*
Y594000D01*
G01X734283Y592333D02*
Y590000D01*
X734617Y589417D01*
X735117Y589083D01*
X735700Y589000D01*
X736283Y589083D01*
X736783Y589417D01*
X737117Y590000D01*
G01Y589000D02*
Y592333D01*
G01X740133Y587750D02*
X740717Y587417D01*
X741383Y587333D01*
X741967Y587417D01*
X742467Y587833D01*
X742800Y588417D01*
Y592333D01*
G01Y591667D02*
X742467Y592000D01*
X741967Y592250D01*
X741383Y592333D01*
X740717Y592167D01*
X740300Y591833D01*
X739967Y591250D01*
X739800Y590667D01*
X739883Y590167D01*
X740217Y589583D01*
X740717Y589167D01*
X741383Y589000D01*
X741883Y589083D01*
X742467Y589417D01*
X742800Y589750D01*
G01X745733Y587750D02*
X746317Y587417D01*
X746983Y587333D01*
X747567Y587417D01*
X748067Y587833D01*
X748400Y588417D01*
Y592333D01*
G01Y591667D02*
X748067Y592000D01*
X747567Y592250D01*
X746983Y592333D01*
X746317Y592167D01*
X745900Y591833D01*
X745567Y591250D01*
X745400Y590667D01*
X745483Y590167D01*
X745817Y589583D01*
X746317Y589167D01*
X746983Y589000D01*
X747483Y589083D01*
X748067Y589417D01*
X748400Y589750D01*
G01X752500Y592333D02*
Y589000D01*
G01Y593667D02*
X752333Y593750D01*
Y593917D01*
X752500Y594000D01*
X752667Y593917D01*
Y593750D01*
X752500Y593667D01*
G01X756683Y589000D02*
Y592333D01*
G01Y591500D02*
X757017Y591917D01*
X757517Y592250D01*
X758183Y592333D01*
X758767Y592250D01*
X759267Y591917D01*
X759517Y591333D01*
Y589000D01*
G01X762533Y587750D02*
X763117Y587417D01*
X763783Y587333D01*
X764367Y587417D01*
X764867Y587833D01*
X765200Y588417D01*
Y592333D01*
G01Y591667D02*
X764867Y592000D01*
X764367Y592250D01*
X763783Y592333D01*
X763117Y592167D01*
X762700Y591833D01*
X762367Y591250D01*
X762200Y590667D01*
X762283Y590167D01*
X762617Y589583D01*
X763117Y589167D01*
X763783Y589000D01*
X764283Y589083D01*
X764867Y589417D01*
X765200Y589750D01*
G01X776400Y594000D02*
Y589000D01*
G01Y589750D02*
X776067Y589333D01*
X775567Y589083D01*
X774983Y589000D01*
X774317Y589167D01*
X773817Y589583D01*
X773483Y590083D01*
X773400Y590667D01*
X773483Y591250D01*
X773817Y591750D01*
X774317Y592167D01*
X774983Y592333D01*
X775567Y592250D01*
X775983Y592083D01*
X776400Y591750D01*
G01X779250Y591250D02*
X781917D01*
X781667Y591833D01*
X781250Y592167D01*
X780667Y592333D01*
X780083Y592250D01*
X779583Y592000D01*
X779250Y591417D01*
X779083Y590917D01*
Y590417D01*
X779250Y589917D01*
X779667Y589417D01*
X780167Y589083D01*
X780750Y589000D01*
X781333Y589167D01*
X781917Y589667D01*
G01X785600Y589000D02*
Y593250D01*
X785767Y593667D01*
X786100Y593917D01*
X786600Y594000D01*
X787100Y593833D01*
X787350Y593417D01*
G01X786350Y592000D02*
X784683D01*
G01X791700Y592333D02*
Y589000D01*
G01Y593667D02*
X791533Y593750D01*
Y593917D01*
X791700Y594000D01*
X791867Y593917D01*
Y593750D01*
X791700Y593667D01*
G01X795883Y589000D02*
Y592333D01*
G01Y591500D02*
X796217Y591917D01*
X796717Y592250D01*
X797383Y592333D01*
X797967Y592250D01*
X798467Y591917D01*
X798717Y591333D01*
Y589000D01*
G01X801650Y591250D02*
X804317D01*
X804067Y591833D01*
X803650Y592167D01*
X803067Y592333D01*
X802483Y592250D01*
X801983Y592000D01*
X801650Y591417D01*
X801483Y590917D01*
Y590417D01*
X801650Y589917D01*
X802067Y589417D01*
X802567Y589083D01*
X803150Y589000D01*
X803733Y589167D01*
X804317Y589667D01*
G01X713000Y604500D02*
X1343000D01*
G01X722667Y765000D02*
X723167Y764417D01*
X723833Y764083D01*
X724583Y764000D01*
X725250Y764083D01*
X725917Y764500D01*
X726333Y765000D01*
X726417Y765500D01*
X726250Y766083D01*
X725667Y766500D01*
X725083Y766667D01*
X724333D01*
G01X725083D02*
X725583Y766917D01*
X726000Y767333D01*
X726167Y767833D01*
X726000Y768333D01*
X725583Y768750D01*
X724833Y769000D01*
X724083Y768917D01*
X723333Y768583D01*
G01X730100Y763833D02*
X729933Y763917D01*
Y764083D01*
X730100Y764167D01*
X730267Y764083D01*
Y763917D01*
X730100Y763833D01*
G01X739633Y764000D02*
Y769000D01*
X741633D01*
X742300Y768750D01*
X742800Y768167D01*
X742967Y767500D01*
X742800Y766833D01*
X742383Y766333D01*
X741633Y766083D01*
X739633D01*
G01X746900Y764000D02*
Y769000D01*
G01X751083Y767333D02*
Y765000D01*
X751417Y764417D01*
X751917Y764083D01*
X752500Y764000D01*
X753083Y764083D01*
X753583Y764417D01*
X753917Y765000D01*
G01Y764000D02*
Y767333D01*
G01X756933Y762750D02*
X757517Y762417D01*
X758183Y762333D01*
X758767Y762417D01*
X759267Y762833D01*
X759600Y763417D01*
Y767333D01*
G01Y766667D02*
X759267Y767000D01*
X758767Y767250D01*
X758183Y767333D01*
X757517Y767167D01*
X757100Y766833D01*
X756767Y766250D01*
X756600Y765667D01*
X756683Y765167D01*
X757017Y764583D01*
X757517Y764167D01*
X758183Y764000D01*
X758683Y764083D01*
X759267Y764417D01*
X759600Y764750D01*
G01X767800Y767333D02*
X769300Y764000D01*
X770800Y767333D01*
G01X774900D02*
Y764000D01*
G01Y768667D02*
X774733Y768750D01*
Y768917D01*
X774900Y769000D01*
X775067Y768917D01*
Y768750D01*
X774900Y768667D01*
G01X782000Y764000D02*
Y767333D01*
G01Y766750D02*
X781667Y767083D01*
X781167Y767250D01*
X780583Y767333D01*
X780000Y767167D01*
X779500Y766833D01*
X779167Y766333D01*
X779000Y765667D01*
X779167Y765000D01*
X779500Y764500D01*
X780000Y764167D01*
X780583Y764000D01*
X781167Y764083D01*
X781667Y764333D01*
X782000Y764667D01*
G01X790200Y763833D02*
X793200Y769000D01*
G01X795217D02*
X797300Y764000D01*
X799383Y769000D01*
G01X802900Y764000D02*
X802233Y764083D01*
X801650Y764417D01*
X801150Y764917D01*
X800817Y765500D01*
X800650Y766167D01*
Y766833D01*
X800817Y767500D01*
X801150Y768083D01*
X801650Y768583D01*
X802233Y768917D01*
X802900Y769000D01*
X803567Y768917D01*
X804150Y768583D01*
X804650Y768083D01*
X804983Y767500D01*
X805150Y766833D01*
Y766167D01*
X804983Y765500D01*
X804650Y764917D01*
X804150Y764417D01*
X803567Y764083D01*
X802900Y764000D01*
G01X806833D02*
Y769000D01*
X808833D01*
X809500Y768750D01*
X810000Y768167D01*
X810167Y767500D01*
X810000Y766833D01*
X809583Y766333D01*
X808833Y766083D01*
X806833D01*
G01X812600Y763833D02*
X815600Y769000D01*
G01X817617D02*
X819700Y764000D01*
X821783Y769000D01*
G01X824300D02*
X826300D01*
G01X825300D02*
Y764000D01*
G01X824300D02*
X826300D01*
G01X829233D02*
Y769000D01*
X831233D01*
X831900Y768750D01*
X832400Y768167D01*
X832567Y767500D01*
X832400Y766833D01*
X831983Y766333D01*
X831233Y766083D01*
X829233D01*
G01X836500Y763833D02*
X836333Y763917D01*
Y764083D01*
X836500Y764167D01*
X836667Y764083D01*
Y763917D01*
X836500Y763833D01*
G01Y766083D02*
X836333Y766167D01*
Y766333D01*
X836500Y766417D01*
X836667Y766333D01*
Y766167D01*
X836500Y766083D01*
G01X713000Y752000D02*
X1344500D01*
G01X724813Y813000D02*
Y818000D01*
X726897D01*
X727563Y817750D01*
X727980Y817417D01*
X728147Y816750D01*
X727980Y816083D01*
X727480Y815667D01*
X726897Y815417D01*
X724813D01*
G01X726897D02*
X728147Y813000D01*
G01X732080D02*
X731580Y813083D01*
X731080Y813417D01*
X730747Y814000D01*
X730580Y814667D01*
X730747Y815333D01*
X731080Y815917D01*
X731580Y816250D01*
X732080Y816333D01*
X732580Y816250D01*
X733080Y815917D01*
X733413Y815333D01*
X733497Y814667D01*
X733413Y814000D01*
X733080Y813417D01*
X732580Y813083D01*
X732080Y813000D01*
G01X736263Y816333D02*
Y814000D01*
X736597Y813417D01*
X737097Y813083D01*
X737680Y813000D01*
X738263Y813083D01*
X738763Y813417D01*
X739097Y814000D01*
G01Y813000D02*
Y816333D01*
G01X743280Y818000D02*
Y813000D01*
G01X742113Y816333D02*
X744447D01*
G01X748880D02*
Y813000D01*
G01Y817667D02*
X748713Y817750D01*
Y817917D01*
X748880Y818000D01*
X749047Y817917D01*
Y817750D01*
X748880Y817667D01*
G01X753063Y813000D02*
Y816333D01*
G01Y815500D02*
X753397Y815917D01*
X753897Y816250D01*
X754563Y816333D01*
X755147Y816250D01*
X755647Y815917D01*
X755897Y815333D01*
Y813000D01*
G01X758913Y811750D02*
X759497Y811417D01*
X760163Y811333D01*
X760747Y811417D01*
X761247Y811833D01*
X761580Y812417D01*
Y816333D01*
G01Y815667D02*
X761247Y816000D01*
X760747Y816250D01*
X760163Y816333D01*
X759497Y816167D01*
X759080Y815833D01*
X758747Y815250D01*
X758580Y814667D01*
X758663Y814167D01*
X758997Y813583D01*
X759497Y813167D01*
X760163Y813000D01*
X760663Y813083D01*
X761247Y813417D01*
X761580Y813750D01*
G01X712980Y850500D02*
X1343000D01*
G01X802167Y-15500D02*
Y-10500D01*
X803833D01*
X804500Y-10750D01*
X805000Y-11083D01*
X805417Y-11583D01*
X805750Y-12167D01*
X805833Y-13000D01*
X805750Y-13833D01*
X805417Y-14417D01*
X805000Y-14917D01*
X804500Y-15250D01*
X803833Y-15500D01*
X802167D01*
G01X809600D02*
Y-10500D01*
X808600Y-11500D01*
G01Y-15500D02*
X810600D01*
G01X813617Y-13417D02*
X814200Y-12833D01*
X814700Y-12500D01*
X815367Y-12333D01*
X815950Y-12500D01*
X816367Y-12833D01*
X816700Y-13333D01*
X816783Y-13917D01*
X816700Y-14417D01*
X816367Y-14917D01*
X815867Y-15333D01*
X815283Y-15500D01*
X814617Y-15333D01*
X814033Y-14833D01*
X813700Y-14083D01*
X813617Y-13250D01*
X813783Y-12167D01*
X814033Y-11583D01*
X814450Y-11000D01*
X815033Y-10583D01*
X815617Y-10500D01*
X816200Y-10667D01*
X816617Y-11083D01*
G01X777583Y104700D02*
Y99700D01*
X780917D01*
G01X783600Y103033D02*
X786100Y99700D01*
G01Y103033D02*
X783600Y99700D01*
G01X790450Y99533D02*
X790283Y99617D01*
Y99783D01*
X790450Y99867D01*
X790617Y99783D01*
Y99617D01*
X790450Y99533D01*
G01Y101783D02*
X790283Y101867D01*
Y102033D01*
X790450Y102117D01*
X790617Y102033D01*
Y101867D01*
X790450Y101783D01*
G01X799150Y99700D02*
Y103033D01*
G01Y102117D02*
X799400Y102533D01*
X799817Y102867D01*
X800400Y103033D01*
X800983Y102867D01*
X801400Y102533D01*
X801650Y102117D01*
Y99700D01*
G01Y102117D02*
X801900Y102533D01*
X802317Y102867D01*
X802900Y103033D01*
X803483Y102867D01*
X803900Y102533D01*
X804150Y102033D01*
Y99700D01*
G01X805833Y103033D02*
Y100700D01*
X806167Y100117D01*
X806667Y99783D01*
X807250Y99700D01*
X807833Y99783D01*
X808333Y100117D01*
X808667Y100700D01*
G01Y99700D02*
Y103033D01*
G01X811600Y100283D02*
X812017Y99950D01*
X812600Y99700D01*
X813100D01*
X813600Y99867D01*
X813933Y100117D01*
X814100Y100450D01*
X814017Y100950D01*
X813683Y101200D01*
X812183Y101700D01*
X811850Y102283D01*
X812017Y102700D01*
X812350Y102950D01*
X812850Y103033D01*
X813350Y102950D01*
X813850Y102700D01*
G01X818450Y104700D02*
Y99700D01*
G01X817283Y103033D02*
X819617D01*
G01X828150Y99700D02*
Y104700D01*
G01Y102200D02*
X828567Y102700D01*
X829067Y102950D01*
X829567Y103033D01*
X830317Y102867D01*
X830817Y102533D01*
X831150Y101950D01*
Y101283D01*
X830983Y100617D01*
X830650Y100117D01*
X830067Y99783D01*
X829567Y99700D01*
X829067Y99783D01*
X828567Y100033D01*
X828150Y100450D01*
G01X834000Y101950D02*
X836667D01*
X836417Y102533D01*
X836000Y102867D01*
X835417Y103033D01*
X834833Y102950D01*
X834333Y102700D01*
X834000Y102117D01*
X833833Y101617D01*
Y101117D01*
X834000Y100617D01*
X834417Y100117D01*
X834917Y99783D01*
X835500Y99700D01*
X836083Y99867D01*
X836667Y100367D01*
G01X844950Y99700D02*
Y104700D01*
G01Y102200D02*
X845367Y102700D01*
X845867Y102950D01*
X846367Y103033D01*
X847117Y102867D01*
X847617Y102533D01*
X847950Y101950D01*
Y101283D01*
X847783Y100617D01*
X847450Y100117D01*
X846867Y99783D01*
X846367Y99700D01*
X845867Y99783D01*
X845367Y100033D01*
X844950Y100450D01*
G01X850883Y99700D02*
Y103033D01*
G01Y102367D02*
X851300Y102700D01*
X851717Y102950D01*
X852300Y103033D01*
X852717Y102950D01*
X853217Y102700D01*
G01X857650Y99700D02*
X857150Y99783D01*
X856650Y100117D01*
X856317Y100700D01*
X856150Y101367D01*
X856317Y102033D01*
X856650Y102617D01*
X857150Y102950D01*
X857650Y103033D01*
X858150Y102950D01*
X858650Y102617D01*
X858983Y102033D01*
X859067Y101367D01*
X858983Y100700D01*
X858650Y100117D01*
X858150Y99783D01*
X857650Y99700D01*
G01X861833D02*
Y104700D01*
G01X864500Y103033D02*
X861833Y101117D01*
G01X862917Y101867D02*
X864667Y99700D01*
G01X867600Y101950D02*
X870267D01*
X870017Y102533D01*
X869600Y102867D01*
X869017Y103033D01*
X868433Y102950D01*
X867933Y102700D01*
X867600Y102117D01*
X867433Y101617D01*
Y101117D01*
X867600Y100617D01*
X868017Y100117D01*
X868517Y99783D01*
X869100Y99700D01*
X869683Y99867D01*
X870267Y100367D01*
G01X873033Y99700D02*
Y103033D01*
G01Y102200D02*
X873367Y102617D01*
X873867Y102950D01*
X874533Y103033D01*
X875117Y102950D01*
X875617Y102617D01*
X875867Y102033D01*
Y99700D01*
G01X885650D02*
Y104700D01*
G01X892750Y99700D02*
Y103033D01*
G01Y102450D02*
X892417Y102783D01*
X891917Y102950D01*
X891333Y103033D01*
X890750Y102867D01*
X890250Y102533D01*
X889917Y102033D01*
X889750Y101367D01*
X889917Y100700D01*
X890250Y100200D01*
X890750Y99867D01*
X891333Y99700D01*
X891917Y99783D01*
X892417Y100033D01*
X892750Y100367D01*
G01X895100Y98200D02*
X895600Y98033D01*
X896267Y98200D01*
X896683Y98533D01*
X897017Y98950D01*
X897517Y100283D01*
X898600Y103033D01*
G01X895933D02*
X897517Y100283D01*
G01X901200Y101950D02*
X903867D01*
X903617Y102533D01*
X903200Y102867D01*
X902617Y103033D01*
X902033Y102950D01*
X901533Y102700D01*
X901200Y102117D01*
X901033Y101617D01*
Y101117D01*
X901200Y100617D01*
X901617Y100117D01*
X902117Y99783D01*
X902700Y99700D01*
X903283Y99867D01*
X903867Y100367D01*
G01X906883Y99700D02*
Y103033D01*
G01Y102367D02*
X907300Y102700D01*
X907717Y102950D01*
X908300Y103033D01*
X908717Y102950D01*
X909217Y102700D01*
G01X777167Y123000D02*
Y128000D01*
X778833D01*
X779500Y127750D01*
X780000Y127417D01*
X780417Y126917D01*
X780750Y126333D01*
X780833Y125500D01*
X780750Y124667D01*
X780417Y124083D01*
X780000Y123583D01*
X779500Y123250D01*
X778833Y123000D01*
X777167D01*
G01X783433D02*
Y126333D01*
G01Y125667D02*
X783850Y126000D01*
X784267Y126250D01*
X784850Y126333D01*
X785267Y126250D01*
X785767Y126000D01*
G01X790200Y126333D02*
Y123000D01*
G01Y127667D02*
X790033Y127750D01*
Y127917D01*
X790200Y128000D01*
X790367Y127917D01*
Y127750D01*
X790200Y127667D01*
G01X795800Y123000D02*
Y128000D01*
G01X801400Y123000D02*
Y128000D01*
G01X811017Y123000D02*
Y128000D01*
X814183D01*
G01X813017Y125583D02*
X811017D01*
G01X817033Y123000D02*
Y126333D01*
G01Y125667D02*
X817450Y126000D01*
X817867Y126250D01*
X818450Y126333D01*
X818867Y126250D01*
X819367Y126000D01*
G01X823800Y123000D02*
X823300Y123083D01*
X822800Y123417D01*
X822467Y124000D01*
X822300Y124667D01*
X822467Y125333D01*
X822800Y125917D01*
X823300Y126250D01*
X823800Y126333D01*
X824300Y126250D01*
X824800Y125917D01*
X825133Y125333D01*
X825217Y124667D01*
X825133Y124000D01*
X824800Y123417D01*
X824300Y123083D01*
X823800Y123000D01*
G01X826900D02*
Y126333D01*
G01Y125417D02*
X827150Y125833D01*
X827567Y126167D01*
X828150Y126333D01*
X828733Y126167D01*
X829150Y125833D01*
X829400Y125417D01*
Y123000D01*
G01Y125417D02*
X829650Y125833D01*
X830067Y126167D01*
X830650Y126333D01*
X831233Y126167D01*
X831650Y125833D01*
X831900Y125333D01*
Y123000D01*
G01X838933Y128000D02*
Y123000D01*
X842267D01*
G01X846200D02*
Y128000D01*
X845200Y127000D01*
G01Y123000D02*
X847200D01*
G01X856983Y121333D02*
X856150Y122167D01*
X855733Y123000D01*
Y126333D01*
X856150Y127167D01*
X856983Y128000D01*
G01X863000D02*
Y123000D01*
G01X861083Y128000D02*
X864917D01*
G01X868600Y123000D02*
X867933Y123083D01*
X867350Y123417D01*
X866850Y123917D01*
X866517Y124500D01*
X866350Y125167D01*
Y125833D01*
X866517Y126500D01*
X866850Y127083D01*
X867350Y127583D01*
X867933Y127917D01*
X868600Y128000D01*
X869267Y127917D01*
X869850Y127583D01*
X870350Y127083D01*
X870683Y126500D01*
X870850Y125833D01*
Y125167D01*
X870683Y124500D01*
X870350Y123917D01*
X869850Y123417D01*
X869267Y123083D01*
X868600Y123000D01*
G01X872533D02*
Y128000D01*
X874533D01*
X875200Y127750D01*
X875700Y127167D01*
X875867Y126500D01*
X875700Y125833D01*
X875283Y125333D01*
X874533Y125083D01*
X872533D01*
G01X880217Y121333D02*
X881050Y122167D01*
X881467Y123000D01*
Y126333D01*
X881050Y127167D01*
X880217Y128000D01*
G01X891000D02*
Y123000D01*
G01X889833Y126333D02*
X892167D01*
G01X896600Y123000D02*
X896100Y123083D01*
X895600Y123417D01*
X895267Y124000D01*
X895100Y124667D01*
X895267Y125333D01*
X895600Y125917D01*
X896100Y126250D01*
X896600Y126333D01*
X897100Y126250D01*
X897600Y125917D01*
X897933Y125333D01*
X898017Y124667D01*
X897933Y124000D01*
X897600Y123417D01*
X897100Y123083D01*
X896600Y123000D01*
G01X906133Y128000D02*
Y123000D01*
X909467D01*
G01X912150Y126333D02*
X914650Y123000D01*
G01Y126333D02*
X912150Y123000D01*
G01X776983Y116310D02*
Y111310D01*
X780317D01*
G01X782833D02*
Y114643D01*
G01Y113810D02*
X783167Y114227D01*
X783667Y114560D01*
X784333Y114643D01*
X784917Y114560D01*
X785417Y114227D01*
X785667Y113643D01*
Y111310D01*
G01X789850Y111143D02*
X789683Y111227D01*
Y111393D01*
X789850Y111477D01*
X790017Y111393D01*
Y111227D01*
X789850Y111143D01*
G01Y113393D02*
X789683Y113477D01*
Y113643D01*
X789850Y113727D01*
X790017Y113643D01*
Y113477D01*
X789850Y113393D01*
G01X802383Y114227D02*
X801800Y114560D01*
X801300Y114643D01*
X800633Y114477D01*
X800133Y114143D01*
X799800Y113560D01*
X799717Y112977D01*
X799800Y112393D01*
X800133Y111893D01*
X800633Y111477D01*
X801300Y111310D01*
X801883Y111477D01*
X802383Y111810D01*
G01X808150Y111310D02*
Y114643D01*
G01Y114060D02*
X807817Y114393D01*
X807317Y114560D01*
X806733Y114643D01*
X806150Y114477D01*
X805650Y114143D01*
X805317Y113643D01*
X805150Y112977D01*
X805317Y112310D01*
X805650Y111810D01*
X806150Y111477D01*
X806733Y111310D01*
X807317Y111393D01*
X807817Y111643D01*
X808150Y111977D01*
G01X810833Y111310D02*
Y114643D01*
G01Y113810D02*
X811167Y114227D01*
X811667Y114560D01*
X812333Y114643D01*
X812917Y114560D01*
X813417Y114227D01*
X813667Y113643D01*
Y111310D01*
G01X817850Y114643D02*
X818683Y115685D01*
Y116310D01*
X818058D01*
Y115685D01*
X818683D01*
G01X823450Y116310D02*
Y111310D01*
G01X822283Y114643D02*
X824617D01*
G01X833150Y111310D02*
Y116310D01*
G01Y113810D02*
X833567Y114310D01*
X834067Y114560D01*
X834567Y114643D01*
X835317Y114477D01*
X835817Y114143D01*
X836150Y113560D01*
Y112893D01*
X835983Y112227D01*
X835650Y111727D01*
X835067Y111393D01*
X834567Y111310D01*
X834067Y111393D01*
X833567Y111643D01*
X833150Y112060D01*
G01X839000Y113560D02*
X841667D01*
X841417Y114143D01*
X841000Y114477D01*
X840417Y114643D01*
X839833Y114560D01*
X839333Y114310D01*
X839000Y113727D01*
X838833Y113227D01*
Y112727D01*
X839000Y112227D01*
X839417Y111727D01*
X839917Y111393D01*
X840500Y111310D01*
X841083Y111477D01*
X841667Y111977D01*
G01X849950Y111310D02*
Y116310D01*
G01Y113810D02*
X850367Y114310D01*
X850867Y114560D01*
X851367Y114643D01*
X852117Y114477D01*
X852617Y114143D01*
X852950Y113560D01*
Y112893D01*
X852783Y112227D01*
X852450Y111727D01*
X851867Y111393D01*
X851367Y111310D01*
X850867Y111393D01*
X850367Y111643D01*
X849950Y112060D01*
G01X855883Y111310D02*
Y114643D01*
G01Y113977D02*
X856300Y114310D01*
X856717Y114560D01*
X857300Y114643D01*
X857717Y114560D01*
X858217Y114310D01*
G01X862650Y111310D02*
X862150Y111393D01*
X861650Y111727D01*
X861317Y112310D01*
X861150Y112977D01*
X861317Y113643D01*
X861650Y114227D01*
X862150Y114560D01*
X862650Y114643D01*
X863150Y114560D01*
X863650Y114227D01*
X863983Y113643D01*
X864067Y112977D01*
X863983Y112310D01*
X863650Y111727D01*
X863150Y111393D01*
X862650Y111310D01*
G01X866833D02*
Y116310D01*
G01X869500Y114643D02*
X866833Y112727D01*
G01X867917Y113477D02*
X869667Y111310D01*
G01X872600Y113560D02*
X875267D01*
X875017Y114143D01*
X874600Y114477D01*
X874017Y114643D01*
X873433Y114560D01*
X872933Y114310D01*
X872600Y113727D01*
X872433Y113227D01*
Y112727D01*
X872600Y112227D01*
X873017Y111727D01*
X873517Y111393D01*
X874100Y111310D01*
X874683Y111477D01*
X875267Y111977D01*
G01X878033Y111310D02*
Y114643D01*
G01Y113810D02*
X878367Y114227D01*
X878867Y114560D01*
X879533Y114643D01*
X880117Y114560D01*
X880617Y114227D01*
X880867Y113643D01*
Y111310D01*
G01X890650D02*
Y116310D01*
G01X897750Y111310D02*
Y114643D01*
G01Y114060D02*
X897417Y114393D01*
X896917Y114560D01*
X896333Y114643D01*
X895750Y114477D01*
X895250Y114143D01*
X894917Y113643D01*
X894750Y112977D01*
X894917Y112310D01*
X895250Y111810D01*
X895750Y111477D01*
X896333Y111310D01*
X896917Y111393D01*
X897417Y111643D01*
X897750Y111977D01*
G01X900100Y109810D02*
X900600Y109643D01*
X901267Y109810D01*
X901683Y110143D01*
X902017Y110560D01*
X902517Y111893D01*
X903600Y114643D01*
G01X900933D02*
X902517Y111893D01*
G01X906200Y113560D02*
X908867D01*
X908617Y114143D01*
X908200Y114477D01*
X907617Y114643D01*
X907033Y114560D01*
X906533Y114310D01*
X906200Y113727D01*
X906033Y113227D01*
Y112727D01*
X906200Y112227D01*
X906617Y111727D01*
X907117Y111393D01*
X907700Y111310D01*
X908283Y111477D01*
X908867Y111977D01*
G01X911883Y111310D02*
Y114643D01*
G01Y113977D02*
X912300Y114310D01*
X912717Y114560D01*
X913300Y114643D01*
X913717Y114560D01*
X914217Y114310D01*
G01X794500Y674500D02*
Y669500D01*
G01X793333Y672833D02*
X795667D01*
G01X798683Y669500D02*
Y674500D01*
G01Y672083D02*
X799100Y672500D01*
X799517Y672750D01*
X800183Y672833D01*
X800683Y672750D01*
X801267Y672417D01*
X801517Y671917D01*
Y669500D01*
G01X805700Y672833D02*
Y669500D01*
G01Y674167D02*
X805533Y674250D01*
Y674417D01*
X805700Y674500D01*
X805867Y674417D01*
Y674250D01*
X805700Y674167D01*
G01X812633Y672417D02*
X812050Y672750D01*
X811550Y672833D01*
X810883Y672667D01*
X810383Y672333D01*
X810050Y671750D01*
X809967Y671167D01*
X810050Y670583D01*
X810383Y670083D01*
X810883Y669667D01*
X811550Y669500D01*
X812133Y669667D01*
X812633Y670000D01*
G01X815483Y669500D02*
Y674500D01*
G01X818150Y672833D02*
X815483Y670917D01*
G01X816567Y671667D02*
X818317Y669500D01*
G01X821083D02*
Y672833D01*
G01Y672000D02*
X821417Y672417D01*
X821917Y672750D01*
X822583Y672833D01*
X823167Y672750D01*
X823667Y672417D01*
X823917Y671833D01*
Y669500D01*
G01X826850Y671750D02*
X829517D01*
X829267Y672333D01*
X828850Y672667D01*
X828267Y672833D01*
X827683Y672750D01*
X827183Y672500D01*
X826850Y671917D01*
X826683Y671417D01*
Y670917D01*
X826850Y670417D01*
X827267Y669917D01*
X827767Y669583D01*
X828350Y669500D01*
X828933Y669667D01*
X829517Y670167D01*
G01X832450Y670083D02*
X832867Y669750D01*
X833450Y669500D01*
X833950D01*
X834450Y669667D01*
X834783Y669917D01*
X834950Y670250D01*
X834867Y670750D01*
X834533Y671000D01*
X833033Y671500D01*
X832700Y672083D01*
X832867Y672500D01*
X833200Y672750D01*
X833700Y672833D01*
X834200Y672750D01*
X834700Y672500D01*
G01X838050Y670083D02*
X838467Y669750D01*
X839050Y669500D01*
X839550D01*
X840050Y669667D01*
X840383Y669917D01*
X840550Y670250D01*
X840467Y670750D01*
X840133Y671000D01*
X838633Y671500D01*
X838300Y672083D01*
X838467Y672500D01*
X838800Y672750D01*
X839300Y672833D01*
X839800Y672750D01*
X840300Y672500D01*
G01X788000Y850610D02*
Y782110D01*
G01X798500Y795500D02*
Y790500D01*
G01X796583Y795500D02*
X800417D01*
G01X802017Y793833D02*
X803017Y790500D01*
X804100Y793833D01*
X805183Y790500D01*
X806183Y793833D01*
G01X809700D02*
Y790500D01*
G01Y795167D02*
X809533Y795250D01*
Y795417D01*
X809700Y795500D01*
X809867Y795417D01*
Y795250D01*
X809700Y795167D01*
G01X814050Y791083D02*
X814467Y790750D01*
X815050Y790500D01*
X815550D01*
X816050Y790667D01*
X816383Y790917D01*
X816550Y791250D01*
X816467Y791750D01*
X816133Y792000D01*
X814633Y792500D01*
X814300Y793083D01*
X814467Y793500D01*
X814800Y793750D01*
X815300Y793833D01*
X815800Y793750D01*
X816300Y793500D01*
G01X820900Y795500D02*
Y790500D01*
G01X819733Y793833D02*
X822067D01*
G01X833600Y790500D02*
Y793833D01*
G01Y793250D02*
X833267Y793583D01*
X832767Y793750D01*
X832183Y793833D01*
X831600Y793667D01*
X831100Y793333D01*
X830767Y792833D01*
X830600Y792167D01*
X830767Y791500D01*
X831100Y791000D01*
X831600Y790667D01*
X832183Y790500D01*
X832767Y790583D01*
X833267Y790833D01*
X833600Y791167D01*
G01X836283Y790500D02*
Y793833D01*
G01Y793000D02*
X836617Y793417D01*
X837117Y793750D01*
X837783Y793833D01*
X838367Y793750D01*
X838867Y793417D01*
X839117Y792833D01*
Y790500D01*
G01X844800Y795500D02*
Y790500D01*
G01Y791250D02*
X844467Y790833D01*
X843967Y790583D01*
X843383Y790500D01*
X842717Y790667D01*
X842217Y791083D01*
X841883Y791583D01*
X841800Y792167D01*
X841883Y792750D01*
X842217Y793250D01*
X842717Y793667D01*
X843383Y793833D01*
X843967Y793750D01*
X844383Y793583D01*
X844800Y793250D01*
G01X853000Y790500D02*
Y795500D01*
G01Y793000D02*
X853417Y793500D01*
X853917Y793750D01*
X854417Y793833D01*
X855167Y793667D01*
X855667Y793333D01*
X856000Y792750D01*
Y792083D01*
X855833Y791417D01*
X855500Y790917D01*
X854917Y790583D01*
X854417Y790500D01*
X853917Y790583D01*
X853417Y790833D01*
X853000Y791250D01*
G01X860100Y790500D02*
X859600Y790583D01*
X859100Y790917D01*
X858767Y791500D01*
X858600Y792167D01*
X858767Y792833D01*
X859100Y793417D01*
X859600Y793750D01*
X860100Y793833D01*
X860600Y793750D01*
X861100Y793417D01*
X861433Y792833D01*
X861517Y792167D01*
X861433Y791500D01*
X861100Y790917D01*
X860600Y790583D01*
X860100Y790500D01*
G01X863617Y793833D02*
X864617Y790500D01*
X865700Y793833D01*
X866783Y790500D01*
X867783Y793833D01*
G01X788000Y805500D02*
X1343000D01*
G01X796833Y826500D02*
Y831500D01*
X798917D01*
X799583Y831250D01*
X800000Y830917D01*
X800167Y830250D01*
X800000Y829583D01*
X799500Y829167D01*
X798917Y828917D01*
X796833D01*
G01X798917D02*
X800167Y826500D01*
G01X804100D02*
X803600Y826583D01*
X803100Y826917D01*
X802767Y827500D01*
X802600Y828167D01*
X802767Y828833D01*
X803100Y829417D01*
X803600Y829750D01*
X804100Y829833D01*
X804600Y829750D01*
X805100Y829417D01*
X805433Y828833D01*
X805517Y828167D01*
X805433Y827500D01*
X805100Y826917D01*
X804600Y826583D01*
X804100Y826500D01*
G01X808283Y829833D02*
Y827500D01*
X808617Y826917D01*
X809117Y826583D01*
X809700Y826500D01*
X810283Y826583D01*
X810783Y826917D01*
X811117Y827500D01*
G01Y826500D02*
Y829833D01*
G01X815300Y831500D02*
Y826500D01*
G01X814133Y829833D02*
X816467D01*
G01X820900D02*
Y826500D01*
G01Y831167D02*
X820733Y831250D01*
Y831417D01*
X820900Y831500D01*
X821067Y831417D01*
Y831250D01*
X820900Y831167D01*
G01X825083Y826500D02*
Y829833D01*
G01Y829000D02*
X825417Y829417D01*
X825917Y829750D01*
X826583Y829833D01*
X827167Y829750D01*
X827667Y829417D01*
X827917Y828833D01*
Y826500D01*
G01X830933Y825250D02*
X831517Y824917D01*
X832183Y824833D01*
X832767Y824917D01*
X833267Y825333D01*
X833600Y825917D01*
Y829833D01*
G01Y829167D02*
X833267Y829500D01*
X832767Y829750D01*
X832183Y829833D01*
X831517Y829667D01*
X831100Y829333D01*
X830767Y828750D01*
X830600Y828167D01*
X830683Y827667D01*
X831017Y827083D01*
X831517Y826667D01*
X832183Y826500D01*
X832683Y826583D01*
X833267Y826917D01*
X833600Y827250D01*
G01X843300Y831500D02*
Y826500D01*
G01X842133Y829833D02*
X844467D01*
G01X848900Y826500D02*
X848400Y826583D01*
X847900Y826917D01*
X847567Y827500D01*
X847400Y828167D01*
X847567Y828833D01*
X847900Y829417D01*
X848400Y829750D01*
X848900Y829833D01*
X849400Y829750D01*
X849900Y829417D01*
X850233Y828833D01*
X850317Y828167D01*
X850233Y827500D01*
X849900Y826917D01*
X849400Y826583D01*
X848900Y826500D01*
G01X854500D02*
Y831500D01*
G01X858850Y828750D02*
X861517D01*
X861267Y829333D01*
X860850Y829667D01*
X860267Y829833D01*
X859683Y829750D01*
X859183Y829500D01*
X858850Y828917D01*
X858683Y828417D01*
Y827917D01*
X858850Y827417D01*
X859267Y826917D01*
X859767Y826583D01*
X860350Y826500D01*
X860933Y826667D01*
X861517Y827167D01*
G01X864533Y826500D02*
Y829833D01*
G01Y829167D02*
X864950Y829500D01*
X865367Y829750D01*
X865950Y829833D01*
X866367Y829750D01*
X866867Y829500D01*
G01X872800Y826500D02*
Y829833D01*
G01Y829250D02*
X872467Y829583D01*
X871967Y829750D01*
X871383Y829833D01*
X870800Y829667D01*
X870300Y829333D01*
X869967Y828833D01*
X869800Y828167D01*
X869967Y827500D01*
X870300Y827000D01*
X870800Y826667D01*
X871383Y826500D01*
X871967Y826583D01*
X872467Y826833D01*
X872800Y827167D01*
G01X875483Y826500D02*
Y829833D01*
G01Y829000D02*
X875817Y829417D01*
X876317Y829750D01*
X876983Y829833D01*
X877567Y829750D01*
X878067Y829417D01*
X878317Y828833D01*
Y826500D01*
G01X883833Y829417D02*
X883250Y829750D01*
X882750Y829833D01*
X882083Y829667D01*
X881583Y829333D01*
X881250Y828750D01*
X881167Y828167D01*
X881250Y827583D01*
X881583Y827083D01*
X882083Y826667D01*
X882750Y826500D01*
X883333Y826667D01*
X883833Y827000D01*
G01X886850Y828750D02*
X889517D01*
X889267Y829333D01*
X888850Y829667D01*
X888267Y829833D01*
X887683Y829750D01*
X887183Y829500D01*
X886850Y828917D01*
X886683Y828417D01*
Y827917D01*
X886850Y827417D01*
X887267Y826917D01*
X887767Y826583D01*
X888350Y826500D01*
X888933Y826667D01*
X889517Y827167D01*
G01X827667Y150500D02*
Y155500D01*
X829333D01*
X830000Y155250D01*
X830500Y154917D01*
X830917Y154417D01*
X831250Y153833D01*
X831333Y153000D01*
X831250Y152167D01*
X830917Y151583D01*
X830500Y151083D01*
X830000Y150750D01*
X829333Y150500D01*
X827667D01*
G01X835100D02*
Y155500D01*
X834100Y154500D01*
G01Y150500D02*
X836100D01*
G01X825667Y314500D02*
Y319500D01*
X827333D01*
X828000Y319250D01*
X828500Y318917D01*
X828917Y318417D01*
X829250Y317833D01*
X829333Y317000D01*
X829250Y316167D01*
X828917Y315583D01*
X828500Y315083D01*
X828000Y314750D01*
X827333Y314500D01*
X825667D01*
G01X831517Y318667D02*
X832017Y319167D01*
X832600Y319417D01*
X833267Y319500D01*
X834100Y319333D01*
X834683Y318917D01*
X834850Y318417D01*
X834767Y317917D01*
X834433Y317500D01*
X832767Y316667D01*
X832017Y316083D01*
X831517Y315250D01*
X831350Y314500D01*
X834850D01*
G01X821590Y376450D02*
Y379783D01*
G01Y379200D02*
X821257Y379533D01*
X820757Y379700D01*
X820173Y379783D01*
X819590Y379617D01*
X819090Y379283D01*
X818757Y378783D01*
X818590Y378117D01*
X818757Y377450D01*
X819090Y376950D01*
X819590Y376617D01*
X820173Y376450D01*
X820757Y376533D01*
X821257Y376783D01*
X821590Y377117D01*
G01X824273Y376450D02*
Y379783D01*
G01Y378950D02*
X824607Y379367D01*
X825107Y379700D01*
X825773Y379783D01*
X826357Y379700D01*
X826857Y379367D01*
X827107Y378783D01*
Y376450D01*
G01X832790Y381450D02*
Y376450D01*
G01Y377200D02*
X832457Y376783D01*
X831957Y376533D01*
X831373Y376450D01*
X830707Y376617D01*
X830207Y377033D01*
X829873Y377533D01*
X829790Y378117D01*
X829873Y378700D01*
X830207Y379200D01*
X830707Y379617D01*
X831373Y379783D01*
X831957Y379700D01*
X832373Y379533D01*
X832790Y379200D01*
G01X843823Y379367D02*
X843240Y379700D01*
X842740Y379783D01*
X842073Y379617D01*
X841573Y379283D01*
X841240Y378700D01*
X841157Y378117D01*
X841240Y377533D01*
X841573Y377033D01*
X842073Y376617D01*
X842740Y376450D01*
X843323Y376617D01*
X843823Y376950D01*
G01X848090Y376450D02*
X847590Y376533D01*
X847090Y376867D01*
X846757Y377450D01*
X846590Y378117D01*
X846757Y378783D01*
X847090Y379367D01*
X847590Y379700D01*
X848090Y379783D01*
X848590Y379700D01*
X849090Y379367D01*
X849423Y378783D01*
X849507Y378117D01*
X849423Y377450D01*
X849090Y376867D01*
X848590Y376533D01*
X848090Y376450D01*
G01X852190Y379783D02*
X853690Y376450D01*
X855190Y379783D01*
G01X858040Y378700D02*
X860707D01*
X860457Y379283D01*
X860040Y379617D01*
X859457Y379783D01*
X858873Y379700D01*
X858373Y379450D01*
X858040Y378867D01*
X857873Y378367D01*
Y377867D01*
X858040Y377367D01*
X858457Y376867D01*
X858957Y376533D01*
X859540Y376450D01*
X860123Y376617D01*
X860707Y377117D01*
G01X863723Y376450D02*
Y379783D01*
G01Y379117D02*
X864140Y379450D01*
X864557Y379700D01*
X865140Y379783D01*
X865557Y379700D01*
X866057Y379450D01*
G01X869240Y378700D02*
X871907D01*
X871657Y379283D01*
X871240Y379617D01*
X870657Y379783D01*
X870073Y379700D01*
X869573Y379450D01*
X869240Y378867D01*
X869073Y378367D01*
Y377867D01*
X869240Y377367D01*
X869657Y376867D01*
X870157Y376533D01*
X870740Y376450D01*
X871323Y376617D01*
X871907Y377117D01*
G01X877590Y381450D02*
Y376450D01*
G01Y377200D02*
X877257Y376783D01*
X876757Y376533D01*
X876173Y376450D01*
X875507Y376617D01*
X875007Y377033D01*
X874673Y377533D01*
X874590Y378117D01*
X874673Y378700D01*
X875007Y379200D01*
X875507Y379617D01*
X876173Y379783D01*
X876757Y379700D01*
X877173Y379533D01*
X877590Y379200D01*
G01X885207Y379783D02*
X886207Y376450D01*
X887290Y379783D01*
X888373Y376450D01*
X889373Y379783D01*
G01X892890D02*
Y376450D01*
G01Y381117D02*
X892723Y381200D01*
Y381367D01*
X892890Y381450D01*
X893057Y381367D01*
Y381200D01*
X892890Y381117D01*
G01X898490Y381450D02*
Y376450D01*
G01X897323Y379783D02*
X899657D01*
G01X902673Y376450D02*
Y381450D01*
G01Y379033D02*
X903090Y379450D01*
X903507Y379700D01*
X904173Y379783D01*
X904673Y379700D01*
X905257Y379367D01*
X905507Y378867D01*
Y376450D01*
G01X916623Y379367D02*
X916040Y379700D01*
X915540Y379783D01*
X914873Y379617D01*
X914373Y379283D01*
X914040Y378700D01*
X913957Y378117D01*
X914040Y377533D01*
X914373Y377033D01*
X914873Y376617D01*
X915540Y376450D01*
X916123Y376617D01*
X916623Y376950D01*
G01X920890Y376450D02*
X920390Y376533D01*
X919890Y376867D01*
X919557Y377450D01*
X919390Y378117D01*
X919557Y378783D01*
X919890Y379367D01*
X920390Y379700D01*
X920890Y379783D01*
X921390Y379700D01*
X921890Y379367D01*
X922223Y378783D01*
X922307Y378117D01*
X922223Y377450D01*
X921890Y376867D01*
X921390Y376533D01*
X920890Y376450D01*
G01X924990Y374783D02*
Y379783D01*
G01Y379033D02*
X925407Y379450D01*
X925823Y379700D01*
X926490Y379783D01*
X927073Y379700D01*
X927657Y379283D01*
X927907Y378700D01*
X927990Y378117D01*
X927907Y377533D01*
X927657Y376950D01*
X927157Y376617D01*
X926490Y376450D01*
X925907Y376533D01*
X925323Y376783D01*
X924990Y377117D01*
G01X930590Y374783D02*
Y379783D01*
G01Y379033D02*
X931007Y379450D01*
X931423Y379700D01*
X932090Y379783D01*
X932673Y379700D01*
X933257Y379283D01*
X933507Y378700D01*
X933590Y378117D01*
X933507Y377533D01*
X933257Y376950D01*
X932757Y376617D01*
X932090Y376450D01*
X931507Y376533D01*
X930923Y376783D01*
X930590Y377117D01*
G01X936440Y378700D02*
X939107D01*
X938857Y379283D01*
X938440Y379617D01*
X937857Y379783D01*
X937273Y379700D01*
X936773Y379450D01*
X936440Y378867D01*
X936273Y378367D01*
Y377867D01*
X936440Y377367D01*
X936857Y376867D01*
X937357Y376533D01*
X937940Y376450D01*
X938523Y376617D01*
X939107Y377117D01*
G01X942123Y376450D02*
Y379783D01*
G01Y379117D02*
X942540Y379450D01*
X942957Y379700D01*
X943540Y379783D01*
X943957Y379700D01*
X944457Y379450D01*
G01X812000Y604500D02*
Y366000D01*
G01X819590Y389810D02*
Y394060D01*
X819757Y394477D01*
X820090Y394727D01*
X820590Y394810D01*
X821090Y394643D01*
X821340Y394227D01*
G01X820340Y392810D02*
X818673D01*
G01X825690Y389810D02*
X825190Y389893D01*
X824690Y390227D01*
X824357Y390810D01*
X824190Y391477D01*
X824357Y392143D01*
X824690Y392727D01*
X825190Y393060D01*
X825690Y393143D01*
X826190Y393060D01*
X826690Y392727D01*
X827023Y392143D01*
X827107Y391477D01*
X827023Y390810D01*
X826690Y390227D01*
X826190Y389893D01*
X825690Y389810D01*
G01X831290D02*
Y394810D01*
G01X836890Y389810D02*
Y394810D01*
G01X842490Y389810D02*
X841990Y389893D01*
X841490Y390227D01*
X841157Y390810D01*
X840990Y391477D01*
X841157Y392143D01*
X841490Y392727D01*
X841990Y393060D01*
X842490Y393143D01*
X842990Y393060D01*
X843490Y392727D01*
X843823Y392143D01*
X843907Y391477D01*
X843823Y390810D01*
X843490Y390227D01*
X842990Y389893D01*
X842490Y389810D01*
G01X846007Y393143D02*
X847007Y389810D01*
X848090Y393143D01*
X849173Y389810D01*
X850173Y393143D01*
G01X859790Y392310D02*
X861457D01*
Y390810D01*
X860957Y390310D01*
X860373Y389977D01*
X859540Y389810D01*
X858707Y389977D01*
X858123Y390310D01*
X857623Y390810D01*
X857290Y391393D01*
X857123Y392060D01*
Y392643D01*
X857290Y393143D01*
X857623Y393727D01*
X858123Y394227D01*
X858623Y394560D01*
X859290Y394810D01*
X859873D01*
X860540Y394643D01*
X861040Y394310D01*
G01X863640Y392060D02*
X866307D01*
X866057Y392643D01*
X865640Y392977D01*
X865057Y393143D01*
X864473Y393060D01*
X863973Y392810D01*
X863640Y392227D01*
X863473Y391727D01*
Y391227D01*
X863640Y390727D01*
X864057Y390227D01*
X864557Y389893D01*
X865140Y389810D01*
X865723Y389977D01*
X866307Y390477D01*
G01X869323Y389810D02*
Y393143D01*
G01Y392477D02*
X869740Y392810D01*
X870157Y393060D01*
X870740Y393143D01*
X871157Y393060D01*
X871657Y392810D01*
G01X874590Y389810D02*
Y394810D01*
G01Y392310D02*
X875007Y392810D01*
X875507Y393060D01*
X876007Y393143D01*
X876757Y392977D01*
X877257Y392643D01*
X877590Y392060D01*
Y391393D01*
X877423Y390727D01*
X877090Y390227D01*
X876507Y389893D01*
X876007Y389810D01*
X875507Y389893D01*
X875007Y390143D01*
X874590Y390560D01*
G01X880440Y392060D02*
X883107D01*
X882857Y392643D01*
X882440Y392977D01*
X881857Y393143D01*
X881273Y393060D01*
X880773Y392810D01*
X880440Y392227D01*
X880273Y391727D01*
Y391227D01*
X880440Y390727D01*
X880857Y390227D01*
X881357Y389893D01*
X881940Y389810D01*
X882523Y389977D01*
X883107Y390477D01*
G01X886123Y389810D02*
Y393143D01*
G01Y392477D02*
X886540Y392810D01*
X886957Y393060D01*
X887540Y393143D01*
X887957Y393060D01*
X888457Y392810D01*
G01X899990Y389810D02*
Y393143D01*
G01Y392560D02*
X899657Y392893D01*
X899157Y393060D01*
X898573Y393143D01*
X897990Y392977D01*
X897490Y392643D01*
X897157Y392143D01*
X896990Y391477D01*
X897157Y390810D01*
X897490Y390310D01*
X897990Y389977D01*
X898573Y389810D01*
X899157Y389893D01*
X899657Y390143D01*
X899990Y390477D01*
G01X902673Y389810D02*
Y393143D01*
G01Y392310D02*
X903007Y392727D01*
X903507Y393060D01*
X904173Y393143D01*
X904757Y393060D01*
X905257Y392727D01*
X905507Y392143D01*
Y389810D01*
G01X911190Y394810D02*
Y389810D01*
G01Y390560D02*
X910857Y390143D01*
X910357Y389893D01*
X909773Y389810D01*
X909107Y389977D01*
X908607Y390393D01*
X908273Y390893D01*
X908190Y391477D01*
X908273Y392060D01*
X908607Y392560D01*
X909107Y392977D01*
X909773Y393143D01*
X910357Y393060D01*
X910773Y392893D01*
X911190Y392560D01*
G01X919390Y388143D02*
Y393143D01*
G01Y392393D02*
X919807Y392810D01*
X920223Y393060D01*
X920890Y393143D01*
X921473Y393060D01*
X922057Y392643D01*
X922307Y392060D01*
X922390Y391477D01*
X922307Y390893D01*
X922057Y390310D01*
X921557Y389977D01*
X920890Y389810D01*
X920307Y389893D01*
X919723Y390143D01*
X919390Y390477D01*
G01X926490Y389810D02*
Y394810D01*
G01X930673Y393143D02*
Y390810D01*
X931007Y390227D01*
X931507Y389893D01*
X932090Y389810D01*
X932673Y389893D01*
X933173Y390227D01*
X933507Y390810D01*
G01Y389810D02*
Y393143D01*
G01X936523Y388560D02*
X937107Y388227D01*
X937773Y388143D01*
X938357Y388227D01*
X938857Y388643D01*
X939190Y389227D01*
Y393143D01*
G01Y392477D02*
X938857Y392810D01*
X938357Y393060D01*
X937773Y393143D01*
X937107Y392977D01*
X936690Y392643D01*
X936357Y392060D01*
X936190Y391477D01*
X936273Y390977D01*
X936607Y390393D01*
X937107Y389977D01*
X937773Y389810D01*
X938273Y389893D01*
X938857Y390227D01*
X939190Y390560D01*
G01X946807Y393143D02*
X947807Y389810D01*
X948890Y393143D01*
X949973Y389810D01*
X950973Y393143D01*
G01X954490D02*
Y389810D01*
G01Y394477D02*
X954323Y394560D01*
Y394727D01*
X954490Y394810D01*
X954657Y394727D01*
Y394560D01*
X954490Y394477D01*
G01X960090Y394810D02*
Y389810D01*
G01X958923Y393143D02*
X961257D01*
G01X964273Y389810D02*
Y394810D01*
G01Y392393D02*
X964690Y392810D01*
X965107Y393060D01*
X965773Y393143D01*
X966273Y393060D01*
X966857Y392727D01*
X967107Y392227D01*
Y389810D01*
G01X975723D02*
Y393143D01*
G01Y392477D02*
X976140Y392810D01*
X976557Y393060D01*
X977140Y393143D01*
X977557Y393060D01*
X978057Y392810D01*
G01X981240Y392060D02*
X983907D01*
X983657Y392643D01*
X983240Y392977D01*
X982657Y393143D01*
X982073Y393060D01*
X981573Y392810D01*
X981240Y392227D01*
X981073Y391727D01*
Y391227D01*
X981240Y390727D01*
X981657Y390227D01*
X982157Y389893D01*
X982740Y389810D01*
X983323Y389977D01*
X983907Y390477D01*
G01X986840Y390393D02*
X987257Y390060D01*
X987840Y389810D01*
X988340D01*
X988840Y389977D01*
X989173Y390227D01*
X989340Y390560D01*
X989257Y391060D01*
X988923Y391310D01*
X987423Y391810D01*
X987090Y392393D01*
X987257Y392810D01*
X987590Y393060D01*
X988090Y393143D01*
X988590Y393060D01*
X989090Y392810D01*
G01X993690Y393143D02*
Y389810D01*
G01Y394477D02*
X993523Y394560D01*
Y394727D01*
X993690Y394810D01*
X993857Y394727D01*
Y394560D01*
X993690Y394477D01*
G01X997873Y389810D02*
Y393143D01*
G01Y392310D02*
X998207Y392727D01*
X998707Y393060D01*
X999373Y393143D01*
X999957Y393060D01*
X1000457Y392727D01*
X1000707Y392143D01*
Y389810D01*
G01X821500Y440500D02*
Y444750D01*
X821667Y445167D01*
X822000Y445417D01*
X822500Y445500D01*
X823000Y445333D01*
X823250Y444917D01*
G01X822250Y443500D02*
X820583D01*
G01X827600Y440500D02*
X827100Y440583D01*
X826600Y440917D01*
X826267Y441500D01*
X826100Y442167D01*
X826267Y442833D01*
X826600Y443417D01*
X827100Y443750D01*
X827600Y443833D01*
X828100Y443750D01*
X828600Y443417D01*
X828933Y442833D01*
X829017Y442167D01*
X828933Y441500D01*
X828600Y440917D01*
X828100Y440583D01*
X827600Y440500D01*
G01X833200D02*
Y445500D01*
G01X838800Y440500D02*
Y445500D01*
G01X844400Y440500D02*
X843900Y440583D01*
X843400Y440917D01*
X843067Y441500D01*
X842900Y442167D01*
X843067Y442833D01*
X843400Y443417D01*
X843900Y443750D01*
X844400Y443833D01*
X844900Y443750D01*
X845400Y443417D01*
X845733Y442833D01*
X845817Y442167D01*
X845733Y441500D01*
X845400Y440917D01*
X844900Y440583D01*
X844400Y440500D01*
G01X847917Y443833D02*
X848917Y440500D01*
X850000Y443833D01*
X851083Y440500D01*
X852083Y443833D01*
G01X861700Y443000D02*
X863367D01*
Y441500D01*
X862867Y441000D01*
X862283Y440667D01*
X861450Y440500D01*
X860617Y440667D01*
X860033Y441000D01*
X859533Y441500D01*
X859200Y442083D01*
X859033Y442750D01*
Y443333D01*
X859200Y443833D01*
X859533Y444417D01*
X860033Y444917D01*
X860533Y445250D01*
X861200Y445500D01*
X861783D01*
X862450Y445333D01*
X862950Y445000D01*
G01X865550Y442750D02*
X868217D01*
X867967Y443333D01*
X867550Y443667D01*
X866967Y443833D01*
X866383Y443750D01*
X865883Y443500D01*
X865550Y442917D01*
X865383Y442417D01*
Y441917D01*
X865550Y441417D01*
X865967Y440917D01*
X866467Y440583D01*
X867050Y440500D01*
X867633Y440667D01*
X868217Y441167D01*
G01X871233Y440500D02*
Y443833D01*
G01Y443167D02*
X871650Y443500D01*
X872067Y443750D01*
X872650Y443833D01*
X873067Y443750D01*
X873567Y443500D01*
G01X876500Y440500D02*
Y445500D01*
G01Y443000D02*
X876917Y443500D01*
X877417Y443750D01*
X877917Y443833D01*
X878667Y443667D01*
X879167Y443333D01*
X879500Y442750D01*
Y442083D01*
X879333Y441417D01*
X879000Y440917D01*
X878417Y440583D01*
X877917Y440500D01*
X877417Y440583D01*
X876917Y440833D01*
X876500Y441250D01*
G01X882350Y442750D02*
X885017D01*
X884767Y443333D01*
X884350Y443667D01*
X883767Y443833D01*
X883183Y443750D01*
X882683Y443500D01*
X882350Y442917D01*
X882183Y442417D01*
Y441917D01*
X882350Y441417D01*
X882767Y440917D01*
X883267Y440583D01*
X883850Y440500D01*
X884433Y440667D01*
X885017Y441167D01*
G01X888033Y440500D02*
Y443833D01*
G01Y443167D02*
X888450Y443500D01*
X888867Y443750D01*
X889450Y443833D01*
X889867Y443750D01*
X890367Y443500D01*
G01X821500Y419500D02*
Y423750D01*
X821667Y424167D01*
X822000Y424417D01*
X822500Y424500D01*
X823000Y424333D01*
X823250Y423917D01*
G01X822250Y422500D02*
X820583D01*
G01X827600Y419500D02*
X827100Y419583D01*
X826600Y419917D01*
X826267Y420500D01*
X826100Y421167D01*
X826267Y421833D01*
X826600Y422417D01*
X827100Y422750D01*
X827600Y422833D01*
X828100Y422750D01*
X828600Y422417D01*
X828933Y421833D01*
X829017Y421167D01*
X828933Y420500D01*
X828600Y419917D01*
X828100Y419583D01*
X827600Y419500D01*
G01X833200D02*
Y424500D01*
G01X838800Y419500D02*
Y424500D01*
G01X844400Y419500D02*
X843900Y419583D01*
X843400Y419917D01*
X843067Y420500D01*
X842900Y421167D01*
X843067Y421833D01*
X843400Y422417D01*
X843900Y422750D01*
X844400Y422833D01*
X844900Y422750D01*
X845400Y422417D01*
X845733Y421833D01*
X845817Y421167D01*
X845733Y420500D01*
X845400Y419917D01*
X844900Y419583D01*
X844400Y419500D01*
G01X847917Y422833D02*
X848917Y419500D01*
X850000Y422833D01*
X851083Y419500D01*
X852083Y422833D01*
G01X861700Y422000D02*
X863367D01*
Y420500D01*
X862867Y420000D01*
X862283Y419667D01*
X861450Y419500D01*
X860617Y419667D01*
X860033Y420000D01*
X859533Y420500D01*
X859200Y421083D01*
X859033Y421750D01*
Y422333D01*
X859200Y422833D01*
X859533Y423417D01*
X860033Y423917D01*
X860533Y424250D01*
X861200Y424500D01*
X861783D01*
X862450Y424333D01*
X862950Y424000D01*
G01X865550Y421750D02*
X868217D01*
X867967Y422333D01*
X867550Y422667D01*
X866967Y422833D01*
X866383Y422750D01*
X865883Y422500D01*
X865550Y421917D01*
X865383Y421417D01*
Y420917D01*
X865550Y420417D01*
X865967Y419917D01*
X866467Y419583D01*
X867050Y419500D01*
X867633Y419667D01*
X868217Y420167D01*
G01X871233Y419500D02*
Y422833D01*
G01Y422167D02*
X871650Y422500D01*
X872067Y422750D01*
X872650Y422833D01*
X873067Y422750D01*
X873567Y422500D01*
G01X876500Y419500D02*
Y424500D01*
G01Y422000D02*
X876917Y422500D01*
X877417Y422750D01*
X877917Y422833D01*
X878667Y422667D01*
X879167Y422333D01*
X879500Y421750D01*
Y421083D01*
X879333Y420417D01*
X879000Y419917D01*
X878417Y419583D01*
X877917Y419500D01*
X877417Y419583D01*
X876917Y419833D01*
X876500Y420250D01*
G01X882350Y421750D02*
X885017D01*
X884767Y422333D01*
X884350Y422667D01*
X883767Y422833D01*
X883183Y422750D01*
X882683Y422500D01*
X882350Y421917D01*
X882183Y421417D01*
Y420917D01*
X882350Y420417D01*
X882767Y419917D01*
X883267Y419583D01*
X883850Y419500D01*
X884433Y419667D01*
X885017Y420167D01*
G01X888033Y419500D02*
Y422833D01*
G01Y422167D02*
X888450Y422500D01*
X888867Y422750D01*
X889450Y422833D01*
X889867Y422750D01*
X890367Y422500D01*
G01X901900Y419500D02*
Y422833D01*
G01Y422250D02*
X901567Y422583D01*
X901067Y422750D01*
X900483Y422833D01*
X899900Y422667D01*
X899400Y422333D01*
X899067Y421833D01*
X898900Y421167D01*
X899067Y420500D01*
X899400Y420000D01*
X899900Y419667D01*
X900483Y419500D01*
X901067Y419583D01*
X901567Y419833D01*
X901900Y420167D01*
G01X904583Y419500D02*
Y422833D01*
G01Y422000D02*
X904917Y422417D01*
X905417Y422750D01*
X906083Y422833D01*
X906667Y422750D01*
X907167Y422417D01*
X907417Y421833D01*
Y419500D01*
G01X913100Y424500D02*
Y419500D01*
G01Y420250D02*
X912767Y419833D01*
X912267Y419583D01*
X911683Y419500D01*
X911017Y419667D01*
X910517Y420083D01*
X910183Y420583D01*
X910100Y421167D01*
X910183Y421750D01*
X910517Y422250D01*
X911017Y422667D01*
X911683Y422833D01*
X912267Y422750D01*
X912683Y422583D01*
X913100Y422250D01*
G01X921300Y417833D02*
Y422833D01*
G01Y422083D02*
X921717Y422500D01*
X922133Y422750D01*
X922800Y422833D01*
X923383Y422750D01*
X923967Y422333D01*
X924217Y421750D01*
X924300Y421167D01*
X924217Y420583D01*
X923967Y420000D01*
X923467Y419667D01*
X922800Y419500D01*
X922217Y419583D01*
X921633Y419833D01*
X921300Y420167D01*
G01X928400Y419500D02*
Y424500D01*
G01X932583Y422833D02*
Y420500D01*
X932917Y419917D01*
X933417Y419583D01*
X934000Y419500D01*
X934583Y419583D01*
X935083Y419917D01*
X935417Y420500D01*
G01Y419500D02*
Y422833D01*
G01X938433Y418250D02*
X939017Y417917D01*
X939683Y417833D01*
X940267Y417917D01*
X940767Y418333D01*
X941100Y418917D01*
Y422833D01*
G01Y422167D02*
X940767Y422500D01*
X940267Y422750D01*
X939683Y422833D01*
X939017Y422667D01*
X938600Y422333D01*
X938267Y421750D01*
X938100Y421167D01*
X938183Y420667D01*
X938517Y420083D01*
X939017Y419667D01*
X939683Y419500D01*
X940183Y419583D01*
X940767Y419917D01*
X941100Y420250D01*
G01X948717Y422833D02*
X949717Y419500D01*
X950800Y422833D01*
X951883Y419500D01*
X952883Y422833D01*
G01X956400D02*
Y419500D01*
G01Y424167D02*
X956233Y424250D01*
Y424417D01*
X956400Y424500D01*
X956567Y424417D01*
Y424250D01*
X956400Y424167D01*
G01X962000Y424500D02*
Y419500D01*
G01X960833Y422833D02*
X963167D01*
G01X966183Y419500D02*
Y424500D01*
G01Y422083D02*
X966600Y422500D01*
X967017Y422750D01*
X967683Y422833D01*
X968183Y422750D01*
X968767Y422417D01*
X969017Y421917D01*
Y419500D01*
G01X977633D02*
Y422833D01*
G01Y422167D02*
X978050Y422500D01*
X978467Y422750D01*
X979050Y422833D01*
X979467Y422750D01*
X979967Y422500D01*
G01X983150Y421750D02*
X985817D01*
X985567Y422333D01*
X985150Y422667D01*
X984567Y422833D01*
X983983Y422750D01*
X983483Y422500D01*
X983150Y421917D01*
X982983Y421417D01*
Y420917D01*
X983150Y420417D01*
X983567Y419917D01*
X984067Y419583D01*
X984650Y419500D01*
X985233Y419667D01*
X985817Y420167D01*
G01X988750Y420083D02*
X989167Y419750D01*
X989750Y419500D01*
X990250D01*
X990750Y419667D01*
X991083Y419917D01*
X991250Y420250D01*
X991167Y420750D01*
X990833Y421000D01*
X989333Y421500D01*
X989000Y422083D01*
X989167Y422500D01*
X989500Y422750D01*
X990000Y422833D01*
X990500Y422750D01*
X991000Y422500D01*
G01X995600Y422833D02*
Y419500D01*
G01Y424167D02*
X995433Y424250D01*
Y424417D01*
X995600Y424500D01*
X995767Y424417D01*
Y424250D01*
X995600Y424167D01*
G01X999783Y419500D02*
Y422833D01*
G01Y422000D02*
X1000117Y422417D01*
X1000617Y422750D01*
X1001283Y422833D01*
X1001867Y422750D01*
X1002367Y422417D01*
X1002617Y421833D01*
Y419500D01*
G01X823500Y455500D02*
Y458833D01*
G01Y458250D02*
X823167Y458583D01*
X822667Y458750D01*
X822083Y458833D01*
X821500Y458667D01*
X821000Y458333D01*
X820667Y457833D01*
X820500Y457167D01*
X820667Y456500D01*
X821000Y456000D01*
X821500Y455667D01*
X822083Y455500D01*
X822667Y455583D01*
X823167Y455833D01*
X823500Y456167D01*
G01X826183Y455500D02*
Y458833D01*
G01Y458000D02*
X826517Y458417D01*
X827017Y458750D01*
X827683Y458833D01*
X828267Y458750D01*
X828767Y458417D01*
X829017Y457833D01*
Y455500D01*
G01X834700Y460500D02*
Y455500D01*
G01Y456250D02*
X834367Y455833D01*
X833867Y455583D01*
X833283Y455500D01*
X832617Y455667D01*
X832117Y456083D01*
X831783Y456583D01*
X831700Y457167D01*
X831783Y457750D01*
X832117Y458250D01*
X832617Y458667D01*
X833283Y458833D01*
X833867Y458750D01*
X834283Y458583D01*
X834700Y458250D01*
G01X842900Y455500D02*
Y460500D01*
G01Y458000D02*
X843317Y458500D01*
X843817Y458750D01*
X844317Y458833D01*
X845067Y458667D01*
X845567Y458333D01*
X845900Y457750D01*
Y457083D01*
X845733Y456417D01*
X845400Y455917D01*
X844817Y455583D01*
X844317Y455500D01*
X843817Y455583D01*
X843317Y455833D01*
X842900Y456250D01*
G01X850000Y455500D02*
X849500Y455583D01*
X849000Y455917D01*
X848667Y456500D01*
X848500Y457167D01*
X848667Y457833D01*
X849000Y458417D01*
X849500Y458750D01*
X850000Y458833D01*
X850500Y458750D01*
X851000Y458417D01*
X851333Y457833D01*
X851417Y457167D01*
X851333Y456500D01*
X851000Y455917D01*
X850500Y455583D01*
X850000Y455500D01*
G01X855600Y460500D02*
Y455500D01*
G01X854433Y458833D02*
X856767D01*
G01X861200Y460500D02*
Y455500D01*
G01X860033Y458833D02*
X862367D01*
G01X866800Y455500D02*
X866300Y455583D01*
X865800Y455917D01*
X865467Y456500D01*
X865300Y457167D01*
X865467Y457833D01*
X865800Y458417D01*
X866300Y458750D01*
X866800Y458833D01*
X867300Y458750D01*
X867800Y458417D01*
X868133Y457833D01*
X868217Y457167D01*
X868133Y456500D01*
X867800Y455917D01*
X867300Y455583D01*
X866800Y455500D01*
G01X869900D02*
Y458833D01*
G01Y457917D02*
X870150Y458333D01*
X870567Y458667D01*
X871150Y458833D01*
X871733Y458667D01*
X872150Y458333D01*
X872400Y457917D01*
Y455500D01*
G01Y457917D02*
X872650Y458333D01*
X873067Y458667D01*
X873650Y458833D01*
X874233Y458667D01*
X874650Y458333D01*
X874900Y457833D01*
Y455500D01*
G01X882350Y456083D02*
X882767Y455750D01*
X883350Y455500D01*
X883850D01*
X884350Y455667D01*
X884683Y455917D01*
X884850Y456250D01*
X884767Y456750D01*
X884433Y457000D01*
X882933Y457500D01*
X882600Y458083D01*
X882767Y458500D01*
X883100Y458750D01*
X883600Y458833D01*
X884100Y458750D01*
X884600Y458500D01*
G01X889200Y458833D02*
Y455500D01*
G01Y460167D02*
X889033Y460250D01*
Y460417D01*
X889200Y460500D01*
X889367Y460417D01*
Y460250D01*
X889200Y460167D01*
G01X896300Y460500D02*
Y455500D01*
G01Y456250D02*
X895967Y455833D01*
X895467Y455583D01*
X894883Y455500D01*
X894217Y455667D01*
X893717Y456083D01*
X893383Y456583D01*
X893300Y457167D01*
X893383Y457750D01*
X893717Y458250D01*
X894217Y458667D01*
X894883Y458833D01*
X895467Y458750D01*
X895883Y458583D01*
X896300Y458250D01*
G01X899150Y457750D02*
X901817D01*
X901567Y458333D01*
X901150Y458667D01*
X900567Y458833D01*
X899983Y458750D01*
X899483Y458500D01*
X899150Y457917D01*
X898983Y457417D01*
Y456917D01*
X899150Y456417D01*
X899567Y455917D01*
X900067Y455583D01*
X900650Y455500D01*
X901233Y455667D01*
X901817Y456167D01*
G01X819917Y470833D02*
X820917Y467500D01*
X822000Y470833D01*
X823083Y467500D01*
X824083Y470833D01*
G01X827600D02*
Y467500D01*
G01Y472167D02*
X827433Y472250D01*
Y472417D01*
X827600Y472500D01*
X827767Y472417D01*
Y472250D01*
X827600Y472167D01*
G01X833200Y472500D02*
Y467500D01*
G01X832033Y470833D02*
X834367D01*
G01X837383Y467500D02*
Y472500D01*
G01Y470083D02*
X837800Y470500D01*
X838217Y470750D01*
X838883Y470833D01*
X839383Y470750D01*
X839967Y470417D01*
X840217Y469917D01*
Y467500D01*
G01X844400D02*
X843900Y467583D01*
X843400Y467917D01*
X843067Y468500D01*
X842900Y469167D01*
X843067Y469833D01*
X843400Y470417D01*
X843900Y470750D01*
X844400Y470833D01*
X844900Y470750D01*
X845400Y470417D01*
X845733Y469833D01*
X845817Y469167D01*
X845733Y468500D01*
X845400Y467917D01*
X844900Y467583D01*
X844400Y467500D01*
G01X848583Y470833D02*
Y468500D01*
X848917Y467917D01*
X849417Y467583D01*
X850000Y467500D01*
X850583Y467583D01*
X851083Y467917D01*
X851417Y468500D01*
G01Y467500D02*
Y470833D01*
G01X855600Y472500D02*
Y467500D01*
G01X854433Y470833D02*
X856767D01*
G01X865550Y468083D02*
X865967Y467750D01*
X866550Y467500D01*
X867050D01*
X867550Y467667D01*
X867883Y467917D01*
X868050Y468250D01*
X867967Y468750D01*
X867633Y469000D01*
X866133Y469500D01*
X865800Y470083D01*
X865967Y470500D01*
X866300Y470750D01*
X866800Y470833D01*
X867300Y470750D01*
X867800Y470500D01*
G01X872400Y467500D02*
X871900Y467583D01*
X871400Y467917D01*
X871067Y468500D01*
X870900Y469167D01*
X871067Y469833D01*
X871400Y470417D01*
X871900Y470750D01*
X872400Y470833D01*
X872900Y470750D01*
X873400Y470417D01*
X873733Y469833D01*
X873817Y469167D01*
X873733Y468500D01*
X873400Y467917D01*
X872900Y467583D01*
X872400Y467500D01*
G01X878000D02*
Y472500D01*
G01X885100D02*
Y467500D01*
G01Y468250D02*
X884767Y467833D01*
X884267Y467583D01*
X883683Y467500D01*
X883017Y467667D01*
X882517Y468083D01*
X882183Y468583D01*
X882100Y469167D01*
X882183Y469750D01*
X882517Y470250D01*
X883017Y470667D01*
X883683Y470833D01*
X884267Y470750D01*
X884683Y470583D01*
X885100Y470250D01*
G01X887950Y469750D02*
X890617D01*
X890367Y470333D01*
X889950Y470667D01*
X889367Y470833D01*
X888783Y470750D01*
X888283Y470500D01*
X887950Y469917D01*
X887783Y469417D01*
Y468917D01*
X887950Y468417D01*
X888367Y467917D01*
X888867Y467583D01*
X889450Y467500D01*
X890033Y467667D01*
X890617Y468167D01*
G01X893633Y467500D02*
Y470833D01*
G01Y470167D02*
X894050Y470500D01*
X894467Y470750D01*
X895050Y470833D01*
X895467Y470750D01*
X895967Y470500D01*
G01X903500Y467500D02*
Y470833D01*
G01Y469917D02*
X903750Y470333D01*
X904167Y470667D01*
X904750Y470833D01*
X905333Y470667D01*
X905750Y470333D01*
X906000Y469917D01*
Y467500D01*
G01Y469917D02*
X906250Y470333D01*
X906667Y470667D01*
X907250Y470833D01*
X907833Y470667D01*
X908250Y470333D01*
X908500Y469833D01*
Y467500D01*
G01X913100D02*
Y470833D01*
G01Y470250D02*
X912767Y470583D01*
X912267Y470750D01*
X911683Y470833D01*
X911100Y470667D01*
X910600Y470333D01*
X910267Y469833D01*
X910100Y469167D01*
X910267Y468500D01*
X910600Y468000D01*
X911100Y467667D01*
X911683Y467500D01*
X912267Y467583D01*
X912767Y467833D01*
X913100Y468167D01*
G01X915950Y468083D02*
X916367Y467750D01*
X916950Y467500D01*
X917450D01*
X917950Y467667D01*
X918283Y467917D01*
X918450Y468250D01*
X918367Y468750D01*
X918033Y469000D01*
X916533Y469500D01*
X916200Y470083D01*
X916367Y470500D01*
X916700Y470750D01*
X917200Y470833D01*
X917700Y470750D01*
X918200Y470500D01*
G01X921383Y467500D02*
Y472500D01*
G01X924050Y470833D02*
X921383Y468917D01*
G01X922467Y469667D02*
X924217Y467500D01*
G01X932500Y465833D02*
Y470833D01*
G01Y470083D02*
X932917Y470500D01*
X933333Y470750D01*
X934000Y470833D01*
X934583Y470750D01*
X935167Y470333D01*
X935417Y469750D01*
X935500Y469167D01*
X935417Y468583D01*
X935167Y468000D01*
X934667Y467667D01*
X934000Y467500D01*
X933417Y467583D01*
X932833Y467833D01*
X932500Y468167D01*
G01X941100Y467500D02*
Y470833D01*
G01Y470250D02*
X940767Y470583D01*
X940267Y470750D01*
X939683Y470833D01*
X939100Y470667D01*
X938600Y470333D01*
X938267Y469833D01*
X938100Y469167D01*
X938267Y468500D01*
X938600Y468000D01*
X939100Y467667D01*
X939683Y467500D01*
X940267Y467583D01*
X940767Y467833D01*
X941100Y468167D01*
G01X946700Y472500D02*
Y467500D01*
G01Y468250D02*
X946367Y467833D01*
X945867Y467583D01*
X945283Y467500D01*
X944617Y467667D01*
X944117Y468083D01*
X943783Y468583D01*
X943700Y469167D01*
X943783Y469750D01*
X944117Y470250D01*
X944617Y470667D01*
X945283Y470833D01*
X945867Y470750D01*
X946283Y470583D01*
X946700Y470250D01*
G01X956400Y467500D02*
X955900Y467583D01*
X955400Y467917D01*
X955067Y468500D01*
X954900Y469167D01*
X955067Y469833D01*
X955400Y470417D01*
X955900Y470750D01*
X956400Y470833D01*
X956900Y470750D01*
X957400Y470417D01*
X957733Y469833D01*
X957817Y469167D01*
X957733Y468500D01*
X957400Y467917D01*
X956900Y467583D01*
X956400Y467500D01*
G01X960583D02*
Y470833D01*
G01Y470000D02*
X960917Y470417D01*
X961417Y470750D01*
X962083Y470833D01*
X962667Y470750D01*
X963167Y470417D01*
X963417Y469833D01*
Y467500D01*
G01X973200Y472500D02*
Y467500D01*
G01X972033Y470833D02*
X974367D01*
G01X978800Y467500D02*
X978300Y467583D01*
X977800Y467917D01*
X977467Y468500D01*
X977300Y469167D01*
X977467Y469833D01*
X977800Y470417D01*
X978300Y470750D01*
X978800Y470833D01*
X979300Y470750D01*
X979800Y470417D01*
X980133Y469833D01*
X980217Y469167D01*
X980133Y468500D01*
X979800Y467917D01*
X979300Y467583D01*
X978800Y467500D01*
G01X982900Y465833D02*
Y470833D01*
G01Y470083D02*
X983317Y470500D01*
X983733Y470750D01*
X984400Y470833D01*
X984983Y470750D01*
X985567Y470333D01*
X985817Y469750D01*
X985900Y469167D01*
X985817Y468583D01*
X985567Y468000D01*
X985067Y467667D01*
X984400Y467500D01*
X983817Y467583D01*
X983233Y467833D01*
X982900Y468167D01*
G01X829750Y542583D02*
X830167Y542250D01*
X830750Y542000D01*
X831250D01*
X831750Y542167D01*
X832083Y542417D01*
X832250Y542750D01*
X832167Y543250D01*
X831833Y543500D01*
X830333Y544000D01*
X830000Y544583D01*
X830167Y545000D01*
X830500Y545250D01*
X831000Y545333D01*
X831500Y545250D01*
X832000Y545000D01*
G01X836600Y542000D02*
X836100Y542083D01*
X835600Y542417D01*
X835267Y543000D01*
X835100Y543667D01*
X835267Y544333D01*
X835600Y544917D01*
X836100Y545250D01*
X836600Y545333D01*
X837100Y545250D01*
X837600Y544917D01*
X837933Y544333D01*
X838017Y543667D01*
X837933Y543000D01*
X837600Y542417D01*
X837100Y542083D01*
X836600Y542000D01*
G01X842200D02*
Y547000D01*
G01X849300D02*
Y542000D01*
G01Y542750D02*
X848967Y542333D01*
X848467Y542083D01*
X847883Y542000D01*
X847217Y542167D01*
X846717Y542583D01*
X846383Y543083D01*
X846300Y543667D01*
X846383Y544250D01*
X846717Y544750D01*
X847217Y545167D01*
X847883Y545333D01*
X848467Y545250D01*
X848883Y545083D01*
X849300Y544750D01*
G01X852150Y544250D02*
X854817D01*
X854567Y544833D01*
X854150Y545167D01*
X853567Y545333D01*
X852983Y545250D01*
X852483Y545000D01*
X852150Y544417D01*
X851983Y543917D01*
Y543417D01*
X852150Y542917D01*
X852567Y542417D01*
X853067Y542083D01*
X853650Y542000D01*
X854233Y542167D01*
X854817Y542667D01*
G01X857833Y542000D02*
Y545333D01*
G01Y544667D02*
X858250Y545000D01*
X858667Y545250D01*
X859250Y545333D01*
X859667Y545250D01*
X860167Y545000D01*
G01X867700Y542000D02*
Y545333D01*
G01Y544417D02*
X867950Y544833D01*
X868367Y545167D01*
X868950Y545333D01*
X869533Y545167D01*
X869950Y544833D01*
X870200Y544417D01*
Y542000D01*
G01Y544417D02*
X870450Y544833D01*
X870867Y545167D01*
X871450Y545333D01*
X872033Y545167D01*
X872450Y544833D01*
X872700Y544333D01*
Y542000D01*
G01X877300D02*
Y545333D01*
G01Y544750D02*
X876967Y545083D01*
X876467Y545250D01*
X875883Y545333D01*
X875300Y545167D01*
X874800Y544833D01*
X874467Y544333D01*
X874300Y543667D01*
X874467Y543000D01*
X874800Y542500D01*
X875300Y542167D01*
X875883Y542000D01*
X876467Y542083D01*
X876967Y542333D01*
X877300Y542667D01*
G01X880150Y542583D02*
X880567Y542250D01*
X881150Y542000D01*
X881650D01*
X882150Y542167D01*
X882483Y542417D01*
X882650Y542750D01*
X882567Y543250D01*
X882233Y543500D01*
X880733Y544000D01*
X880400Y544583D01*
X880567Y545000D01*
X880900Y545250D01*
X881400Y545333D01*
X881900Y545250D01*
X882400Y545000D01*
G01X885583Y542000D02*
Y547000D01*
G01X888250Y545333D02*
X885583Y543417D01*
G01X886667Y544167D02*
X888417Y542000D01*
G01X896700Y540333D02*
Y545333D01*
G01Y544583D02*
X897117Y545000D01*
X897533Y545250D01*
X898200Y545333D01*
X898783Y545250D01*
X899367Y544833D01*
X899617Y544250D01*
X899700Y543667D01*
X899617Y543083D01*
X899367Y542500D01*
X898867Y542167D01*
X898200Y542000D01*
X897617Y542083D01*
X897033Y542333D01*
X896700Y542667D01*
G01X905300Y542000D02*
Y545333D01*
G01Y544750D02*
X904967Y545083D01*
X904467Y545250D01*
X903883Y545333D01*
X903300Y545167D01*
X902800Y544833D01*
X902467Y544333D01*
X902300Y543667D01*
X902467Y543000D01*
X902800Y542500D01*
X903300Y542167D01*
X903883Y542000D01*
X904467Y542083D01*
X904967Y542333D01*
X905300Y542667D01*
G01X910900Y547000D02*
Y542000D01*
G01Y542750D02*
X910567Y542333D01*
X910067Y542083D01*
X909483Y542000D01*
X908817Y542167D01*
X908317Y542583D01*
X907983Y543083D01*
X907900Y543667D01*
X907983Y544250D01*
X908317Y544750D01*
X908817Y545167D01*
X909483Y545333D01*
X910067Y545250D01*
X910483Y545083D01*
X910900Y544750D01*
G01X829917Y563333D02*
X830917Y560000D01*
X832000Y563333D01*
X833083Y560000D01*
X834083Y563333D01*
G01X836183Y560000D02*
Y565000D01*
G01Y562583D02*
X836600Y563000D01*
X837017Y563250D01*
X837683Y563333D01*
X838183Y563250D01*
X838767Y562917D01*
X839017Y562417D01*
Y560000D01*
G01X843200Y563333D02*
Y560000D01*
G01Y564667D02*
X843033Y564750D01*
Y564917D01*
X843200Y565000D01*
X843367Y564917D01*
Y564750D01*
X843200Y564667D01*
G01X850133Y562917D02*
X849550Y563250D01*
X849050Y563333D01*
X848383Y563167D01*
X847883Y562833D01*
X847550Y562250D01*
X847467Y561667D01*
X847550Y561083D01*
X847883Y560583D01*
X848383Y560167D01*
X849050Y560000D01*
X849633Y560167D01*
X850133Y560500D01*
G01X852983Y560000D02*
Y565000D01*
G01Y562583D02*
X853400Y563000D01*
X853817Y563250D01*
X854483Y563333D01*
X854983Y563250D01*
X855567Y562917D01*
X855817Y562417D01*
Y560000D01*
G01X864350Y560583D02*
X864767Y560250D01*
X865350Y560000D01*
X865850D01*
X866350Y560167D01*
X866683Y560417D01*
X866850Y560750D01*
X866767Y561250D01*
X866433Y561500D01*
X864933Y562000D01*
X864600Y562583D01*
X864767Y563000D01*
X865100Y563250D01*
X865600Y563333D01*
X866100Y563250D01*
X866600Y563000D01*
G01X871200Y563333D02*
Y560000D01*
G01Y564667D02*
X871033Y564750D01*
Y564917D01*
X871200Y565000D01*
X871367Y564917D01*
Y564750D01*
X871200Y564667D01*
G01X875550Y563333D02*
X878050D01*
X875550Y560000D01*
X878050D01*
G01X881150Y562250D02*
X883817D01*
X883567Y562833D01*
X883150Y563167D01*
X882567Y563333D01*
X881983Y563250D01*
X881483Y563000D01*
X881150Y562417D01*
X880983Y561917D01*
Y561417D01*
X881150Y560917D01*
X881567Y560417D01*
X882067Y560083D01*
X882650Y560000D01*
X883233Y560167D01*
X883817Y560667D01*
G01X893600Y563333D02*
Y560000D01*
G01Y564667D02*
X893433Y564750D01*
Y564917D01*
X893600Y565000D01*
X893767Y564917D01*
Y564750D01*
X893600Y564667D01*
G01X897950Y560583D02*
X898367Y560250D01*
X898950Y560000D01*
X899450D01*
X899950Y560167D01*
X900283Y560417D01*
X900450Y560750D01*
X900367Y561250D01*
X900033Y561500D01*
X898533Y562000D01*
X898200Y562583D01*
X898367Y563000D01*
X898700Y563250D01*
X899200Y563333D01*
X899700Y563250D01*
X900200Y563000D01*
G01X908900Y560000D02*
Y565000D01*
G01Y562500D02*
X909317Y563000D01*
X909817Y563250D01*
X910317Y563333D01*
X911067Y563167D01*
X911567Y562833D01*
X911900Y562250D01*
Y561583D01*
X911733Y560917D01*
X911400Y560417D01*
X910817Y560083D01*
X910317Y560000D01*
X909817Y560083D01*
X909317Y560333D01*
X908900Y560750D01*
G01X916000Y563333D02*
Y560000D01*
G01Y564667D02*
X915833Y564750D01*
Y564917D01*
X916000Y565000D01*
X916167Y564917D01*
Y564750D01*
X916000Y564667D01*
G01X920433Y558750D02*
X921017Y558417D01*
X921683Y558333D01*
X922267Y558417D01*
X922767Y558833D01*
X923100Y559417D01*
Y563333D01*
G01Y562667D02*
X922767Y563000D01*
X922267Y563250D01*
X921683Y563333D01*
X921017Y563167D01*
X920600Y562833D01*
X920267Y562250D01*
X920100Y561667D01*
X920183Y561167D01*
X920517Y560583D01*
X921017Y560167D01*
X921683Y560000D01*
X922183Y560083D01*
X922767Y560417D01*
X923100Y560750D01*
G01X926033Y558750D02*
X926617Y558417D01*
X927283Y558333D01*
X927867Y558417D01*
X928367Y558833D01*
X928700Y559417D01*
Y563333D01*
G01Y562667D02*
X928367Y563000D01*
X927867Y563250D01*
X927283Y563333D01*
X926617Y563167D01*
X926200Y562833D01*
X925867Y562250D01*
X925700Y561667D01*
X925783Y561167D01*
X926117Y560583D01*
X926617Y560167D01*
X927283Y560000D01*
X927783Y560083D01*
X928367Y560417D01*
X928700Y560750D01*
G01X931550Y562250D02*
X934217D01*
X933967Y562833D01*
X933550Y563167D01*
X932967Y563333D01*
X932383Y563250D01*
X931883Y563000D01*
X931550Y562417D01*
X931383Y561917D01*
Y561417D01*
X931550Y560917D01*
X931967Y560417D01*
X932467Y560083D01*
X933050Y560000D01*
X933633Y560167D01*
X934217Y560667D01*
G01X937233Y560000D02*
Y563333D01*
G01Y562667D02*
X937650Y563000D01*
X938067Y563250D01*
X938650Y563333D01*
X939067Y563250D01*
X939567Y563000D01*
G01X949600Y565000D02*
Y560000D01*
G01X948433Y563333D02*
X950767D01*
G01X953783Y560000D02*
Y565000D01*
G01Y562583D02*
X954200Y563000D01*
X954617Y563250D01*
X955283Y563333D01*
X955783Y563250D01*
X956367Y562917D01*
X956617Y562417D01*
Y560000D01*
G01X962300D02*
Y563333D01*
G01Y562750D02*
X961967Y563083D01*
X961467Y563250D01*
X960883Y563333D01*
X960300Y563167D01*
X959800Y562833D01*
X959467Y562333D01*
X959300Y561667D01*
X959467Y561000D01*
X959800Y560500D01*
X960300Y560167D01*
X960883Y560000D01*
X961467Y560083D01*
X961967Y560333D01*
X962300Y560667D01*
G01X964983Y560000D02*
Y563333D01*
G01Y562500D02*
X965317Y562917D01*
X965817Y563250D01*
X966483Y563333D01*
X967067Y563250D01*
X967567Y562917D01*
X967817Y562333D01*
Y560000D01*
G01X979100D02*
Y563333D01*
G01Y562750D02*
X978767Y563083D01*
X978267Y563250D01*
X977683Y563333D01*
X977100Y563167D01*
X976600Y562833D01*
X976267Y562333D01*
X976100Y561667D01*
X976267Y561000D01*
X976600Y560500D01*
X977100Y560167D01*
X977683Y560000D01*
X978267Y560083D01*
X978767Y560333D01*
X979100Y560667D01*
G01X981783Y560000D02*
Y563333D01*
G01Y562500D02*
X982117Y562917D01*
X982617Y563250D01*
X983283Y563333D01*
X983867Y563250D01*
X984367Y562917D01*
X984617Y562333D01*
Y560000D01*
G01X987383D02*
Y563333D01*
G01Y562500D02*
X987717Y562917D01*
X988217Y563250D01*
X988883Y563333D01*
X989467Y563250D01*
X989967Y562917D01*
X990217Y562333D01*
Y560000D01*
G01X992983Y563333D02*
Y561000D01*
X993317Y560417D01*
X993817Y560083D01*
X994400Y560000D01*
X994983Y560083D01*
X995483Y560417D01*
X995817Y561000D01*
G01Y560000D02*
Y563333D01*
G01X1001500Y560000D02*
Y563333D01*
G01Y562750D02*
X1001167Y563083D01*
X1000667Y563250D01*
X1000083Y563333D01*
X999500Y563167D01*
X999000Y562833D01*
X998667Y562333D01*
X998500Y561667D01*
X998667Y561000D01*
X999000Y560500D01*
X999500Y560167D01*
X1000083Y560000D01*
X1000667Y560083D01*
X1001167Y560333D01*
X1001500Y560667D01*
G01X1005600Y560000D02*
Y565000D01*
G01X822000Y569000D02*
Y574000D01*
X821000Y573000D01*
G01Y569000D02*
X823000D01*
G01X827600Y568833D02*
X827433Y568917D01*
Y569083D01*
X827600Y569167D01*
X827767Y569083D01*
Y568917D01*
X827600Y568833D01*
G01X833200Y569000D02*
X832533Y569083D01*
X831950Y569417D01*
X831450Y569917D01*
X831117Y570500D01*
X830950Y571167D01*
Y571833D01*
X831117Y572500D01*
X831450Y573083D01*
X831950Y573583D01*
X832533Y573917D01*
X833200Y574000D01*
X833867Y573917D01*
X834450Y573583D01*
X834950Y573083D01*
X835283Y572500D01*
X835450Y571833D01*
Y571167D01*
X835283Y570500D01*
X834950Y569917D01*
X834450Y569417D01*
X833867Y569083D01*
X833200Y569000D01*
G01X837383D02*
Y572333D01*
G01Y571500D02*
X837717Y571917D01*
X838217Y572250D01*
X838883Y572333D01*
X839467Y572250D01*
X839967Y571917D01*
X840217Y571333D01*
Y569000D01*
G01X843150Y571250D02*
X845817D01*
X845567Y571833D01*
X845150Y572167D01*
X844567Y572333D01*
X843983Y572250D01*
X843483Y572000D01*
X843150Y571417D01*
X842983Y570917D01*
Y570417D01*
X843150Y569917D01*
X843567Y569417D01*
X844067Y569083D01*
X844650Y569000D01*
X845233Y569167D01*
X845817Y569667D01*
G01X854350Y569583D02*
X854767Y569250D01*
X855350Y569000D01*
X855850D01*
X856350Y569167D01*
X856683Y569417D01*
X856850Y569750D01*
X856767Y570250D01*
X856433Y570500D01*
X854933Y571000D01*
X854600Y571583D01*
X854767Y572000D01*
X855100Y572250D01*
X855600Y572333D01*
X856100Y572250D01*
X856600Y572000D01*
G01X861200Y572333D02*
Y569000D01*
G01Y573667D02*
X861033Y573750D01*
Y573917D01*
X861200Y574000D01*
X861367Y573917D01*
Y573750D01*
X861200Y573667D01*
G01X868300Y574000D02*
Y569000D01*
G01Y569750D02*
X867967Y569333D01*
X867467Y569083D01*
X866883Y569000D01*
X866217Y569167D01*
X865717Y569583D01*
X865383Y570083D01*
X865300Y570667D01*
X865383Y571250D01*
X865717Y571750D01*
X866217Y572167D01*
X866883Y572333D01*
X867467Y572250D01*
X867883Y572083D01*
X868300Y571750D01*
G01X871150Y571250D02*
X873817D01*
X873567Y571833D01*
X873150Y572167D01*
X872567Y572333D01*
X871983Y572250D01*
X871483Y572000D01*
X871150Y571417D01*
X870983Y570917D01*
Y570417D01*
X871150Y569917D01*
X871567Y569417D01*
X872067Y569083D01*
X872650Y569000D01*
X873233Y569167D01*
X873817Y569667D01*
G01X881517Y572333D02*
X882517Y569000D01*
X883600Y572333D01*
X884683Y569000D01*
X885683Y572333D01*
G01X889200D02*
Y569000D01*
G01Y573667D02*
X889033Y573750D01*
Y573917D01*
X889200Y574000D01*
X889367Y573917D01*
Y573750D01*
X889200Y573667D01*
G01X894800Y574000D02*
Y569000D01*
G01X893633Y572333D02*
X895967D01*
G01X898983Y569000D02*
Y574000D01*
G01Y571583D02*
X899400Y572000D01*
X899817Y572250D01*
X900483Y572333D01*
X900983Y572250D01*
X901567Y571917D01*
X901817Y571417D01*
Y569000D01*
G01X910350Y569583D02*
X910767Y569250D01*
X911350Y569000D01*
X911850D01*
X912350Y569167D01*
X912683Y569417D01*
X912850Y569750D01*
X912767Y570250D01*
X912433Y570500D01*
X910933Y571000D01*
X910600Y571583D01*
X910767Y572000D01*
X911100Y572250D01*
X911600Y572333D01*
X912100Y572250D01*
X912600Y572000D01*
G01X917200Y569000D02*
X916700Y569083D01*
X916200Y569417D01*
X915867Y570000D01*
X915700Y570667D01*
X915867Y571333D01*
X916200Y571917D01*
X916700Y572250D01*
X917200Y572333D01*
X917700Y572250D01*
X918200Y571917D01*
X918533Y571333D01*
X918617Y570667D01*
X918533Y570000D01*
X918200Y569417D01*
X917700Y569083D01*
X917200Y569000D01*
G01X922800D02*
Y574000D01*
G01X929900D02*
Y569000D01*
G01Y569750D02*
X929567Y569333D01*
X929067Y569083D01*
X928483Y569000D01*
X927817Y569167D01*
X927317Y569583D01*
X926983Y570083D01*
X926900Y570667D01*
X926983Y571250D01*
X927317Y571750D01*
X927817Y572167D01*
X928483Y572333D01*
X929067Y572250D01*
X929483Y572083D01*
X929900Y571750D01*
G01X932750Y571250D02*
X935417D01*
X935167Y571833D01*
X934750Y572167D01*
X934167Y572333D01*
X933583Y572250D01*
X933083Y572000D01*
X932750Y571417D01*
X932583Y570917D01*
Y570417D01*
X932750Y569917D01*
X933167Y569417D01*
X933667Y569083D01*
X934250Y569000D01*
X934833Y569167D01*
X935417Y569667D01*
G01X938433Y569000D02*
Y572333D01*
G01Y571667D02*
X938850Y572000D01*
X939267Y572250D01*
X939850Y572333D01*
X940267Y572250D01*
X940767Y572000D01*
G01X948300Y569000D02*
Y572333D01*
G01Y571417D02*
X948550Y571833D01*
X948967Y572167D01*
X949550Y572333D01*
X950133Y572167D01*
X950550Y571833D01*
X950800Y571417D01*
Y569000D01*
G01Y571417D02*
X951050Y571833D01*
X951467Y572167D01*
X952050Y572333D01*
X952633Y572167D01*
X953050Y571833D01*
X953300Y571333D01*
Y569000D01*
G01X957900D02*
Y572333D01*
G01Y571750D02*
X957567Y572083D01*
X957067Y572250D01*
X956483Y572333D01*
X955900Y572167D01*
X955400Y571833D01*
X955067Y571333D01*
X954900Y570667D01*
X955067Y570000D01*
X955400Y569500D01*
X955900Y569167D01*
X956483Y569000D01*
X957067Y569083D01*
X957567Y569333D01*
X957900Y569667D01*
G01X960750Y569583D02*
X961167Y569250D01*
X961750Y569000D01*
X962250D01*
X962750Y569167D01*
X963083Y569417D01*
X963250Y569750D01*
X963167Y570250D01*
X962833Y570500D01*
X961333Y571000D01*
X961000Y571583D01*
X961167Y572000D01*
X961500Y572250D01*
X962000Y572333D01*
X962500Y572250D01*
X963000Y572000D01*
G01X966183Y569000D02*
Y574000D01*
G01X968850Y572333D02*
X966183Y570417D01*
G01X967267Y571167D02*
X969017Y569000D01*
G01X977300Y567333D02*
Y572333D01*
G01Y571583D02*
X977717Y572000D01*
X978133Y572250D01*
X978800Y572333D01*
X979383Y572250D01*
X979967Y571833D01*
X980217Y571250D01*
X980300Y570667D01*
X980217Y570083D01*
X979967Y569500D01*
X979467Y569167D01*
X978800Y569000D01*
X978217Y569083D01*
X977633Y569333D01*
X977300Y569667D01*
G01X985900Y569000D02*
Y572333D01*
G01Y571750D02*
X985567Y572083D01*
X985067Y572250D01*
X984483Y572333D01*
X983900Y572167D01*
X983400Y571833D01*
X983067Y571333D01*
X982900Y570667D01*
X983067Y570000D01*
X983400Y569500D01*
X983900Y569167D01*
X984483Y569000D01*
X985067Y569083D01*
X985567Y569333D01*
X985900Y569667D01*
G01X991500Y574000D02*
Y569000D01*
G01Y569750D02*
X991167Y569333D01*
X990667Y569083D01*
X990083Y569000D01*
X989417Y569167D01*
X988917Y569583D01*
X988583Y570083D01*
X988500Y570667D01*
X988583Y571250D01*
X988917Y571750D01*
X989417Y572167D01*
X990083Y572333D01*
X990667Y572250D01*
X991083Y572083D01*
X991500Y571750D01*
G01X831333Y551000D02*
Y554333D01*
G01Y553667D02*
X831750Y554000D01*
X832167Y554250D01*
X832750Y554333D01*
X833167Y554250D01*
X833667Y554000D01*
G01X838100Y554333D02*
Y551000D01*
G01Y555667D02*
X837933Y555750D01*
Y555917D01*
X838100Y556000D01*
X838267Y555917D01*
Y555750D01*
X838100Y555667D01*
G01X842283Y551000D02*
Y554333D01*
G01Y553500D02*
X842617Y553917D01*
X843117Y554250D01*
X843783Y554333D01*
X844367Y554250D01*
X844867Y553917D01*
X845117Y553333D01*
Y551000D01*
G01X848133Y549750D02*
X848717Y549417D01*
X849383Y549333D01*
X849967Y549417D01*
X850467Y549833D01*
X850800Y550417D01*
Y554333D01*
G01Y553667D02*
X850467Y554000D01*
X849967Y554250D01*
X849383Y554333D01*
X848717Y554167D01*
X848300Y553833D01*
X847967Y553250D01*
X847800Y552667D01*
X847883Y552167D01*
X848217Y551583D01*
X848717Y551167D01*
X849383Y551000D01*
X849883Y551083D01*
X850467Y551417D01*
X850800Y551750D01*
G01X859250Y551583D02*
X859667Y551250D01*
X860250Y551000D01*
X860750D01*
X861250Y551167D01*
X861583Y551417D01*
X861750Y551750D01*
X861667Y552250D01*
X861333Y552500D01*
X859833Y553000D01*
X859500Y553583D01*
X859667Y554000D01*
X860000Y554250D01*
X860500Y554333D01*
X861000Y554250D01*
X861500Y554000D01*
G01X866100Y554333D02*
Y551000D01*
G01Y555667D02*
X865933Y555750D01*
Y555917D01*
X866100Y556000D01*
X866267Y555917D01*
Y555750D01*
X866100Y555667D01*
G01X870450Y554333D02*
X872950D01*
X870450Y551000D01*
X872950D01*
G01X876050Y553250D02*
X878717D01*
X878467Y553833D01*
X878050Y554167D01*
X877467Y554333D01*
X876883Y554250D01*
X876383Y554000D01*
X876050Y553417D01*
X875883Y552917D01*
Y552417D01*
X876050Y551917D01*
X876467Y551417D01*
X876967Y551083D01*
X877550Y551000D01*
X878133Y551167D01*
X878717Y551667D01*
G01X888333Y550083D02*
X888667Y551167D01*
G01X809000Y686500D02*
Y691500D01*
G01Y689000D02*
X809417Y689500D01*
X809917Y689750D01*
X810417Y689833D01*
X811167Y689667D01*
X811667Y689333D01*
X812000Y688750D01*
Y688083D01*
X811833Y687417D01*
X811500Y686917D01*
X810917Y686583D01*
X810417Y686500D01*
X809917Y686583D01*
X809417Y686833D01*
X809000Y687250D01*
G01X816100Y686500D02*
X815600Y686583D01*
X815100Y686917D01*
X814767Y687500D01*
X814600Y688167D01*
X814767Y688833D01*
X815100Y689417D01*
X815600Y689750D01*
X816100Y689833D01*
X816600Y689750D01*
X817100Y689417D01*
X817433Y688833D01*
X817517Y688167D01*
X817433Y687500D01*
X817100Y686917D01*
X816600Y686583D01*
X816100Y686500D01*
G01X823200D02*
Y689833D01*
G01Y689250D02*
X822867Y689583D01*
X822367Y689750D01*
X821783Y689833D01*
X821200Y689667D01*
X820700Y689333D01*
X820367Y688833D01*
X820200Y688167D01*
X820367Y687500D01*
X820700Y687000D01*
X821200Y686667D01*
X821783Y686500D01*
X822367Y686583D01*
X822867Y686833D01*
X823200Y687167D01*
G01X826133Y686500D02*
Y689833D01*
G01Y689167D02*
X826550Y689500D01*
X826967Y689750D01*
X827550Y689833D01*
X827967Y689750D01*
X828467Y689500D01*
G01X834400Y691500D02*
Y686500D01*
G01Y687250D02*
X834067Y686833D01*
X833567Y686583D01*
X832983Y686500D01*
X832317Y686667D01*
X831817Y687083D01*
X831483Y687583D01*
X831400Y688167D01*
X831483Y688750D01*
X831817Y689250D01*
X832317Y689667D01*
X832983Y689833D01*
X833567Y689750D01*
X833983Y689583D01*
X834400Y689250D01*
G01X868250Y152000D02*
Y157000D01*
G01X871750D02*
Y152000D01*
G01Y154500D02*
X868250D01*
G01X875600Y152000D02*
X874933Y152083D01*
X874350Y152417D01*
X873850Y152917D01*
X873517Y153500D01*
X873350Y154167D01*
Y154833D01*
X873517Y155500D01*
X873850Y156083D01*
X874350Y156583D01*
X874933Y156917D01*
X875600Y157000D01*
X876267Y156917D01*
X876850Y156583D01*
X877350Y156083D01*
X877683Y155500D01*
X877850Y154833D01*
Y154167D01*
X877683Y153500D01*
X877350Y152917D01*
X876850Y152417D01*
X876267Y152083D01*
X875600Y152000D01*
G01X879533Y157000D02*
Y152000D01*
X882867D01*
G01X888467D02*
X885133D01*
Y157000D01*
X888467D01*
G01X887133Y154583D02*
X885133D01*
G01X912300Y152000D02*
Y155333D01*
G01Y154417D02*
X912550Y154833D01*
X912967Y155167D01*
X913550Y155333D01*
X914133Y155167D01*
X914550Y154833D01*
X914800Y154417D01*
Y152000D01*
G01Y154417D02*
X915050Y154833D01*
X915467Y155167D01*
X916050Y155333D01*
X916633Y155167D01*
X917050Y154833D01*
X917300Y154333D01*
Y152000D01*
G01X920400Y155333D02*
Y152000D01*
G01Y156667D02*
X920233Y156750D01*
Y156917D01*
X920400Y157000D01*
X920567Y156917D01*
Y156750D01*
X920400Y156667D01*
G01X926000Y152000D02*
Y157000D01*
G01X930350Y152583D02*
X930767Y152250D01*
X931350Y152000D01*
X931850D01*
X932350Y152167D01*
X932683Y152417D01*
X932850Y152750D01*
X932767Y153250D01*
X932433Y153500D01*
X930933Y154000D01*
X930600Y154583D01*
X930767Y155000D01*
X931100Y155250D01*
X931600Y155333D01*
X932100Y155250D01*
X932600Y155000D01*
G01X936783Y150333D02*
X935950Y151167D01*
X935533Y152000D01*
Y155333D01*
X935950Y156167D01*
X936783Y157000D01*
G01X941133Y152000D02*
Y157000D01*
X943133D01*
X943800Y156750D01*
X944300Y156167D01*
X944467Y155500D01*
X944300Y154833D01*
X943883Y154333D01*
X943133Y154083D01*
X941133D01*
G01X948400Y157000D02*
Y152000D01*
G01X946483Y157000D02*
X950317D01*
G01X952250Y152000D02*
Y157000D01*
G01X955750D02*
Y152000D01*
G01Y154500D02*
X952250D01*
G01X960017Y150333D02*
X960850Y151167D01*
X961267Y152000D01*
Y155333D01*
X960850Y156167D01*
X960017Y157000D01*
G01X868167Y308167D02*
X868500Y308417D01*
X868750Y308833D01*
X868917Y309417D01*
X868750Y309917D01*
X868417Y310250D01*
X867833Y310500D01*
X865583D01*
Y305500D01*
X868333D01*
X868917Y305833D01*
X869250Y306333D01*
X869417Y306917D01*
X869250Y307500D01*
X868750Y308000D01*
X868167Y308167D01*
X865583D01*
G01X871017Y305500D02*
X873100Y310500D01*
X875183Y305500D01*
G01X874433Y307250D02*
X871767D01*
G01X880533Y310083D02*
X880033Y310333D01*
X879450Y310500D01*
X878783D01*
X878033Y310250D01*
X877450Y309833D01*
X877033Y309333D01*
X876700Y308500D01*
X876617Y307750D01*
X876783Y307000D01*
X877033Y306500D01*
X877533Y306000D01*
X878117Y305667D01*
X878700Y305500D01*
X879283D01*
X879867Y305667D01*
X880367Y305917D01*
X880783Y306250D01*
G01X882467Y305500D02*
Y310500D01*
G01X885633D02*
X882467Y307417D01*
G01X886133Y305500D02*
X883883Y308833D01*
G01X893667Y305500D02*
Y310500D01*
X895333D01*
X896000Y310250D01*
X896500Y309917D01*
X896917Y309417D01*
X897250Y308833D01*
X897333Y308000D01*
X897250Y307167D01*
X896917Y306583D01*
X896500Y306083D01*
X896000Y305750D01*
X895333Y305500D01*
X893667D01*
G01X899433D02*
Y310500D01*
X901517D01*
X902183Y310250D01*
X902600Y309917D01*
X902767Y309250D01*
X902600Y308583D01*
X902100Y308167D01*
X901517Y307917D01*
X899433D01*
G01X901517D02*
X902767Y305500D01*
G01X905700Y310500D02*
X907700D01*
G01X906700D02*
Y305500D01*
G01X905700D02*
X907700D01*
G01X910633Y310500D02*
Y305500D01*
X913967D01*
G01X916233Y310500D02*
Y305500D01*
X919567D01*
G01X943400D02*
Y308833D01*
G01Y307917D02*
X943650Y308333D01*
X944067Y308667D01*
X944650Y308833D01*
X945233Y308667D01*
X945650Y308333D01*
X945900Y307917D01*
Y305500D01*
G01Y307917D02*
X946150Y308333D01*
X946567Y308667D01*
X947150Y308833D01*
X947733Y308667D01*
X948150Y308333D01*
X948400Y307833D01*
Y305500D01*
G01X951500Y308833D02*
Y305500D01*
G01Y310167D02*
X951333Y310250D01*
Y310417D01*
X951500Y310500D01*
X951667Y310417D01*
Y310250D01*
X951500Y310167D01*
G01X957100Y305500D02*
Y310500D01*
G01X961450Y306083D02*
X961867Y305750D01*
X962450Y305500D01*
X962950D01*
X963450Y305667D01*
X963783Y305917D01*
X963950Y306250D01*
X963867Y306750D01*
X963533Y307000D01*
X962033Y307500D01*
X961700Y308083D01*
X961867Y308500D01*
X962200Y308750D01*
X962700Y308833D01*
X963200Y308750D01*
X963700Y308500D01*
G01X967883Y303833D02*
X967050Y304667D01*
X966633Y305500D01*
Y308833D01*
X967050Y309667D01*
X967883Y310500D01*
G01X971983Y305500D02*
Y310500D01*
X975817Y305500D01*
Y310500D01*
G01X977833Y305500D02*
Y310500D01*
X979833D01*
X980500Y310250D01*
X981000Y309667D01*
X981167Y309000D01*
X981000Y308333D01*
X980583Y307833D01*
X979833Y307583D01*
X977833D01*
G01X985100Y310500D02*
Y305500D01*
G01X983183Y310500D02*
X987017D01*
G01X988950Y305500D02*
Y310500D01*
G01X992450D02*
Y305500D01*
G01Y308000D02*
X988950D01*
G01X996717Y303833D02*
X997550Y304667D01*
X997967Y305500D01*
Y308833D01*
X997550Y309667D01*
X996717Y310500D01*
G01X843083Y734500D02*
Y739500D01*
G01Y737083D02*
X843500Y737500D01*
X843917Y737750D01*
X844583Y737833D01*
X845083Y737750D01*
X845667Y737417D01*
X845917Y736917D01*
Y734500D01*
G01X851600D02*
Y737833D01*
G01Y737250D02*
X851267Y737583D01*
X850767Y737750D01*
X850183Y737833D01*
X849600Y737667D01*
X849100Y737333D01*
X848767Y736833D01*
X848600Y736167D01*
X848767Y735500D01*
X849100Y735000D01*
X849600Y734667D01*
X850183Y734500D01*
X850767Y734583D01*
X851267Y734833D01*
X851600Y735167D01*
G01X855700Y734500D02*
Y739500D01*
G01X860800Y734500D02*
Y738750D01*
X860967Y739167D01*
X861300Y739417D01*
X861800Y739500D01*
X862300Y739333D01*
X862550Y738917D01*
G01X861550Y737500D02*
X859883D01*
G01X871000Y732833D02*
Y737833D01*
G01Y737083D02*
X871417Y737500D01*
X871833Y737750D01*
X872500Y737833D01*
X873083Y737750D01*
X873667Y737333D01*
X873917Y736750D01*
X874000Y736167D01*
X873917Y735583D01*
X873667Y735000D01*
X873167Y734667D01*
X872500Y734500D01*
X871917Y734583D01*
X871333Y734833D01*
X871000Y735167D01*
G01X878100Y734500D02*
Y739500D01*
G01X882283Y737833D02*
Y735500D01*
X882617Y734917D01*
X883117Y734583D01*
X883700Y734500D01*
X884283Y734583D01*
X884783Y734917D01*
X885117Y735500D01*
G01Y734500D02*
Y737833D01*
G01X888133Y733250D02*
X888717Y732917D01*
X889383Y732833D01*
X889967Y732917D01*
X890467Y733333D01*
X890800Y733917D01*
Y737833D01*
G01Y737167D02*
X890467Y737500D01*
X889967Y737750D01*
X889383Y737833D01*
X888717Y737667D01*
X888300Y737333D01*
X887967Y736750D01*
X887800Y736167D01*
X887883Y735667D01*
X888217Y735083D01*
X888717Y734667D01*
X889383Y734500D01*
X889883Y734583D01*
X890467Y734917D01*
X890800Y735250D01*
G01X893733Y733250D02*
X894317Y732917D01*
X894983Y732833D01*
X895567Y732917D01*
X896067Y733333D01*
X896400Y733917D01*
Y737833D01*
G01Y737167D02*
X896067Y737500D01*
X895567Y737750D01*
X894983Y737833D01*
X894317Y737667D01*
X893900Y737333D01*
X893567Y736750D01*
X893400Y736167D01*
X893483Y735667D01*
X893817Y735083D01*
X894317Y734667D01*
X894983Y734500D01*
X895483Y734583D01*
X896067Y734917D01*
X896400Y735250D01*
G01X900500Y737833D02*
Y734500D01*
G01Y739167D02*
X900333Y739250D01*
Y739417D01*
X900500Y739500D01*
X900667Y739417D01*
Y739250D01*
X900500Y739167D01*
G01X904683Y734500D02*
Y737833D01*
G01Y737000D02*
X905017Y737417D01*
X905517Y737750D01*
X906183Y737833D01*
X906767Y737750D01*
X907267Y737417D01*
X907517Y736833D01*
Y734500D01*
G01X910533Y733250D02*
X911117Y732917D01*
X911783Y732833D01*
X912367Y732917D01*
X912867Y733333D01*
X913200Y733917D01*
Y737833D01*
G01Y737167D02*
X912867Y737500D01*
X912367Y737750D01*
X911783Y737833D01*
X911117Y737667D01*
X910700Y737333D01*
X910367Y736750D01*
X910200Y736167D01*
X910283Y735667D01*
X910617Y735083D01*
X911117Y734667D01*
X911783Y734500D01*
X912283Y734583D01*
X912867Y734917D01*
X913200Y735250D01*
G01X909000Y67500D02*
Y72500D01*
X905917Y68917D01*
X910083D01*
G01X911767Y68250D02*
X912267Y67833D01*
X912850Y67583D01*
X913600Y67500D01*
X914350Y67667D01*
X914933Y68000D01*
X915350Y68583D01*
X915433Y69250D01*
X915267Y69917D01*
X914850Y70333D01*
X914267Y70667D01*
X913683Y70750D01*
X913100Y70667D01*
X912350Y70333D01*
X912600Y72500D01*
X914850D01*
G01X900833Y214500D02*
Y209500D01*
X904167D01*
G01X906683D02*
Y212833D01*
G01Y212000D02*
X907017Y212417D01*
X907517Y212750D01*
X908183Y212833D01*
X908767Y212750D01*
X909267Y212417D01*
X909517Y211833D01*
Y209500D01*
G01X902833Y255500D02*
Y250500D01*
X906167D01*
G01X908850Y253833D02*
X911350Y250500D01*
G01Y253833D02*
X908850Y250500D01*
G01X889267Y349073D02*
X892933Y352740D01*
G01X891100Y353407D02*
Y348407D01*
G01X892933Y349073D02*
X889267Y352740D01*
G01X888600Y350907D02*
X893600D01*
G01X896283Y347573D02*
X895450Y348407D01*
X895033Y349240D01*
Y352573D01*
X895450Y353407D01*
X896283Y354240D01*
G01X900467Y349990D02*
X900967Y349573D01*
X901550Y349323D01*
X902300Y349240D01*
X903050Y349407D01*
X903633Y349740D01*
X904050Y350323D01*
X904133Y350990D01*
X903967Y351657D01*
X903550Y352073D01*
X902967Y352407D01*
X902383Y352490D01*
X901800Y352407D01*
X901050Y352073D01*
X901300Y354240D01*
X903550D01*
G01X907900Y349073D02*
X907733Y349157D01*
Y349323D01*
X907900Y349407D01*
X908067Y349323D01*
Y349157D01*
X907900Y349073D01*
G01X913500Y349240D02*
Y354240D01*
X912500Y353240D01*
G01Y349240D02*
X914500D01*
G01X919517Y347573D02*
X920350Y348407D01*
X920767Y349240D01*
Y352573D01*
X920350Y353407D01*
X919517Y354240D01*
G01X894000Y556000D02*
Y551000D01*
G01X892833Y554333D02*
X895167D01*
G01X898183Y551000D02*
Y556000D01*
G01Y553583D02*
X898600Y554000D01*
X899017Y554250D01*
X899683Y554333D01*
X900183Y554250D01*
X900767Y553917D01*
X901017Y553417D01*
Y551000D01*
G01X903950Y553250D02*
X906617D01*
X906367Y553833D01*
X905950Y554167D01*
X905367Y554333D01*
X904783Y554250D01*
X904283Y554000D01*
X903950Y553417D01*
X903783Y552917D01*
Y552417D01*
X903950Y551917D01*
X904367Y551417D01*
X904867Y551083D01*
X905450Y551000D01*
X906033Y551167D01*
X906617Y551667D01*
G01X916400Y551000D02*
X915900Y551083D01*
X915400Y551417D01*
X915067Y552000D01*
X914900Y552667D01*
X915067Y553333D01*
X915400Y553917D01*
X915900Y554250D01*
X916400Y554333D01*
X916900Y554250D01*
X917400Y553917D01*
X917733Y553333D01*
X917817Y552667D01*
X917733Y552000D01*
X917400Y551417D01*
X916900Y551083D01*
X916400Y551000D01*
G01X922000Y556000D02*
Y551000D01*
G01X920833Y554333D02*
X923167D01*
G01X926183Y551000D02*
Y556000D01*
G01Y553583D02*
X926600Y554000D01*
X927017Y554250D01*
X927683Y554333D01*
X928183Y554250D01*
X928767Y553917D01*
X929017Y553417D01*
Y551000D01*
G01X931950Y553250D02*
X934617D01*
X934367Y553833D01*
X933950Y554167D01*
X933367Y554333D01*
X932783Y554250D01*
X932283Y554000D01*
X931950Y553417D01*
X931783Y552917D01*
Y552417D01*
X931950Y551917D01*
X932367Y551417D01*
X932867Y551083D01*
X933450Y551000D01*
X934033Y551167D01*
X934617Y551667D01*
G01X937633Y551000D02*
Y554333D01*
G01Y553667D02*
X938050Y554000D01*
X938467Y554250D01*
X939050Y554333D01*
X939467Y554250D01*
X939967Y554000D01*
G01X948750Y551583D02*
X949167Y551250D01*
X949750Y551000D01*
X950250D01*
X950750Y551167D01*
X951083Y551417D01*
X951250Y551750D01*
X951167Y552250D01*
X950833Y552500D01*
X949333Y553000D01*
X949000Y553583D01*
X949167Y554000D01*
X949500Y554250D01*
X950000Y554333D01*
X950500Y554250D01*
X951000Y554000D01*
G01X955600Y554333D02*
Y551000D01*
G01Y555667D02*
X955433Y555750D01*
Y555917D01*
X955600Y556000D01*
X955767Y555917D01*
Y555750D01*
X955600Y555667D01*
G01X962700Y556000D02*
Y551000D01*
G01Y551750D02*
X962367Y551333D01*
X961867Y551083D01*
X961283Y551000D01*
X960617Y551167D01*
X960117Y551583D01*
X959783Y552083D01*
X959700Y552667D01*
X959783Y553250D01*
X960117Y553750D01*
X960617Y554167D01*
X961283Y554333D01*
X961867Y554250D01*
X962283Y554083D01*
X962700Y553750D01*
G01X965550Y553250D02*
X968217D01*
X967967Y553833D01*
X967550Y554167D01*
X966967Y554333D01*
X966383Y554250D01*
X965883Y554000D01*
X965550Y553417D01*
X965383Y552917D01*
Y552417D01*
X965550Y551917D01*
X965967Y551417D01*
X966467Y551083D01*
X967050Y551000D01*
X967633Y551167D01*
X968217Y551667D01*
G01X975917Y554333D02*
X976917Y551000D01*
X978000Y554333D01*
X979083Y551000D01*
X980083Y554333D01*
G01X983600D02*
Y551000D01*
G01Y555667D02*
X983433Y555750D01*
Y555917D01*
X983600Y556000D01*
X983767Y555917D01*
Y555750D01*
X983600Y555667D01*
G01X989200Y556000D02*
Y551000D01*
G01X988033Y554333D02*
X990367D01*
G01X993383Y551000D02*
Y556000D01*
G01Y553583D02*
X993800Y554000D01*
X994217Y554250D01*
X994883Y554333D01*
X995383Y554250D01*
X995967Y553917D01*
X996217Y553417D01*
Y551000D01*
G01X1000400D02*
X999900Y551083D01*
X999400Y551417D01*
X999067Y552000D01*
X998900Y552667D01*
X999067Y553333D01*
X999400Y553917D01*
X999900Y554250D01*
X1000400Y554333D01*
X1000900Y554250D01*
X1001400Y553917D01*
X1001733Y553333D01*
X1001817Y552667D01*
X1001733Y552000D01*
X1001400Y551417D01*
X1000900Y551083D01*
X1000400Y551000D01*
G01X1004583Y554333D02*
Y552000D01*
X1004917Y551417D01*
X1005417Y551083D01*
X1006000Y551000D01*
X1006583Y551083D01*
X1007083Y551417D01*
X1007417Y552000D01*
G01Y551000D02*
Y554333D01*
G01X1011600Y556000D02*
Y551000D01*
G01X1010433Y554333D02*
X1012767D01*
G01X878000Y591500D02*
X879667D01*
Y590000D01*
X879167Y589500D01*
X878583Y589167D01*
X877750Y589000D01*
X876917Y589167D01*
X876333Y589500D01*
X875833Y590000D01*
X875500Y590583D01*
X875333Y591250D01*
Y591833D01*
X875500Y592333D01*
X875833Y592917D01*
X876333Y593417D01*
X876833Y593750D01*
X877500Y594000D01*
X878083D01*
X878750Y593833D01*
X879250Y593500D01*
G01X881850Y591250D02*
X884517D01*
X884267Y591833D01*
X883850Y592167D01*
X883267Y592333D01*
X882683Y592250D01*
X882183Y592000D01*
X881850Y591417D01*
X881683Y590917D01*
Y590417D01*
X881850Y589917D01*
X882267Y589417D01*
X882767Y589083D01*
X883350Y589000D01*
X883933Y589167D01*
X884517Y589667D01*
G01X887533Y589000D02*
Y592333D01*
G01Y591667D02*
X887950Y592000D01*
X888367Y592250D01*
X888950Y592333D01*
X889367Y592250D01*
X889867Y592000D01*
G01X892800Y589000D02*
Y594000D01*
G01Y591500D02*
X893217Y592000D01*
X893717Y592250D01*
X894217Y592333D01*
X894967Y592167D01*
X895467Y591833D01*
X895800Y591250D01*
Y590583D01*
X895633Y589917D01*
X895300Y589417D01*
X894717Y589083D01*
X894217Y589000D01*
X893717Y589083D01*
X893217Y589333D01*
X892800Y589750D01*
G01X898650Y591250D02*
X901317D01*
X901067Y591833D01*
X900650Y592167D01*
X900067Y592333D01*
X899483Y592250D01*
X898983Y592000D01*
X898650Y591417D01*
X898483Y590917D01*
Y590417D01*
X898650Y589917D01*
X899067Y589417D01*
X899567Y589083D01*
X900150Y589000D01*
X900733Y589167D01*
X901317Y589667D01*
G01X904333Y589000D02*
Y592333D01*
G01Y591667D02*
X904750Y592000D01*
X905167Y592250D01*
X905750Y592333D01*
X906167Y592250D01*
X906667Y592000D01*
G01X918200Y594000D02*
Y589000D01*
G01Y589750D02*
X917867Y589333D01*
X917367Y589083D01*
X916783Y589000D01*
X916117Y589167D01*
X915617Y589583D01*
X915283Y590083D01*
X915200Y590667D01*
X915283Y591250D01*
X915617Y591750D01*
X916117Y592167D01*
X916783Y592333D01*
X917367Y592250D01*
X917783Y592083D01*
X918200Y591750D01*
G01X921050Y591250D02*
X923717D01*
X923467Y591833D01*
X923050Y592167D01*
X922467Y592333D01*
X921883Y592250D01*
X921383Y592000D01*
X921050Y591417D01*
X920883Y590917D01*
Y590417D01*
X921050Y589917D01*
X921467Y589417D01*
X921967Y589083D01*
X922550Y589000D01*
X923133Y589167D01*
X923717Y589667D01*
G01X926650Y589583D02*
X927067Y589250D01*
X927650Y589000D01*
X928150D01*
X928650Y589167D01*
X928983Y589417D01*
X929150Y589750D01*
X929067Y590250D01*
X928733Y590500D01*
X927233Y591000D01*
X926900Y591583D01*
X927067Y592000D01*
X927400Y592250D01*
X927900Y592333D01*
X928400Y592250D01*
X928900Y592000D01*
G01X933500Y592333D02*
Y589000D01*
G01Y593667D02*
X933333Y593750D01*
Y593917D01*
X933500Y594000D01*
X933667Y593917D01*
Y593750D01*
X933500Y593667D01*
G01X937933Y587750D02*
X938517Y587417D01*
X939183Y587333D01*
X939767Y587417D01*
X940267Y587833D01*
X940600Y588417D01*
Y592333D01*
G01Y591667D02*
X940267Y592000D01*
X939767Y592250D01*
X939183Y592333D01*
X938517Y592167D01*
X938100Y591833D01*
X937767Y591250D01*
X937600Y590667D01*
X937683Y590167D01*
X938017Y589583D01*
X938517Y589167D01*
X939183Y589000D01*
X939683Y589083D01*
X940267Y589417D01*
X940600Y589750D01*
G01X943283Y589000D02*
Y592333D01*
G01Y591500D02*
X943617Y591917D01*
X944117Y592250D01*
X944783Y592333D01*
X945367Y592250D01*
X945867Y591917D01*
X946117Y591333D01*
Y589000D01*
G01X928583Y23083D02*
X929167Y22667D01*
X929833Y22500D01*
X930500Y22667D01*
X931083Y23167D01*
X931500Y23917D01*
X931667Y24667D01*
Y25583D01*
X931500Y26333D01*
X931083Y27000D01*
X930583Y27333D01*
X930000Y27500D01*
X929333Y27333D01*
X928833Y27000D01*
X928500Y26500D01*
X928333Y25833D01*
X928500Y25250D01*
X928917Y24667D01*
X929417Y24333D01*
X930000Y24250D01*
X930667Y24417D01*
X931167Y24833D01*
X931667Y25583D01*
G01X934017Y24583D02*
X934600Y25167D01*
X935100Y25500D01*
X935767Y25667D01*
X936350Y25500D01*
X936767Y25167D01*
X937100Y24667D01*
X937183Y24083D01*
X937100Y23583D01*
X936767Y23083D01*
X936267Y22667D01*
X935683Y22500D01*
X935017Y22667D01*
X934433Y23167D01*
X934100Y23917D01*
X934017Y24750D01*
X934183Y25833D01*
X934433Y26417D01*
X934850Y27000D01*
X935433Y27417D01*
X936017Y27500D01*
X936600Y27333D01*
X937017Y26917D01*
G01X909250Y184083D02*
X909667Y183750D01*
X910250Y183500D01*
X910750D01*
X911250Y183667D01*
X911583Y183917D01*
X911750Y184250D01*
X911667Y184750D01*
X911333Y185000D01*
X909833Y185500D01*
X909500Y186083D01*
X909667Y186500D01*
X910000Y186750D01*
X910500Y186833D01*
X911000Y186750D01*
X911500Y186500D01*
G01X916100Y188500D02*
Y183500D01*
G01X914933Y186833D02*
X917267D01*
G01X920283D02*
Y184500D01*
X920617Y183917D01*
X921117Y183583D01*
X921700Y183500D01*
X922283Y183583D01*
X922783Y183917D01*
X923117Y184500D01*
G01Y183500D02*
Y186833D01*
G01X925800Y183500D02*
Y188500D01*
G01Y186000D02*
X926217Y186500D01*
X926717Y186750D01*
X927217Y186833D01*
X927967Y186667D01*
X928467Y186333D01*
X928800Y185750D01*
Y185083D01*
X928633Y184417D01*
X928300Y183917D01*
X927717Y183583D01*
X927217Y183500D01*
X926717Y183583D01*
X926217Y183833D01*
X925800Y184250D01*
G01X938500Y183500D02*
Y188500D01*
G01X942850Y185750D02*
X945517D01*
X945267Y186333D01*
X944850Y186667D01*
X944267Y186833D01*
X943683Y186750D01*
X943183Y186500D01*
X942850Y185917D01*
X942683Y185417D01*
Y184917D01*
X942850Y184417D01*
X943267Y183917D01*
X943767Y183583D01*
X944350Y183500D01*
X944933Y183667D01*
X945517Y184167D01*
G01X948283Y183500D02*
Y186833D01*
G01Y186000D02*
X948617Y186417D01*
X949117Y186750D01*
X949783Y186833D01*
X950367Y186750D01*
X950867Y186417D01*
X951117Y185833D01*
Y183500D01*
G01X954133Y182250D02*
X954717Y181917D01*
X955383Y181833D01*
X955967Y181917D01*
X956467Y182333D01*
X956800Y182917D01*
Y186833D01*
G01Y186167D02*
X956467Y186500D01*
X955967Y186750D01*
X955383Y186833D01*
X954717Y186667D01*
X954300Y186333D01*
X953967Y185750D01*
X953800Y185167D01*
X953883Y184667D01*
X954217Y184083D01*
X954717Y183667D01*
X955383Y183500D01*
X955883Y183583D01*
X956467Y183917D01*
X956800Y184250D01*
G01X960900Y188500D02*
Y183500D01*
G01X959733Y186833D02*
X962067D01*
G01X965083Y183500D02*
Y188500D01*
G01Y186083D02*
X965500Y186500D01*
X965917Y186750D01*
X966583Y186833D01*
X967083Y186750D01*
X967667Y186417D01*
X967917Y185917D01*
Y183500D01*
G01X971017Y184417D02*
X973183D01*
G01Y185917D02*
X971017D01*
G01X976117Y185583D02*
X976700Y186167D01*
X977200Y186500D01*
X977867Y186667D01*
X978450Y186500D01*
X978867Y186167D01*
X979200Y185667D01*
X979283Y185083D01*
X979200Y184583D01*
X978867Y184083D01*
X978367Y183667D01*
X977783Y183500D01*
X977117Y183667D01*
X976533Y184167D01*
X976200Y184917D01*
X976117Y185750D01*
X976283Y186833D01*
X976533Y187417D01*
X976950Y188000D01*
X977533Y188417D01*
X978117Y188500D01*
X978700Y188333D01*
X979117Y187917D01*
G01X982383Y185167D02*
X984383D01*
G01X983300Y186250D02*
Y184083D01*
G01X987400Y183333D02*
X990400Y188500D01*
G01X993417Y185167D02*
X995583D01*
G01X998267Y184250D02*
X998767Y183833D01*
X999350Y183583D01*
X1000100Y183500D01*
X1000850Y183667D01*
X1001433Y184000D01*
X1001850Y184583D01*
X1001933Y185250D01*
X1001767Y185917D01*
X1001350Y186333D01*
X1000767Y186667D01*
X1000183Y186750D01*
X999600Y186667D01*
X998850Y186333D01*
X999100Y188500D01*
X1001350D01*
G01X1003200Y183500D02*
Y186833D01*
G01Y185917D02*
X1003450Y186333D01*
X1003867Y186667D01*
X1004450Y186833D01*
X1005033Y186667D01*
X1005450Y186333D01*
X1005700Y185917D01*
Y183500D01*
G01Y185917D02*
X1005950Y186333D01*
X1006367Y186667D01*
X1006950Y186833D01*
X1007533Y186667D01*
X1007950Y186333D01*
X1008200Y185833D01*
Y183500D01*
G01X1011300Y186833D02*
Y183500D01*
G01Y188167D02*
X1011133Y188250D01*
Y188417D01*
X1011300Y188500D01*
X1011467Y188417D01*
Y188250D01*
X1011300Y188167D01*
G01X1016900Y183500D02*
Y188500D01*
G01X929000Y734500D02*
Y738750D01*
X929167Y739167D01*
X929500Y739417D01*
X930000Y739500D01*
X930500Y739333D01*
X930750Y738917D01*
G01X929750Y737500D02*
X928083D01*
G01X933683Y737833D02*
Y735500D01*
X934017Y734917D01*
X934517Y734583D01*
X935100Y734500D01*
X935683Y734583D01*
X936183Y734917D01*
X936517Y735500D01*
G01Y734500D02*
Y737833D01*
G01X940700Y734500D02*
Y739500D01*
G01X946300Y734500D02*
Y739500D01*
G01X956000Y732833D02*
Y737833D01*
G01Y737083D02*
X956417Y737500D01*
X956833Y737750D01*
X957500Y737833D01*
X958083Y737750D01*
X958667Y737333D01*
X958917Y736750D01*
X959000Y736167D01*
X958917Y735583D01*
X958667Y735000D01*
X958167Y734667D01*
X957500Y734500D01*
X956917Y734583D01*
X956333Y734833D01*
X956000Y735167D01*
G01X963100Y734500D02*
Y739500D01*
G01X967283Y737833D02*
Y735500D01*
X967617Y734917D01*
X968117Y734583D01*
X968700Y734500D01*
X969283Y734583D01*
X969783Y734917D01*
X970117Y735500D01*
G01Y734500D02*
Y737833D01*
G01X973133Y733250D02*
X973717Y732917D01*
X974383Y732833D01*
X974967Y732917D01*
X975467Y733333D01*
X975800Y733917D01*
Y737833D01*
G01Y737167D02*
X975467Y737500D01*
X974967Y737750D01*
X974383Y737833D01*
X973717Y737667D01*
X973300Y737333D01*
X972967Y736750D01*
X972800Y736167D01*
X972883Y735667D01*
X973217Y735083D01*
X973717Y734667D01*
X974383Y734500D01*
X974883Y734583D01*
X975467Y734917D01*
X975800Y735250D01*
G01X978733Y733250D02*
X979317Y732917D01*
X979983Y732833D01*
X980567Y732917D01*
X981067Y733333D01*
X981400Y733917D01*
Y737833D01*
G01Y737167D02*
X981067Y737500D01*
X980567Y737750D01*
X979983Y737833D01*
X979317Y737667D01*
X978900Y737333D01*
X978567Y736750D01*
X978400Y736167D01*
X978483Y735667D01*
X978817Y735083D01*
X979317Y734667D01*
X979983Y734500D01*
X980483Y734583D01*
X981067Y734917D01*
X981400Y735250D01*
G01X985500Y737833D02*
Y734500D01*
G01Y739167D02*
X985333Y739250D01*
Y739417D01*
X985500Y739500D01*
X985667Y739417D01*
Y739250D01*
X985500Y739167D01*
G01X989683Y734500D02*
Y737833D01*
G01Y737000D02*
X990017Y737417D01*
X990517Y737750D01*
X991183Y737833D01*
X991767Y737750D01*
X992267Y737417D01*
X992517Y736833D01*
Y734500D01*
G01X995533Y733250D02*
X996117Y732917D01*
X996783Y732833D01*
X997367Y732917D01*
X997867Y733333D01*
X998200Y733917D01*
Y737833D01*
G01Y737167D02*
X997867Y737500D01*
X997367Y737750D01*
X996783Y737833D01*
X996117Y737667D01*
X995700Y737333D01*
X995367Y736750D01*
X995200Y736167D01*
X995283Y735667D01*
X995617Y735083D01*
X996117Y734667D01*
X996783Y734500D01*
X997283Y734583D01*
X997867Y734917D01*
X998200Y735250D01*
G01X948000Y850610D02*
Y782110D01*
G01X957500Y811500D02*
X959167D01*
Y810000D01*
X958667Y809500D01*
X958083Y809167D01*
X957250Y809000D01*
X956417Y809167D01*
X955833Y809500D01*
X955333Y810000D01*
X955000Y810583D01*
X954833Y811250D01*
Y811833D01*
X955000Y812333D01*
X955333Y812917D01*
X955833Y813417D01*
X956333Y813750D01*
X957000Y814000D01*
X957583D01*
X958250Y813833D01*
X958750Y813500D01*
G01X961100Y808833D02*
X964100Y814000D01*
G01X966617Y809000D02*
Y814000D01*
X969783D01*
G01X968617Y811583D02*
X966617D01*
G01X977650Y809667D02*
X978317Y809250D01*
X979067Y809000D01*
X979733D01*
X980400Y809250D01*
X980900Y809667D01*
X981150Y810250D01*
X980983Y810833D01*
X980567Y811333D01*
X979817Y811667D01*
X978817Y811833D01*
X978233Y812167D01*
X977983Y812750D01*
X978150Y813333D01*
X978567Y813750D01*
X979150Y814000D01*
X979733D01*
X980317Y813833D01*
X980817Y813417D01*
G01X985000Y809000D02*
Y814000D01*
G01X990600Y809000D02*
X990100Y809083D01*
X989600Y809417D01*
X989267Y810000D01*
X989100Y810667D01*
X989267Y811333D01*
X989600Y811917D01*
X990100Y812250D01*
X990600Y812333D01*
X991100Y812250D01*
X991600Y811917D01*
X991933Y811333D01*
X992017Y810667D01*
X991933Y810000D01*
X991600Y809417D01*
X991100Y809083D01*
X990600Y809000D01*
G01X996200Y814000D02*
Y809000D01*
G01X995033Y812333D02*
X997367D01*
G01X956000Y795980D02*
Y790980D01*
G01X954083Y795980D02*
X957917D01*
G01X959517Y794313D02*
X960517Y790980D01*
X961600Y794313D01*
X962683Y790980D01*
X963683Y794313D01*
G01X967200D02*
Y790980D01*
G01Y795647D02*
X967033Y795730D01*
Y795897D01*
X967200Y795980D01*
X967367Y795897D01*
Y795730D01*
X967200Y795647D01*
G01X971550Y791563D02*
X971967Y791230D01*
X972550Y790980D01*
X973050D01*
X973550Y791147D01*
X973883Y791397D01*
X974050Y791730D01*
X973967Y792230D01*
X973633Y792480D01*
X972133Y792980D01*
X971800Y793563D01*
X971967Y793980D01*
X972300Y794230D01*
X972800Y794313D01*
X973300Y794230D01*
X973800Y793980D01*
G01X978400Y795980D02*
Y790980D01*
G01X977233Y794313D02*
X979567D01*
G01X991100Y790980D02*
Y794313D01*
G01Y793730D02*
X990767Y794063D01*
X990267Y794230D01*
X989683Y794313D01*
X989100Y794147D01*
X988600Y793813D01*
X988267Y793313D01*
X988100Y792647D01*
X988267Y791980D01*
X988600Y791480D01*
X989100Y791147D01*
X989683Y790980D01*
X990267Y791063D01*
X990767Y791313D01*
X991100Y791647D01*
G01X993783Y790980D02*
Y794313D01*
G01Y793480D02*
X994117Y793897D01*
X994617Y794230D01*
X995283Y794313D01*
X995867Y794230D01*
X996367Y793897D01*
X996617Y793313D01*
Y790980D01*
G01X1002300Y795980D02*
Y790980D01*
G01Y791730D02*
X1001967Y791313D01*
X1001467Y791063D01*
X1000883Y790980D01*
X1000217Y791147D01*
X999717Y791563D01*
X999383Y792063D01*
X999300Y792647D01*
X999383Y793230D01*
X999717Y793730D01*
X1000217Y794147D01*
X1000883Y794313D01*
X1001467Y794230D01*
X1001883Y794063D01*
X1002300Y793730D01*
G01X1010500Y790980D02*
Y795980D01*
G01Y793480D02*
X1010917Y793980D01*
X1011417Y794230D01*
X1011917Y794313D01*
X1012667Y794147D01*
X1013167Y793813D01*
X1013500Y793230D01*
Y792563D01*
X1013333Y791897D01*
X1013000Y791397D01*
X1012417Y791063D01*
X1011917Y790980D01*
X1011417Y791063D01*
X1010917Y791313D01*
X1010500Y791730D01*
G01X1017600Y790980D02*
X1017100Y791063D01*
X1016600Y791397D01*
X1016267Y791980D01*
X1016100Y792647D01*
X1016267Y793313D01*
X1016600Y793897D01*
X1017100Y794230D01*
X1017600Y794313D01*
X1018100Y794230D01*
X1018600Y793897D01*
X1018933Y793313D01*
X1019017Y792647D01*
X1018933Y791980D01*
X1018600Y791397D01*
X1018100Y791063D01*
X1017600Y790980D01*
G01X1021117Y794313D02*
X1022117Y790980D01*
X1023200Y794313D01*
X1024283Y790980D01*
X1025283Y794313D01*
G01X955750Y826250D02*
X958417D01*
X958167Y826833D01*
X957750Y827167D01*
X957167Y827333D01*
X956583Y827250D01*
X956083Y827000D01*
X955750Y826417D01*
X955583Y825917D01*
Y825417D01*
X955750Y824917D01*
X956167Y824417D01*
X956667Y824083D01*
X957250Y824000D01*
X957833Y824167D01*
X958417Y824667D01*
G01X964100Y829000D02*
Y824000D01*
G01Y824750D02*
X963767Y824333D01*
X963267Y824083D01*
X962683Y824000D01*
X962017Y824167D01*
X961517Y824583D01*
X961183Y825083D01*
X961100Y825667D01*
X961183Y826250D01*
X961517Y826750D01*
X962017Y827167D01*
X962683Y827333D01*
X963267Y827250D01*
X963683Y827083D01*
X964100Y826750D01*
G01X967033Y822750D02*
X967617Y822417D01*
X968283Y822333D01*
X968867Y822417D01*
X969367Y822833D01*
X969700Y823417D01*
Y827333D01*
G01Y826667D02*
X969367Y827000D01*
X968867Y827250D01*
X968283Y827333D01*
X967617Y827167D01*
X967200Y826833D01*
X966867Y826250D01*
X966700Y825667D01*
X966783Y825167D01*
X967117Y824583D01*
X967617Y824167D01*
X968283Y824000D01*
X968783Y824083D01*
X969367Y824417D01*
X969700Y824750D01*
G01X972550Y826250D02*
X975217D01*
X974967Y826833D01*
X974550Y827167D01*
X973967Y827333D01*
X973383Y827250D01*
X972883Y827000D01*
X972550Y826417D01*
X972383Y825917D01*
Y825417D01*
X972550Y824917D01*
X972967Y824417D01*
X973467Y824083D01*
X974050Y824000D01*
X974633Y824167D01*
X975217Y824667D01*
G01X985000Y829000D02*
Y824000D01*
G01X983833Y827333D02*
X986167D01*
G01X990600Y824000D02*
X990100Y824083D01*
X989600Y824417D01*
X989267Y825000D01*
X989100Y825667D01*
X989267Y826333D01*
X989600Y826917D01*
X990100Y827250D01*
X990600Y827333D01*
X991100Y827250D01*
X991600Y826917D01*
X991933Y826333D01*
X992017Y825667D01*
X991933Y825000D01*
X991600Y824417D01*
X991100Y824083D01*
X990600Y824000D01*
G01X1000383D02*
Y829000D01*
G01Y826583D02*
X1000800Y827000D01*
X1001217Y827250D01*
X1001883Y827333D01*
X1002383Y827250D01*
X1002967Y826917D01*
X1003217Y826417D01*
Y824000D01*
G01X1007400D02*
X1006900Y824083D01*
X1006400Y824417D01*
X1006067Y825000D01*
X1005900Y825667D01*
X1006067Y826333D01*
X1006400Y826917D01*
X1006900Y827250D01*
X1007400Y827333D01*
X1007900Y827250D01*
X1008400Y826917D01*
X1008733Y826333D01*
X1008817Y825667D01*
X1008733Y825000D01*
X1008400Y824417D01*
X1007900Y824083D01*
X1007400Y824000D01*
G01X1013000D02*
Y829000D01*
G01X1017350Y826250D02*
X1020017D01*
X1019767Y826833D01*
X1019350Y827167D01*
X1018767Y827333D01*
X1018183Y827250D01*
X1017683Y827000D01*
X1017350Y826417D01*
X1017183Y825917D01*
Y825417D01*
X1017350Y824917D01*
X1017767Y824417D01*
X1018267Y824083D01*
X1018850Y824000D01*
X1019433Y824167D01*
X1020017Y824667D01*
G01X955750Y842750D02*
X958417D01*
X958167Y843333D01*
X957750Y843667D01*
X957167Y843833D01*
X956583Y843750D01*
X956083Y843500D01*
X955750Y842917D01*
X955583Y842417D01*
Y841917D01*
X955750Y841417D01*
X956167Y840917D01*
X956667Y840583D01*
X957250Y840500D01*
X957833Y840667D01*
X958417Y841167D01*
G01X964100Y845500D02*
Y840500D01*
G01Y841250D02*
X963767Y840833D01*
X963267Y840583D01*
X962683Y840500D01*
X962017Y840667D01*
X961517Y841083D01*
X961183Y841583D01*
X961100Y842167D01*
X961183Y842750D01*
X961517Y843250D01*
X962017Y843667D01*
X962683Y843833D01*
X963267Y843750D01*
X963683Y843583D01*
X964100Y843250D01*
G01X967033Y839250D02*
X967617Y838917D01*
X968283Y838833D01*
X968867Y838917D01*
X969367Y839333D01*
X969700Y839917D01*
Y843833D01*
G01Y843167D02*
X969367Y843500D01*
X968867Y843750D01*
X968283Y843833D01*
X967617Y843667D01*
X967200Y843333D01*
X966867Y842750D01*
X966700Y842167D01*
X966783Y841667D01*
X967117Y841083D01*
X967617Y840667D01*
X968283Y840500D01*
X968783Y840583D01*
X969367Y840917D01*
X969700Y841250D01*
G01X972550Y842750D02*
X975217D01*
X974967Y843333D01*
X974550Y843667D01*
X973967Y843833D01*
X973383Y843750D01*
X972883Y843500D01*
X972550Y842917D01*
X972383Y842417D01*
Y841917D01*
X972550Y841417D01*
X972967Y840917D01*
X973467Y840583D01*
X974050Y840500D01*
X974633Y840667D01*
X975217Y841167D01*
G01X985000Y845500D02*
Y840500D01*
G01X983833Y843833D02*
X986167D01*
G01X990600Y840500D02*
X990100Y840583D01*
X989600Y840917D01*
X989267Y841500D01*
X989100Y842167D01*
X989267Y842833D01*
X989600Y843417D01*
X990100Y843750D01*
X990600Y843833D01*
X991100Y843750D01*
X991600Y843417D01*
X991933Y842833D01*
X992017Y842167D01*
X991933Y841500D01*
X991600Y840917D01*
X991100Y840583D01*
X990600Y840500D01*
G01X1000550Y842750D02*
X1003217D01*
X1002967Y843333D01*
X1002550Y843667D01*
X1001967Y843833D01*
X1001383Y843750D01*
X1000883Y843500D01*
X1000550Y842917D01*
X1000383Y842417D01*
Y841917D01*
X1000550Y841417D01*
X1000967Y840917D01*
X1001467Y840583D01*
X1002050Y840500D01*
X1002633Y840667D01*
X1003217Y841167D01*
G01X1008900Y845500D02*
Y840500D01*
G01Y841250D02*
X1008567Y840833D01*
X1008067Y840583D01*
X1007483Y840500D01*
X1006817Y840667D01*
X1006317Y841083D01*
X1005983Y841583D01*
X1005900Y842167D01*
X1005983Y842750D01*
X1006317Y843250D01*
X1006817Y843667D01*
X1007483Y843833D01*
X1008067Y843750D01*
X1008483Y843583D01*
X1008900Y843250D01*
G01X1011833Y839250D02*
X1012417Y838917D01*
X1013083Y838833D01*
X1013667Y838917D01*
X1014167Y839333D01*
X1014500Y839917D01*
Y843833D01*
G01Y843167D02*
X1014167Y843500D01*
X1013667Y843750D01*
X1013083Y843833D01*
X1012417Y843667D01*
X1012000Y843333D01*
X1011667Y842750D01*
X1011500Y842167D01*
X1011583Y841667D01*
X1011917Y841083D01*
X1012417Y840667D01*
X1013083Y840500D01*
X1013583Y840583D01*
X1014167Y840917D01*
X1014500Y841250D01*
G01X1017350Y842750D02*
X1020017D01*
X1019767Y843333D01*
X1019350Y843667D01*
X1018767Y843833D01*
X1018183Y843750D01*
X1017683Y843500D01*
X1017350Y842917D01*
X1017183Y842417D01*
Y841917D01*
X1017350Y841417D01*
X1017767Y840917D01*
X1018267Y840583D01*
X1018850Y840500D01*
X1019433Y840667D01*
X1020017Y841167D01*
G01X948500Y819500D02*
X1343000D01*
G01X948500Y834500D02*
X1343000D01*
G01X995667Y5500D02*
Y10500D01*
X997333D01*
X998000Y10250D01*
X998500Y9917D01*
X998917Y9417D01*
X999250Y8833D01*
X999333Y8000D01*
X999250Y7167D01*
X998917Y6583D01*
X998500Y6083D01*
X998000Y5750D01*
X997333Y5500D01*
X995667D01*
G01X1003100D02*
Y10500D01*
X1002100Y9500D01*
G01Y5500D02*
X1004100D01*
G01X1007117Y7583D02*
X1007700Y8167D01*
X1008200Y8500D01*
X1008867Y8667D01*
X1009450Y8500D01*
X1009867Y8167D01*
X1010200Y7667D01*
X1010283Y7083D01*
X1010200Y6583D01*
X1009867Y6083D01*
X1009367Y5667D01*
X1008783Y5500D01*
X1008117Y5667D01*
X1007533Y6167D01*
X1007200Y6917D01*
X1007117Y7750D01*
X1007283Y8833D01*
X1007533Y9417D01*
X1007950Y10000D01*
X1008533Y10417D01*
X1009117Y10500D01*
X1009700Y10333D01*
X1010117Y9917D01*
G01X1014300Y5333D02*
X1014133Y5417D01*
Y5583D01*
X1014300Y5667D01*
X1014467Y5583D01*
Y5417D01*
X1014300Y5333D01*
G01Y7583D02*
X1014133Y7667D01*
Y7833D01*
X1014300Y7917D01*
X1014467Y7833D01*
Y7667D01*
X1014300Y7583D01*
G01X1018067Y5500D02*
Y10500D01*
X1019733D01*
X1020400Y10250D01*
X1020900Y9917D01*
X1021317Y9417D01*
X1021650Y8833D01*
X1021733Y8000D01*
X1021650Y7167D01*
X1021317Y6583D01*
X1020900Y6083D01*
X1020400Y5750D01*
X1019733Y5500D01*
X1018067D01*
G01X1025500Y8833D02*
Y5500D01*
G01Y10167D02*
X1025333Y10250D01*
Y10417D01*
X1025500Y10500D01*
X1025667Y10417D01*
Y10250D01*
X1025500Y10167D01*
G01X1032600Y5500D02*
Y8833D01*
G01Y8250D02*
X1032267Y8583D01*
X1031767Y8750D01*
X1031183Y8833D01*
X1030600Y8667D01*
X1030100Y8333D01*
X1029767Y7833D01*
X1029600Y7167D01*
X1029767Y6500D01*
X1030100Y6000D01*
X1030600Y5667D01*
X1031183Y5500D01*
X1031767Y5583D01*
X1032267Y5833D01*
X1032600Y6167D01*
G01X1034200Y5500D02*
Y8833D01*
G01Y7917D02*
X1034450Y8333D01*
X1034867Y8667D01*
X1035450Y8833D01*
X1036033Y8667D01*
X1036450Y8333D01*
X1036700Y7917D01*
Y5500D01*
G01Y7917D02*
X1036950Y8333D01*
X1037367Y8667D01*
X1037950Y8833D01*
X1038533Y8667D01*
X1038950Y8333D01*
X1039200Y7833D01*
Y5500D01*
G01X1041050Y7750D02*
X1043717D01*
X1043467Y8333D01*
X1043050Y8667D01*
X1042467Y8833D01*
X1041883Y8750D01*
X1041383Y8500D01*
X1041050Y7917D01*
X1040883Y7417D01*
Y6917D01*
X1041050Y6417D01*
X1041467Y5917D01*
X1041967Y5583D01*
X1042550Y5500D01*
X1043133Y5667D01*
X1043717Y6167D01*
G01X1047900Y10500D02*
Y5500D01*
G01X1046733Y8833D02*
X1049067D01*
G01X1052250Y7750D02*
X1054917D01*
X1054667Y8333D01*
X1054250Y8667D01*
X1053667Y8833D01*
X1053083Y8750D01*
X1052583Y8500D01*
X1052250Y7917D01*
X1052083Y7417D01*
Y6917D01*
X1052250Y6417D01*
X1052667Y5917D01*
X1053167Y5583D01*
X1053750Y5500D01*
X1054333Y5667D01*
X1054917Y6167D01*
G01X1057933Y5500D02*
Y8833D01*
G01Y8167D02*
X1058350Y8500D01*
X1058767Y8750D01*
X1059350Y8833D01*
X1059767Y8750D01*
X1060267Y8500D01*
G01X1070300Y5500D02*
Y10500D01*
X1069300Y9500D01*
G01Y5500D02*
X1071300D01*
G01X1074317Y7583D02*
X1074900Y8167D01*
X1075400Y8500D01*
X1076067Y8667D01*
X1076650Y8500D01*
X1077067Y8167D01*
X1077400Y7667D01*
X1077483Y7083D01*
X1077400Y6583D01*
X1077067Y6083D01*
X1076567Y5667D01*
X1075983Y5500D01*
X1075317Y5667D01*
X1074733Y6167D01*
X1074400Y6917D01*
X1074317Y7750D01*
X1074483Y8833D01*
X1074733Y9417D01*
X1075150Y10000D01*
X1075733Y10417D01*
X1076317Y10500D01*
X1076900Y10333D01*
X1077317Y9917D01*
G01X1079000Y5500D02*
Y8833D01*
G01Y7917D02*
X1079250Y8333D01*
X1079667Y8667D01*
X1080250Y8833D01*
X1080833Y8667D01*
X1081250Y8333D01*
X1081500Y7917D01*
Y5500D01*
G01Y7917D02*
X1081750Y8333D01*
X1082167Y8667D01*
X1082750Y8833D01*
X1083333Y8667D01*
X1083750Y8333D01*
X1084000Y7833D01*
Y5500D01*
G01X1087100Y8833D02*
Y5500D01*
G01Y10167D02*
X1086933Y10250D01*
Y10417D01*
X1087100Y10500D01*
X1087267Y10417D01*
Y10250D01*
X1087100Y10167D01*
G01X1092700Y5500D02*
Y10500D01*
G01X980667Y16500D02*
X977333D01*
Y21500D01*
X980667D01*
G01X979333Y19083D02*
X977333D01*
G01X983350Y19833D02*
X985850Y16500D01*
G01Y19833D02*
X983350Y16500D01*
G01X990200Y16333D02*
X990033Y16417D01*
Y16583D01*
X990200Y16667D01*
X990367Y16583D01*
Y16417D01*
X990200Y16333D01*
G01X994050Y16500D02*
Y21500D01*
G01X997550D02*
Y16500D01*
G01Y19000D02*
X994050D01*
G01X999733Y16500D02*
Y21500D01*
X1001817D01*
X1002483Y21250D01*
X1002900Y20917D01*
X1003067Y20250D01*
X1002900Y19583D01*
X1002400Y19167D01*
X1001817Y18917D01*
X999733D01*
G01X1001817D02*
X1003067Y16500D01*
G01X1008667D02*
X1005333D01*
Y21500D01*
X1008667D01*
G01X1007333Y19083D02*
X1005333D01*
G01X1013600Y16500D02*
Y21500D01*
X1010517Y17917D01*
X1014683D01*
G01X1016367Y17250D02*
X1016867Y16833D01*
X1017450Y16583D01*
X1018200Y16500D01*
X1018950Y16667D01*
X1019533Y17000D01*
X1019950Y17583D01*
X1020033Y18250D01*
X1019867Y18917D01*
X1019450Y19333D01*
X1018867Y19667D01*
X1018283Y19750D01*
X1017700Y19667D01*
X1016950Y19333D01*
X1017200Y21500D01*
X1019450D01*
G01X1022050Y16500D02*
X1025550Y21500D01*
G01X1022050D02*
X1025550Y16500D01*
G01X1027983Y17083D02*
X1028567Y16667D01*
X1029233Y16500D01*
X1029900Y16667D01*
X1030483Y17167D01*
X1030900Y17917D01*
X1031067Y18667D01*
Y19583D01*
X1030900Y20333D01*
X1030483Y21000D01*
X1029983Y21333D01*
X1029400Y21500D01*
X1028733Y21333D01*
X1028233Y21000D01*
X1027900Y20500D01*
X1027733Y19833D01*
X1027900Y19250D01*
X1028317Y18667D01*
X1028817Y18333D01*
X1029400Y18250D01*
X1030067Y18417D01*
X1030567Y18833D01*
X1031067Y19583D01*
G01X1033417Y18583D02*
X1034000Y19167D01*
X1034500Y19500D01*
X1035167Y19667D01*
X1035750Y19500D01*
X1036167Y19167D01*
X1036500Y18667D01*
X1036583Y18083D01*
X1036500Y17583D01*
X1036167Y17083D01*
X1035667Y16667D01*
X1035083Y16500D01*
X1034417Y16667D01*
X1033833Y17167D01*
X1033500Y17917D01*
X1033417Y18750D01*
X1033583Y19833D01*
X1033833Y20417D01*
X1034250Y21000D01*
X1034833Y21417D01*
X1035417Y21500D01*
X1036000Y21333D01*
X1036417Y20917D01*
G01X1040183Y14833D02*
X1039350Y15667D01*
X1038933Y16500D01*
Y19833D01*
X1039350Y20667D01*
X1040183Y21500D01*
G01X1044367Y16500D02*
Y21500D01*
X1046033D01*
X1046700Y21250D01*
X1047200Y20917D01*
X1047617Y20417D01*
X1047950Y19833D01*
X1048033Y19000D01*
X1047950Y18167D01*
X1047617Y17583D01*
X1047200Y17083D01*
X1046700Y16750D01*
X1046033Y16500D01*
X1044367D01*
G01X1051800D02*
Y21500D01*
X1050800Y20500D01*
G01Y16500D02*
X1052800D01*
G01X1055817Y18583D02*
X1056400Y19167D01*
X1056900Y19500D01*
X1057567Y19667D01*
X1058150Y19500D01*
X1058567Y19167D01*
X1058900Y18667D01*
X1058983Y18083D01*
X1058900Y17583D01*
X1058567Y17083D01*
X1058067Y16667D01*
X1057483Y16500D01*
X1056817Y16667D01*
X1056233Y17167D01*
X1055900Y17917D01*
X1055817Y18750D01*
X1055983Y19833D01*
X1056233Y20417D01*
X1056650Y21000D01*
X1057233Y21417D01*
X1057817Y21500D01*
X1058400Y21333D01*
X1058817Y20917D01*
G01X1061250Y16500D02*
X1064750Y21500D01*
G01X1061250D02*
X1064750Y16500D01*
G01X1069600D02*
Y21500D01*
X1066517Y17917D01*
X1070683D01*
G01X1074617Y14833D02*
X1075450Y15667D01*
X1075867Y16500D01*
Y19833D01*
X1075450Y20667D01*
X1074617Y21500D01*
G01X977333Y65500D02*
Y70500D01*
X979417D01*
X980083Y70250D01*
X980500Y69917D01*
X980667Y69250D01*
X980500Y68583D01*
X980000Y68167D01*
X979417Y67917D01*
X977333D01*
G01X979417D02*
X980667Y65500D01*
G01X986267D02*
X982933D01*
Y70500D01*
X986267D01*
G01X984933Y68083D02*
X982933D01*
G01X992033Y70083D02*
X991533Y70333D01*
X990950Y70500D01*
X990283D01*
X989533Y70250D01*
X988950Y69833D01*
X988533Y69333D01*
X988200Y68500D01*
X988117Y67750D01*
X988283Y67000D01*
X988533Y66500D01*
X989033Y66000D01*
X989617Y65667D01*
X990200Y65500D01*
X990783D01*
X991367Y65667D01*
X991867Y65917D01*
X992283Y66250D01*
G01X995800Y70500D02*
Y65500D01*
G01X993883Y70500D02*
X997717D01*
G01X999317Y65500D02*
X1001400Y70500D01*
X1003483Y65500D01*
G01X1002733Y67250D02*
X1000067D01*
G01X1005083Y65500D02*
Y70500D01*
X1008917Y65500D01*
Y70500D01*
G01X1013100Y68000D02*
X1014767D01*
Y66500D01*
X1014267Y66000D01*
X1013683Y65667D01*
X1012850Y65500D01*
X1012017Y65667D01*
X1011433Y66000D01*
X1010933Y66500D01*
X1010600Y67083D01*
X1010433Y67750D01*
Y68333D01*
X1010600Y68833D01*
X1010933Y69417D01*
X1011433Y69917D01*
X1011933Y70250D01*
X1012600Y70500D01*
X1013183D01*
X1013850Y70333D01*
X1014350Y70000D01*
G01X1016533Y70500D02*
Y65500D01*
X1019867D01*
G01X1025467D02*
X1022133D01*
Y70500D01*
X1025467D01*
G01X1024133Y68083D02*
X1022133D01*
G01X1033167Y65500D02*
Y70500D01*
X1034833D01*
X1035500Y70250D01*
X1036000Y69917D01*
X1036417Y69417D01*
X1036750Y68833D01*
X1036833Y68000D01*
X1036750Y67167D01*
X1036417Y66583D01*
X1036000Y66083D01*
X1035500Y65750D01*
X1034833Y65500D01*
X1033167D01*
G01X1038933D02*
Y70500D01*
X1041017D01*
X1041683Y70250D01*
X1042100Y69917D01*
X1042267Y69250D01*
X1042100Y68583D01*
X1041600Y68167D01*
X1041017Y67917D01*
X1038933D01*
G01X1041017D02*
X1042267Y65500D01*
G01X1045200Y70500D02*
X1047200D01*
G01X1046200D02*
Y65500D01*
G01X1045200D02*
X1047200D01*
G01X1050133Y70500D02*
Y65500D01*
X1053467D01*
G01X1055733Y70500D02*
Y65500D01*
X1059067D01*
G01X1066850D02*
Y70500D01*
G01X1070350D02*
Y65500D01*
G01Y68000D02*
X1066850D01*
G01X1074200Y65500D02*
X1073533Y65583D01*
X1072950Y65917D01*
X1072450Y66417D01*
X1072117Y67000D01*
X1071950Y67667D01*
Y68333D01*
X1072117Y69000D01*
X1072450Y69583D01*
X1072950Y70083D01*
X1073533Y70417D01*
X1074200Y70500D01*
X1074867Y70417D01*
X1075450Y70083D01*
X1075950Y69583D01*
X1076283Y69000D01*
X1076450Y68333D01*
Y67667D01*
X1076283Y67000D01*
X1075950Y66417D01*
X1075450Y65917D01*
X1074867Y65583D01*
X1074200Y65500D01*
G01X1078133Y70500D02*
Y65500D01*
X1081467D01*
G01X1087067D02*
X1083733D01*
Y70500D01*
X1087067D01*
G01X1085733Y68083D02*
X1083733D01*
G01X1094767Y65500D02*
Y70500D01*
X1096433D01*
X1097100Y70250D01*
X1097600Y69917D01*
X1098017Y69417D01*
X1098350Y68833D01*
X1098433Y68000D01*
X1098350Y67167D01*
X1098017Y66583D01*
X1097600Y66083D01*
X1097100Y65750D01*
X1096433Y65500D01*
X1094767D01*
G01X1103867D02*
X1100533D01*
Y70500D01*
X1103867D01*
G01X1102533Y68083D02*
X1100533D01*
G01X1106217Y65500D02*
Y70500D01*
X1109383D01*
G01X1108217Y68083D02*
X1106217D01*
G01X1112400Y70500D02*
X1114400D01*
G01X1113400D02*
Y65500D01*
G01X1112400D02*
X1114400D01*
G01X1117083D02*
Y70500D01*
X1120917Y65500D01*
Y70500D01*
G01X1126267Y65500D02*
X1122933D01*
Y70500D01*
X1126267D01*
G01X1124933Y68083D02*
X1122933D01*
G01X1026000Y336000D02*
Y86000D01*
G01X1021417Y383667D02*
X1021917Y384167D01*
X1022500Y384417D01*
X1023167Y384500D01*
X1024000Y384333D01*
X1024583Y383917D01*
X1024750Y383417D01*
X1024667Y382917D01*
X1024333Y382500D01*
X1022667Y381667D01*
X1021917Y381083D01*
X1021417Y380250D01*
X1021250Y379500D01*
X1024750D01*
G01X1028600Y379333D02*
X1028433Y379417D01*
Y379583D01*
X1028600Y379667D01*
X1028767Y379583D01*
Y379417D01*
X1028600Y379333D01*
G01X1032117Y384500D02*
X1034200Y379500D01*
X1036283Y384500D01*
G01X1039800Y382833D02*
Y379500D01*
G01Y384167D02*
X1039633Y384250D01*
Y384417D01*
X1039800Y384500D01*
X1039967Y384417D01*
Y384250D01*
X1039800Y384167D01*
G01X1046900Y379500D02*
Y382833D01*
G01Y382250D02*
X1046567Y382583D01*
X1046067Y382750D01*
X1045483Y382833D01*
X1044900Y382667D01*
X1044400Y382333D01*
X1044067Y381833D01*
X1043900Y381167D01*
X1044067Y380500D01*
X1044400Y380000D01*
X1044900Y379667D01*
X1045483Y379500D01*
X1046067Y379583D01*
X1046567Y379833D01*
X1046900Y380167D01*
G01X1055350Y380083D02*
X1055767Y379750D01*
X1056350Y379500D01*
X1056850D01*
X1057350Y379667D01*
X1057683Y379917D01*
X1057850Y380250D01*
X1057767Y380750D01*
X1057433Y381000D01*
X1055933Y381500D01*
X1055600Y382083D01*
X1055767Y382500D01*
X1056100Y382750D01*
X1056600Y382833D01*
X1057100Y382750D01*
X1057600Y382500D01*
G01X1060783Y379500D02*
Y384500D01*
G01Y382083D02*
X1061200Y382500D01*
X1061617Y382750D01*
X1062283Y382833D01*
X1062783Y382750D01*
X1063367Y382417D01*
X1063617Y381917D01*
Y379500D01*
G01X1067800D02*
X1067300Y379583D01*
X1066800Y379917D01*
X1066467Y380500D01*
X1066300Y381167D01*
X1066467Y381833D01*
X1066800Y382417D01*
X1067300Y382750D01*
X1067800Y382833D01*
X1068300Y382750D01*
X1068800Y382417D01*
X1069133Y381833D01*
X1069217Y381167D01*
X1069133Y380500D01*
X1068800Y379917D01*
X1068300Y379583D01*
X1067800Y379500D01*
G01X1071983Y382833D02*
Y380500D01*
X1072317Y379917D01*
X1072817Y379583D01*
X1073400Y379500D01*
X1073983Y379583D01*
X1074483Y379917D01*
X1074817Y380500D01*
G01Y379500D02*
Y382833D01*
G01X1079000Y379500D02*
Y384500D01*
G01X1086100D02*
Y379500D01*
G01Y380250D02*
X1085767Y379833D01*
X1085267Y379583D01*
X1084683Y379500D01*
X1084017Y379667D01*
X1083517Y380083D01*
X1083183Y380583D01*
X1083100Y381167D01*
X1083183Y381750D01*
X1083517Y382250D01*
X1084017Y382667D01*
X1084683Y382833D01*
X1085267Y382750D01*
X1085683Y382583D01*
X1086100Y382250D01*
G01X1094300Y379500D02*
Y384500D01*
G01Y382000D02*
X1094717Y382500D01*
X1095217Y382750D01*
X1095717Y382833D01*
X1096467Y382667D01*
X1096967Y382333D01*
X1097300Y381750D01*
Y381083D01*
X1097133Y380417D01*
X1096800Y379917D01*
X1096217Y379583D01*
X1095717Y379500D01*
X1095217Y379583D01*
X1094717Y379833D01*
X1094300Y380250D01*
G01X1100150Y381750D02*
X1102817D01*
X1102567Y382333D01*
X1102150Y382667D01*
X1101567Y382833D01*
X1100983Y382750D01*
X1100483Y382500D01*
X1100150Y381917D01*
X1099983Y381417D01*
Y380917D01*
X1100150Y380417D01*
X1100567Y379917D01*
X1101067Y379583D01*
X1101650Y379500D01*
X1102233Y379667D01*
X1102817Y380167D01*
G01X1111100Y377833D02*
Y382833D01*
G01Y382083D02*
X1111517Y382500D01*
X1111933Y382750D01*
X1112600Y382833D01*
X1113183Y382750D01*
X1113767Y382333D01*
X1114017Y381750D01*
X1114100Y381167D01*
X1114017Y380583D01*
X1113767Y380000D01*
X1113267Y379667D01*
X1112600Y379500D01*
X1112017Y379583D01*
X1111433Y379833D01*
X1111100Y380167D01*
G01X1118200Y379500D02*
Y384500D01*
G01X1122383Y382833D02*
Y380500D01*
X1122717Y379917D01*
X1123217Y379583D01*
X1123800Y379500D01*
X1124383Y379583D01*
X1124883Y379917D01*
X1125217Y380500D01*
G01Y379500D02*
Y382833D01*
G01X1128233Y378250D02*
X1128817Y377917D01*
X1129483Y377833D01*
X1130067Y377917D01*
X1130567Y378333D01*
X1130900Y378917D01*
Y382833D01*
G01Y382167D02*
X1130567Y382500D01*
X1130067Y382750D01*
X1129483Y382833D01*
X1128817Y382667D01*
X1128400Y382333D01*
X1128067Y381750D01*
X1127900Y381167D01*
X1127983Y380667D01*
X1128317Y380083D01*
X1128817Y379667D01*
X1129483Y379500D01*
X1129983Y379583D01*
X1130567Y379917D01*
X1130900Y380250D01*
G01X1133833Y378250D02*
X1134417Y377917D01*
X1135083Y377833D01*
X1135667Y377917D01*
X1136167Y378333D01*
X1136500Y378917D01*
Y382833D01*
G01Y382167D02*
X1136167Y382500D01*
X1135667Y382750D01*
X1135083Y382833D01*
X1134417Y382667D01*
X1134000Y382333D01*
X1133667Y381750D01*
X1133500Y381167D01*
X1133583Y380667D01*
X1133917Y380083D01*
X1134417Y379667D01*
X1135083Y379500D01*
X1135583Y379583D01*
X1136167Y379917D01*
X1136500Y380250D01*
G01X1139350Y381750D02*
X1142017D01*
X1141767Y382333D01*
X1141350Y382667D01*
X1140767Y382833D01*
X1140183Y382750D01*
X1139683Y382500D01*
X1139350Y381917D01*
X1139183Y381417D01*
Y380917D01*
X1139350Y380417D01*
X1139767Y379917D01*
X1140267Y379583D01*
X1140850Y379500D01*
X1141433Y379667D01*
X1142017Y380167D01*
G01X1147700Y384500D02*
Y379500D01*
G01Y380250D02*
X1147367Y379833D01*
X1146867Y379583D01*
X1146283Y379500D01*
X1145617Y379667D01*
X1145117Y380083D01*
X1144783Y380583D01*
X1144700Y381167D01*
X1144783Y381750D01*
X1145117Y382250D01*
X1145617Y382667D01*
X1146283Y382833D01*
X1146867Y382750D01*
X1147283Y382583D01*
X1147700Y382250D01*
G01X1155317Y382833D02*
X1156317Y379500D01*
X1157400Y382833D01*
X1158483Y379500D01*
X1159483Y382833D01*
G01X1163000D02*
Y379500D01*
G01Y384167D02*
X1162833Y384250D01*
Y384417D01*
X1163000Y384500D01*
X1163167Y384417D01*
Y384250D01*
X1163000Y384167D01*
G01X1168600Y384500D02*
Y379500D01*
G01X1167433Y382833D02*
X1169767D01*
G01X1172783Y379500D02*
Y384500D01*
G01Y382083D02*
X1173200Y382500D01*
X1173617Y382750D01*
X1174283Y382833D01*
X1174783Y382750D01*
X1175367Y382417D01*
X1175617Y381917D01*
Y379500D01*
G01X1183733D02*
X1187067Y381167D01*
X1183733Y382833D01*
G01X1189583Y380083D02*
X1190167Y379667D01*
X1190833Y379500D01*
X1191500Y379667D01*
X1192083Y380167D01*
X1192500Y380917D01*
X1192667Y381667D01*
Y382583D01*
X1192500Y383333D01*
X1192083Y384000D01*
X1191583Y384333D01*
X1191000Y384500D01*
X1190333Y384333D01*
X1189833Y384000D01*
X1189500Y383500D01*
X1189333Y382833D01*
X1189500Y382250D01*
X1189917Y381667D01*
X1190417Y381333D01*
X1191000Y381250D01*
X1191667Y381417D01*
X1192167Y381833D01*
X1192667Y382583D01*
G01X1196600Y384500D02*
X1195933Y384333D01*
X1195433Y383917D01*
X1195100Y383417D01*
X1194850Y382750D01*
X1194767Y382000D01*
X1194850Y381250D01*
X1195100Y380583D01*
X1195433Y380083D01*
X1195933Y379667D01*
X1196600Y379500D01*
X1197267Y379667D01*
X1197767Y380083D01*
X1198100Y380583D01*
X1198350Y381250D01*
X1198433Y382000D01*
X1198350Y382750D01*
X1198100Y383417D01*
X1197767Y383917D01*
X1197267Y384333D01*
X1196600Y384500D01*
G01X1200700Y379333D02*
X1203700Y384500D01*
G01X1200700D02*
X1200200Y384333D01*
X1199950Y384083D01*
X1199783Y383583D01*
X1199950Y383083D01*
X1200200Y382833D01*
X1200700Y382667D01*
X1201200Y382833D01*
X1201450Y383083D01*
X1201617Y383583D01*
X1201450Y384083D01*
X1201200Y384333D01*
X1200700Y384500D01*
G01X1203700Y381167D02*
X1203200Y381000D01*
X1202950Y380750D01*
X1202783Y380250D01*
X1202950Y379750D01*
X1203200Y379500D01*
X1203700Y379333D01*
X1204200Y379500D01*
X1204450Y379750D01*
X1204617Y380250D01*
X1204450Y380750D01*
X1204200Y381000D01*
X1203700Y381167D01*
G01X1212233Y379500D02*
Y382833D01*
G01Y382167D02*
X1212650Y382500D01*
X1213067Y382750D01*
X1213650Y382833D01*
X1214067Y382750D01*
X1214567Y382500D01*
G01X1217750Y381750D02*
X1220417D01*
X1220167Y382333D01*
X1219750Y382667D01*
X1219167Y382833D01*
X1218583Y382750D01*
X1218083Y382500D01*
X1217750Y381917D01*
X1217583Y381417D01*
Y380917D01*
X1217750Y380417D01*
X1218167Y379917D01*
X1218667Y379583D01*
X1219250Y379500D01*
X1219833Y379667D01*
X1220417Y380167D01*
G01X1223350Y380083D02*
X1223767Y379750D01*
X1224350Y379500D01*
X1224850D01*
X1225350Y379667D01*
X1225683Y379917D01*
X1225850Y380250D01*
X1225767Y380750D01*
X1225433Y381000D01*
X1223933Y381500D01*
X1223600Y382083D01*
X1223767Y382500D01*
X1224100Y382750D01*
X1224600Y382833D01*
X1225100Y382750D01*
X1225600Y382500D01*
G01X1230200Y382833D02*
Y379500D01*
G01Y384167D02*
X1230033Y384250D01*
Y384417D01*
X1230200Y384500D01*
X1230367Y384417D01*
Y384250D01*
X1230200Y384167D01*
G01X1234383Y379500D02*
Y382833D01*
G01Y382000D02*
X1234717Y382417D01*
X1235217Y382750D01*
X1235883Y382833D01*
X1236467Y382750D01*
X1236967Y382417D01*
X1237217Y381833D01*
Y379500D01*
G01X1246417Y378000D02*
X1247583Y379167D01*
Y380333D01*
X1246417D01*
Y379167D01*
X1247583D01*
G01Y381167D02*
Y382333D01*
X1246417D01*
Y381167D01*
X1247583D01*
G01X1250767Y379500D02*
Y384500D01*
X1252433D01*
X1253100Y384250D01*
X1253600Y383917D01*
X1254017Y383417D01*
X1254350Y382833D01*
X1254433Y382000D01*
X1254350Y381167D01*
X1254017Y380583D01*
X1253600Y380083D01*
X1253100Y379750D01*
X1252433Y379500D01*
X1250767D01*
G01X1258200D02*
X1257700Y379583D01*
X1257200Y379917D01*
X1256867Y380500D01*
X1256700Y381167D01*
X1256867Y381833D01*
X1257200Y382417D01*
X1257700Y382750D01*
X1258200Y382833D01*
X1258700Y382750D01*
X1259200Y382417D01*
X1259533Y381833D01*
X1259617Y381167D01*
X1259533Y380500D01*
X1259200Y379917D01*
X1258700Y379583D01*
X1258200Y379500D01*
G01X1267983D02*
Y382833D01*
G01Y382000D02*
X1268317Y382417D01*
X1268817Y382750D01*
X1269483Y382833D01*
X1270067Y382750D01*
X1270567Y382417D01*
X1270817Y381833D01*
Y379500D01*
G01X1275000D02*
X1274500Y379583D01*
X1274000Y379917D01*
X1273667Y380500D01*
X1273500Y381167D01*
X1273667Y381833D01*
X1274000Y382417D01*
X1274500Y382750D01*
X1275000Y382833D01*
X1275500Y382750D01*
X1276000Y382417D01*
X1276333Y381833D01*
X1276417Y381167D01*
X1276333Y380500D01*
X1276000Y379917D01*
X1275500Y379583D01*
X1275000Y379500D01*
G01X1280600Y384500D02*
Y379500D01*
G01X1279433Y382833D02*
X1281767D01*
G01X1293300Y379500D02*
Y382833D01*
G01Y382250D02*
X1292967Y382583D01*
X1292467Y382750D01*
X1291883Y382833D01*
X1291300Y382667D01*
X1290800Y382333D01*
X1290467Y381833D01*
X1290300Y381167D01*
X1290467Y380500D01*
X1290800Y380000D01*
X1291300Y379667D01*
X1291883Y379500D01*
X1292467Y379583D01*
X1292967Y379833D01*
X1293300Y380167D01*
G01X1297400Y379500D02*
Y384500D01*
G01X1303000Y379500D02*
Y384500D01*
G01X1308600Y379500D02*
X1308100Y379583D01*
X1307600Y379917D01*
X1307267Y380500D01*
X1307100Y381167D01*
X1307267Y381833D01*
X1307600Y382417D01*
X1308100Y382750D01*
X1308600Y382833D01*
X1309100Y382750D01*
X1309600Y382417D01*
X1309933Y381833D01*
X1310017Y381167D01*
X1309933Y380500D01*
X1309600Y379917D01*
X1309100Y379583D01*
X1308600Y379500D01*
G01X1312117Y382833D02*
X1313117Y379500D01*
X1314200Y382833D01*
X1315283Y379500D01*
X1316283Y382833D01*
G01X1033500Y370500D02*
Y375500D01*
G01Y373000D02*
X1033917Y373500D01*
X1034417Y373750D01*
X1034917Y373833D01*
X1035667Y373667D01*
X1036167Y373333D01*
X1036500Y372750D01*
Y372083D01*
X1036333Y371417D01*
X1036000Y370917D01*
X1035417Y370583D01*
X1034917Y370500D01*
X1034417Y370583D01*
X1033917Y370833D01*
X1033500Y371250D01*
G01X1039183Y373833D02*
Y371500D01*
X1039517Y370917D01*
X1040017Y370583D01*
X1040600Y370500D01*
X1041183Y370583D01*
X1041683Y370917D01*
X1042017Y371500D01*
G01Y370500D02*
Y373833D01*
G01X1044700Y370500D02*
Y375500D01*
G01Y373000D02*
X1045117Y373500D01*
X1045617Y373750D01*
X1046117Y373833D01*
X1046867Y373667D01*
X1047367Y373333D01*
X1047700Y372750D01*
Y372083D01*
X1047533Y371417D01*
X1047200Y370917D01*
X1046617Y370583D01*
X1046117Y370500D01*
X1045617Y370583D01*
X1045117Y370833D01*
X1044700Y371250D01*
G01X1050300Y370500D02*
Y375500D01*
G01Y373000D02*
X1050717Y373500D01*
X1051217Y373750D01*
X1051717Y373833D01*
X1052467Y373667D01*
X1052967Y373333D01*
X1053300Y372750D01*
Y372083D01*
X1053133Y371417D01*
X1052800Y370917D01*
X1052217Y370583D01*
X1051717Y370500D01*
X1051217Y370583D01*
X1050717Y370833D01*
X1050300Y371250D01*
G01X1057400Y370500D02*
Y375500D01*
G01X1061750Y372750D02*
X1064417D01*
X1064167Y373333D01*
X1063750Y373667D01*
X1063167Y373833D01*
X1062583Y373750D01*
X1062083Y373500D01*
X1061750Y372917D01*
X1061583Y372417D01*
Y371917D01*
X1061750Y371417D01*
X1062167Y370917D01*
X1062667Y370583D01*
X1063250Y370500D01*
X1063833Y370667D01*
X1064417Y371167D01*
G01X1074200Y373833D02*
Y370500D01*
G01Y375167D02*
X1074033Y375250D01*
Y375417D01*
X1074200Y375500D01*
X1074367Y375417D01*
Y375250D01*
X1074200Y375167D01*
G01X1078383Y370500D02*
Y373833D01*
G01Y373000D02*
X1078717Y373417D01*
X1079217Y373750D01*
X1079883Y373833D01*
X1080467Y373750D01*
X1080967Y373417D01*
X1081217Y372833D01*
Y370500D01*
G01X1084150Y371083D02*
X1084567Y370750D01*
X1085150Y370500D01*
X1085650D01*
X1086150Y370667D01*
X1086483Y370917D01*
X1086650Y371250D01*
X1086567Y371750D01*
X1086233Y372000D01*
X1084733Y372500D01*
X1084400Y373083D01*
X1084567Y373500D01*
X1084900Y373750D01*
X1085400Y373833D01*
X1085900Y373750D01*
X1086400Y373500D01*
G01X1091000Y373833D02*
Y370500D01*
G01Y375167D02*
X1090833Y375250D01*
Y375417D01*
X1091000Y375500D01*
X1091167Y375417D01*
Y375250D01*
X1091000Y375167D01*
G01X1098100Y375500D02*
Y370500D01*
G01Y371250D02*
X1097767Y370833D01*
X1097267Y370583D01*
X1096683Y370500D01*
X1096017Y370667D01*
X1095517Y371083D01*
X1095183Y371583D01*
X1095100Y372167D01*
X1095183Y372750D01*
X1095517Y373250D01*
X1096017Y373667D01*
X1096683Y373833D01*
X1097267Y373750D01*
X1097683Y373583D01*
X1098100Y373250D01*
G01X1100950Y372750D02*
X1103617D01*
X1103367Y373333D01*
X1102950Y373667D01*
X1102367Y373833D01*
X1101783Y373750D01*
X1101283Y373500D01*
X1100950Y372917D01*
X1100783Y372417D01*
Y371917D01*
X1100950Y371417D01*
X1101367Y370917D01*
X1101867Y370583D01*
X1102450Y370500D01*
X1103033Y370667D01*
X1103617Y371167D01*
G01X1113400Y375500D02*
Y370500D01*
G01X1112233Y373833D02*
X1114567D01*
G01X1117583Y370500D02*
Y375500D01*
G01Y373083D02*
X1118000Y373500D01*
X1118417Y373750D01*
X1119083Y373833D01*
X1119583Y373750D01*
X1120167Y373417D01*
X1120417Y372917D01*
Y370500D01*
G01X1123350Y372750D02*
X1126017D01*
X1125767Y373333D01*
X1125350Y373667D01*
X1124767Y373833D01*
X1124183Y373750D01*
X1123683Y373500D01*
X1123350Y372917D01*
X1123183Y372417D01*
Y371917D01*
X1123350Y371417D01*
X1123767Y370917D01*
X1124267Y370583D01*
X1124850Y370500D01*
X1125433Y370667D01*
X1126017Y371167D01*
G01X1134633Y370500D02*
Y373833D01*
G01Y373167D02*
X1135050Y373500D01*
X1135467Y373750D01*
X1136050Y373833D01*
X1136467Y373750D01*
X1136967Y373500D01*
G01X1140150Y372750D02*
X1142817D01*
X1142567Y373333D01*
X1142150Y373667D01*
X1141567Y373833D01*
X1140983Y373750D01*
X1140483Y373500D01*
X1140150Y372917D01*
X1139983Y372417D01*
Y371917D01*
X1140150Y371417D01*
X1140567Y370917D01*
X1141067Y370583D01*
X1141650Y370500D01*
X1142233Y370667D01*
X1142817Y371167D01*
G01X1145750Y371083D02*
X1146167Y370750D01*
X1146750Y370500D01*
X1147250D01*
X1147750Y370667D01*
X1148083Y370917D01*
X1148250Y371250D01*
X1148167Y371750D01*
X1147833Y372000D01*
X1146333Y372500D01*
X1146000Y373083D01*
X1146167Y373500D01*
X1146500Y373750D01*
X1147000Y373833D01*
X1147500Y373750D01*
X1148000Y373500D01*
G01X1152600Y373833D02*
Y370500D01*
G01Y375167D02*
X1152433Y375250D01*
Y375417D01*
X1152600Y375500D01*
X1152767Y375417D01*
Y375250D01*
X1152600Y375167D01*
G01X1156783Y370500D02*
Y373833D01*
G01Y373000D02*
X1157117Y373417D01*
X1157617Y373750D01*
X1158283Y373833D01*
X1158867Y373750D01*
X1159367Y373417D01*
X1159617Y372833D01*
Y370500D01*
G01X1163800Y370333D02*
X1163633Y370417D01*
Y370583D01*
X1163800Y370667D01*
X1163967Y370583D01*
Y370417D01*
X1163800Y370333D01*
G01X1016000Y604500D02*
Y366000D01*
G01X1023000Y390000D02*
Y395000D01*
X1022000Y394000D01*
G01Y390000D02*
X1024000D01*
G01X1028600Y389833D02*
X1028433Y389917D01*
Y390083D01*
X1028600Y390167D01*
X1028767Y390083D01*
Y389917D01*
X1028600Y389833D01*
G01X1032367Y390000D02*
Y395000D01*
X1034033D01*
X1034700Y394750D01*
X1035200Y394417D01*
X1035617Y393917D01*
X1035950Y393333D01*
X1036033Y392500D01*
X1035950Y391667D01*
X1035617Y391083D01*
X1035200Y390583D01*
X1034700Y390250D01*
X1034033Y390000D01*
X1032367D01*
G01X1039800Y393333D02*
Y390000D01*
G01Y394667D02*
X1039633Y394750D01*
Y394917D01*
X1039800Y395000D01*
X1039967Y394917D01*
Y394750D01*
X1039800Y394667D01*
G01X1042900Y390000D02*
Y393333D01*
G01Y392417D02*
X1043150Y392833D01*
X1043567Y393167D01*
X1044150Y393333D01*
X1044733Y393167D01*
X1045150Y392833D01*
X1045400Y392417D01*
Y390000D01*
G01Y392417D02*
X1045650Y392833D01*
X1046067Y393167D01*
X1046650Y393333D01*
X1047233Y393167D01*
X1047650Y392833D01*
X1047900Y392333D01*
Y390000D01*
G01X1049500Y388333D02*
Y393333D01*
G01Y392583D02*
X1049917Y393000D01*
X1050333Y393250D01*
X1051000Y393333D01*
X1051583Y393250D01*
X1052167Y392833D01*
X1052417Y392250D01*
X1052500Y391667D01*
X1052417Y391083D01*
X1052167Y390500D01*
X1051667Y390167D01*
X1051000Y390000D01*
X1050417Y390083D01*
X1049833Y390333D01*
X1049500Y390667D01*
G01X1056600Y390000D02*
Y395000D01*
G01X1060950Y392250D02*
X1063617D01*
X1063367Y392833D01*
X1062950Y393167D01*
X1062367Y393333D01*
X1061783Y393250D01*
X1061283Y393000D01*
X1060950Y392417D01*
X1060783Y391917D01*
Y391417D01*
X1060950Y390917D01*
X1061367Y390417D01*
X1061867Y390083D01*
X1062450Y390000D01*
X1063033Y390167D01*
X1063617Y390667D01*
G01X1075067Y390000D02*
X1071733Y391667D01*
X1075067Y393333D01*
G01X1084600Y390000D02*
Y395000D01*
X1083600Y394000D01*
G01Y390000D02*
X1085600D01*
G01X1093300D02*
Y393333D01*
G01Y392417D02*
X1093550Y392833D01*
X1093967Y393167D01*
X1094550Y393333D01*
X1095133Y393167D01*
X1095550Y392833D01*
X1095800Y392417D01*
Y390000D01*
G01Y392417D02*
X1096050Y392833D01*
X1096467Y393167D01*
X1097050Y393333D01*
X1097633Y393167D01*
X1098050Y392833D01*
X1098300Y392333D01*
Y390000D01*
G01X1101400Y393333D02*
Y390000D01*
G01Y394667D02*
X1101233Y394750D01*
Y394917D01*
X1101400Y395000D01*
X1101567Y394917D01*
Y394750D01*
X1101400Y394667D01*
G01X1107000Y390000D02*
Y395000D01*
G01X1117617Y388500D02*
X1118783Y389667D01*
Y390833D01*
X1117617D01*
Y389667D01*
X1118783D01*
G01Y391667D02*
Y392833D01*
X1117617D01*
Y391667D01*
X1118783D01*
G01X1033500Y413500D02*
Y418500D01*
G01Y416000D02*
X1033917Y416500D01*
X1034417Y416750D01*
X1034917Y416833D01*
X1035667Y416667D01*
X1036167Y416333D01*
X1036500Y415750D01*
Y415083D01*
X1036333Y414417D01*
X1036000Y413917D01*
X1035417Y413583D01*
X1034917Y413500D01*
X1034417Y413583D01*
X1033917Y413833D01*
X1033500Y414250D01*
G01X1039183Y416833D02*
Y414500D01*
X1039517Y413917D01*
X1040017Y413583D01*
X1040600Y413500D01*
X1041183Y413583D01*
X1041683Y413917D01*
X1042017Y414500D01*
G01Y413500D02*
Y416833D01*
G01X1044700Y413500D02*
Y418500D01*
G01Y416000D02*
X1045117Y416500D01*
X1045617Y416750D01*
X1046117Y416833D01*
X1046867Y416667D01*
X1047367Y416333D01*
X1047700Y415750D01*
Y415083D01*
X1047533Y414417D01*
X1047200Y413917D01*
X1046617Y413583D01*
X1046117Y413500D01*
X1045617Y413583D01*
X1045117Y413833D01*
X1044700Y414250D01*
G01X1050300Y413500D02*
Y418500D01*
G01Y416000D02*
X1050717Y416500D01*
X1051217Y416750D01*
X1051717Y416833D01*
X1052467Y416667D01*
X1052967Y416333D01*
X1053300Y415750D01*
Y415083D01*
X1053133Y414417D01*
X1052800Y413917D01*
X1052217Y413583D01*
X1051717Y413500D01*
X1051217Y413583D01*
X1050717Y413833D01*
X1050300Y414250D01*
G01X1057400Y413500D02*
Y418500D01*
G01X1061750Y415750D02*
X1064417D01*
X1064167Y416333D01*
X1063750Y416667D01*
X1063167Y416833D01*
X1062583Y416750D01*
X1062083Y416500D01*
X1061750Y415917D01*
X1061583Y415417D01*
Y414917D01*
X1061750Y414417D01*
X1062167Y413917D01*
X1062667Y413583D01*
X1063250Y413500D01*
X1063833Y413667D01*
X1064417Y414167D01*
G01X1074200Y416833D02*
Y413500D01*
G01Y418167D02*
X1074033Y418250D01*
Y418417D01*
X1074200Y418500D01*
X1074367Y418417D01*
Y418250D01*
X1074200Y418167D01*
G01X1078383Y413500D02*
Y416833D01*
G01Y416000D02*
X1078717Y416417D01*
X1079217Y416750D01*
X1079883Y416833D01*
X1080467Y416750D01*
X1080967Y416417D01*
X1081217Y415833D01*
Y413500D01*
G01X1084150Y414083D02*
X1084567Y413750D01*
X1085150Y413500D01*
X1085650D01*
X1086150Y413667D01*
X1086483Y413917D01*
X1086650Y414250D01*
X1086567Y414750D01*
X1086233Y415000D01*
X1084733Y415500D01*
X1084400Y416083D01*
X1084567Y416500D01*
X1084900Y416750D01*
X1085400Y416833D01*
X1085900Y416750D01*
X1086400Y416500D01*
G01X1091000Y416833D02*
Y413500D01*
G01Y418167D02*
X1090833Y418250D01*
Y418417D01*
X1091000Y418500D01*
X1091167Y418417D01*
Y418250D01*
X1091000Y418167D01*
G01X1098100Y418500D02*
Y413500D01*
G01Y414250D02*
X1097767Y413833D01*
X1097267Y413583D01*
X1096683Y413500D01*
X1096017Y413667D01*
X1095517Y414083D01*
X1095183Y414583D01*
X1095100Y415167D01*
X1095183Y415750D01*
X1095517Y416250D01*
X1096017Y416667D01*
X1096683Y416833D01*
X1097267Y416750D01*
X1097683Y416583D01*
X1098100Y416250D01*
G01X1100950Y415750D02*
X1103617D01*
X1103367Y416333D01*
X1102950Y416667D01*
X1102367Y416833D01*
X1101783Y416750D01*
X1101283Y416500D01*
X1100950Y415917D01*
X1100783Y415417D01*
Y414917D01*
X1100950Y414417D01*
X1101367Y413917D01*
X1101867Y413583D01*
X1102450Y413500D01*
X1103033Y413667D01*
X1103617Y414167D01*
G01X1113400Y418500D02*
Y413500D01*
G01X1112233Y416833D02*
X1114567D01*
G01X1117583Y413500D02*
Y418500D01*
G01Y416083D02*
X1118000Y416500D01*
X1118417Y416750D01*
X1119083Y416833D01*
X1119583Y416750D01*
X1120167Y416417D01*
X1120417Y415917D01*
Y413500D01*
G01X1123350Y415750D02*
X1126017D01*
X1125767Y416333D01*
X1125350Y416667D01*
X1124767Y416833D01*
X1124183Y416750D01*
X1123683Y416500D01*
X1123350Y415917D01*
X1123183Y415417D01*
Y414917D01*
X1123350Y414417D01*
X1123767Y413917D01*
X1124267Y413583D01*
X1124850Y413500D01*
X1125433Y413667D01*
X1126017Y414167D01*
G01X1134633Y413500D02*
Y416833D01*
G01Y416167D02*
X1135050Y416500D01*
X1135467Y416750D01*
X1136050Y416833D01*
X1136467Y416750D01*
X1136967Y416500D01*
G01X1140150Y415750D02*
X1142817D01*
X1142567Y416333D01*
X1142150Y416667D01*
X1141567Y416833D01*
X1140983Y416750D01*
X1140483Y416500D01*
X1140150Y415917D01*
X1139983Y415417D01*
Y414917D01*
X1140150Y414417D01*
X1140567Y413917D01*
X1141067Y413583D01*
X1141650Y413500D01*
X1142233Y413667D01*
X1142817Y414167D01*
G01X1145750Y414083D02*
X1146167Y413750D01*
X1146750Y413500D01*
X1147250D01*
X1147750Y413667D01*
X1148083Y413917D01*
X1148250Y414250D01*
X1148167Y414750D01*
X1147833Y415000D01*
X1146333Y415500D01*
X1146000Y416083D01*
X1146167Y416500D01*
X1146500Y416750D01*
X1147000Y416833D01*
X1147500Y416750D01*
X1148000Y416500D01*
G01X1152600Y416833D02*
Y413500D01*
G01Y418167D02*
X1152433Y418250D01*
Y418417D01*
X1152600Y418500D01*
X1152767Y418417D01*
Y418250D01*
X1152600Y418167D01*
G01X1156783Y413500D02*
Y416833D01*
G01Y416000D02*
X1157117Y416417D01*
X1157617Y416750D01*
X1158283Y416833D01*
X1158867Y416750D01*
X1159367Y416417D01*
X1159617Y415833D01*
Y413500D01*
G01X1163800Y413333D02*
X1163633Y413417D01*
Y413583D01*
X1163800Y413667D01*
X1163967Y413583D01*
Y413417D01*
X1163800Y413333D01*
G01X1023000Y424000D02*
Y429000D01*
X1022000Y428000D01*
G01Y424000D02*
X1024000D01*
G01X1028600Y423833D02*
X1028433Y423917D01*
Y424083D01*
X1028600Y424167D01*
X1028767Y424083D01*
Y423917D01*
X1028600Y423833D01*
G01X1032117Y429000D02*
X1034200Y424000D01*
X1036283Y429000D01*
G01X1039800Y427333D02*
Y424000D01*
G01Y428667D02*
X1039633Y428750D01*
Y428917D01*
X1039800Y429000D01*
X1039967Y428917D01*
Y428750D01*
X1039800Y428667D01*
G01X1046900Y424000D02*
Y427333D01*
G01Y426750D02*
X1046567Y427083D01*
X1046067Y427250D01*
X1045483Y427333D01*
X1044900Y427167D01*
X1044400Y426833D01*
X1044067Y426333D01*
X1043900Y425667D01*
X1044067Y425000D01*
X1044400Y424500D01*
X1044900Y424167D01*
X1045483Y424000D01*
X1046067Y424083D01*
X1046567Y424333D01*
X1046900Y424667D01*
G01X1055350Y424583D02*
X1055767Y424250D01*
X1056350Y424000D01*
X1056850D01*
X1057350Y424167D01*
X1057683Y424417D01*
X1057850Y424750D01*
X1057767Y425250D01*
X1057433Y425500D01*
X1055933Y426000D01*
X1055600Y426583D01*
X1055767Y427000D01*
X1056100Y427250D01*
X1056600Y427333D01*
X1057100Y427250D01*
X1057600Y427000D01*
G01X1060783Y424000D02*
Y429000D01*
G01Y426583D02*
X1061200Y427000D01*
X1061617Y427250D01*
X1062283Y427333D01*
X1062783Y427250D01*
X1063367Y426917D01*
X1063617Y426417D01*
Y424000D01*
G01X1067800D02*
X1067300Y424083D01*
X1066800Y424417D01*
X1066467Y425000D01*
X1066300Y425667D01*
X1066467Y426333D01*
X1066800Y426917D01*
X1067300Y427250D01*
X1067800Y427333D01*
X1068300Y427250D01*
X1068800Y426917D01*
X1069133Y426333D01*
X1069217Y425667D01*
X1069133Y425000D01*
X1068800Y424417D01*
X1068300Y424083D01*
X1067800Y424000D01*
G01X1071983Y427333D02*
Y425000D01*
X1072317Y424417D01*
X1072817Y424083D01*
X1073400Y424000D01*
X1073983Y424083D01*
X1074483Y424417D01*
X1074817Y425000D01*
G01Y424000D02*
Y427333D01*
G01X1079000Y424000D02*
Y429000D01*
G01X1086100D02*
Y424000D01*
G01Y424750D02*
X1085767Y424333D01*
X1085267Y424083D01*
X1084683Y424000D01*
X1084017Y424167D01*
X1083517Y424583D01*
X1083183Y425083D01*
X1083100Y425667D01*
X1083183Y426250D01*
X1083517Y426750D01*
X1084017Y427167D01*
X1084683Y427333D01*
X1085267Y427250D01*
X1085683Y427083D01*
X1086100Y426750D01*
G01X1094300Y424000D02*
Y429000D01*
G01Y426500D02*
X1094717Y427000D01*
X1095217Y427250D01*
X1095717Y427333D01*
X1096467Y427167D01*
X1096967Y426833D01*
X1097300Y426250D01*
Y425583D01*
X1097133Y424917D01*
X1096800Y424417D01*
X1096217Y424083D01*
X1095717Y424000D01*
X1095217Y424083D01*
X1094717Y424333D01*
X1094300Y424750D01*
G01X1100150Y426250D02*
X1102817D01*
X1102567Y426833D01*
X1102150Y427167D01*
X1101567Y427333D01*
X1100983Y427250D01*
X1100483Y427000D01*
X1100150Y426417D01*
X1099983Y425917D01*
Y425417D01*
X1100150Y424917D01*
X1100567Y424417D01*
X1101067Y424083D01*
X1101650Y424000D01*
X1102233Y424167D01*
X1102817Y424667D01*
G01X1111100Y422333D02*
Y427333D01*
G01Y426583D02*
X1111517Y427000D01*
X1111933Y427250D01*
X1112600Y427333D01*
X1113183Y427250D01*
X1113767Y426833D01*
X1114017Y426250D01*
X1114100Y425667D01*
X1114017Y425083D01*
X1113767Y424500D01*
X1113267Y424167D01*
X1112600Y424000D01*
X1112017Y424083D01*
X1111433Y424333D01*
X1111100Y424667D01*
G01X1118200Y424000D02*
Y429000D01*
G01X1122383Y427333D02*
Y425000D01*
X1122717Y424417D01*
X1123217Y424083D01*
X1123800Y424000D01*
X1124383Y424083D01*
X1124883Y424417D01*
X1125217Y425000D01*
G01Y424000D02*
Y427333D01*
G01X1128233Y422750D02*
X1128817Y422417D01*
X1129483Y422333D01*
X1130067Y422417D01*
X1130567Y422833D01*
X1130900Y423417D01*
Y427333D01*
G01Y426667D02*
X1130567Y427000D01*
X1130067Y427250D01*
X1129483Y427333D01*
X1128817Y427167D01*
X1128400Y426833D01*
X1128067Y426250D01*
X1127900Y425667D01*
X1127983Y425167D01*
X1128317Y424583D01*
X1128817Y424167D01*
X1129483Y424000D01*
X1129983Y424083D01*
X1130567Y424417D01*
X1130900Y424750D01*
G01X1133833Y422750D02*
X1134417Y422417D01*
X1135083Y422333D01*
X1135667Y422417D01*
X1136167Y422833D01*
X1136500Y423417D01*
Y427333D01*
G01Y426667D02*
X1136167Y427000D01*
X1135667Y427250D01*
X1135083Y427333D01*
X1134417Y427167D01*
X1134000Y426833D01*
X1133667Y426250D01*
X1133500Y425667D01*
X1133583Y425167D01*
X1133917Y424583D01*
X1134417Y424167D01*
X1135083Y424000D01*
X1135583Y424083D01*
X1136167Y424417D01*
X1136500Y424750D01*
G01X1139350Y426250D02*
X1142017D01*
X1141767Y426833D01*
X1141350Y427167D01*
X1140767Y427333D01*
X1140183Y427250D01*
X1139683Y427000D01*
X1139350Y426417D01*
X1139183Y425917D01*
Y425417D01*
X1139350Y424917D01*
X1139767Y424417D01*
X1140267Y424083D01*
X1140850Y424000D01*
X1141433Y424167D01*
X1142017Y424667D01*
G01X1147700Y429000D02*
Y424000D01*
G01Y424750D02*
X1147367Y424333D01*
X1146867Y424083D01*
X1146283Y424000D01*
X1145617Y424167D01*
X1145117Y424583D01*
X1144783Y425083D01*
X1144700Y425667D01*
X1144783Y426250D01*
X1145117Y426750D01*
X1145617Y427167D01*
X1146283Y427333D01*
X1146867Y427250D01*
X1147283Y427083D01*
X1147700Y426750D01*
G01X1155317Y427333D02*
X1156317Y424000D01*
X1157400Y427333D01*
X1158483Y424000D01*
X1159483Y427333D01*
G01X1163000D02*
Y424000D01*
G01Y428667D02*
X1162833Y428750D01*
Y428917D01*
X1163000Y429000D01*
X1163167Y428917D01*
Y428750D01*
X1163000Y428667D01*
G01X1168600Y429000D02*
Y424000D01*
G01X1167433Y427333D02*
X1169767D01*
G01X1172783Y424000D02*
Y429000D01*
G01Y426583D02*
X1173200Y427000D01*
X1173617Y427250D01*
X1174283Y427333D01*
X1174783Y427250D01*
X1175367Y426917D01*
X1175617Y426417D01*
Y424000D01*
G01X1183733D02*
X1187067Y425667D01*
X1183733Y427333D01*
G01X1189583Y424583D02*
X1190167Y424167D01*
X1190833Y424000D01*
X1191500Y424167D01*
X1192083Y424667D01*
X1192500Y425417D01*
X1192667Y426167D01*
Y427083D01*
X1192500Y427833D01*
X1192083Y428500D01*
X1191583Y428833D01*
X1191000Y429000D01*
X1190333Y428833D01*
X1189833Y428500D01*
X1189500Y428000D01*
X1189333Y427333D01*
X1189500Y426750D01*
X1189917Y426167D01*
X1190417Y425833D01*
X1191000Y425750D01*
X1191667Y425917D01*
X1192167Y426333D01*
X1192667Y427083D01*
G01X1196600Y429000D02*
X1195933Y428833D01*
X1195433Y428417D01*
X1195100Y427917D01*
X1194850Y427250D01*
X1194767Y426500D01*
X1194850Y425750D01*
X1195100Y425083D01*
X1195433Y424583D01*
X1195933Y424167D01*
X1196600Y424000D01*
X1197267Y424167D01*
X1197767Y424583D01*
X1198100Y425083D01*
X1198350Y425750D01*
X1198433Y426500D01*
X1198350Y427250D01*
X1198100Y427917D01*
X1197767Y428417D01*
X1197267Y428833D01*
X1196600Y429000D01*
G01X1200700Y423833D02*
X1203700Y429000D01*
G01X1200700D02*
X1200200Y428833D01*
X1199950Y428583D01*
X1199783Y428083D01*
X1199950Y427583D01*
X1200200Y427333D01*
X1200700Y427167D01*
X1201200Y427333D01*
X1201450Y427583D01*
X1201617Y428083D01*
X1201450Y428583D01*
X1201200Y428833D01*
X1200700Y429000D01*
G01X1203700Y425667D02*
X1203200Y425500D01*
X1202950Y425250D01*
X1202783Y424750D01*
X1202950Y424250D01*
X1203200Y424000D01*
X1203700Y423833D01*
X1204200Y424000D01*
X1204450Y424250D01*
X1204617Y424750D01*
X1204450Y425250D01*
X1204200Y425500D01*
X1203700Y425667D01*
G01X1212233Y424000D02*
Y427333D01*
G01Y426667D02*
X1212650Y427000D01*
X1213067Y427250D01*
X1213650Y427333D01*
X1214067Y427250D01*
X1214567Y427000D01*
G01X1217750Y426250D02*
X1220417D01*
X1220167Y426833D01*
X1219750Y427167D01*
X1219167Y427333D01*
X1218583Y427250D01*
X1218083Y427000D01*
X1217750Y426417D01*
X1217583Y425917D01*
Y425417D01*
X1217750Y424917D01*
X1218167Y424417D01*
X1218667Y424083D01*
X1219250Y424000D01*
X1219833Y424167D01*
X1220417Y424667D01*
G01X1223350Y424583D02*
X1223767Y424250D01*
X1224350Y424000D01*
X1224850D01*
X1225350Y424167D01*
X1225683Y424417D01*
X1225850Y424750D01*
X1225767Y425250D01*
X1225433Y425500D01*
X1223933Y426000D01*
X1223600Y426583D01*
X1223767Y427000D01*
X1224100Y427250D01*
X1224600Y427333D01*
X1225100Y427250D01*
X1225600Y427000D01*
G01X1230200Y427333D02*
Y424000D01*
G01Y428667D02*
X1230033Y428750D01*
Y428917D01*
X1230200Y429000D01*
X1230367Y428917D01*
Y428750D01*
X1230200Y428667D01*
G01X1234383Y424000D02*
Y427333D01*
G01Y426500D02*
X1234717Y426917D01*
X1235217Y427250D01*
X1235883Y427333D01*
X1236467Y427250D01*
X1236967Y426917D01*
X1237217Y426333D01*
Y424000D01*
G01X1246417Y422500D02*
X1247583Y423667D01*
Y424833D01*
X1246417D01*
Y423667D01*
X1247583D01*
G01Y425667D02*
Y426833D01*
X1246417D01*
Y425667D01*
X1247583D01*
G01X1250767Y424000D02*
Y429000D01*
X1252433D01*
X1253100Y428750D01*
X1253600Y428417D01*
X1254017Y427917D01*
X1254350Y427333D01*
X1254433Y426500D01*
X1254350Y425667D01*
X1254017Y425083D01*
X1253600Y424583D01*
X1253100Y424250D01*
X1252433Y424000D01*
X1250767D01*
G01X1258200D02*
X1257700Y424083D01*
X1257200Y424417D01*
X1256867Y425000D01*
X1256700Y425667D01*
X1256867Y426333D01*
X1257200Y426917D01*
X1257700Y427250D01*
X1258200Y427333D01*
X1258700Y427250D01*
X1259200Y426917D01*
X1259533Y426333D01*
X1259617Y425667D01*
X1259533Y425000D01*
X1259200Y424417D01*
X1258700Y424083D01*
X1258200Y424000D01*
G01X1267983D02*
Y427333D01*
G01Y426500D02*
X1268317Y426917D01*
X1268817Y427250D01*
X1269483Y427333D01*
X1270067Y427250D01*
X1270567Y426917D01*
X1270817Y426333D01*
Y424000D01*
G01X1275000D02*
X1274500Y424083D01*
X1274000Y424417D01*
X1273667Y425000D01*
X1273500Y425667D01*
X1273667Y426333D01*
X1274000Y426917D01*
X1274500Y427250D01*
X1275000Y427333D01*
X1275500Y427250D01*
X1276000Y426917D01*
X1276333Y426333D01*
X1276417Y425667D01*
X1276333Y425000D01*
X1276000Y424417D01*
X1275500Y424083D01*
X1275000Y424000D01*
G01X1280600Y429000D02*
Y424000D01*
G01X1279433Y427333D02*
X1281767D01*
G01X1293300Y424000D02*
Y427333D01*
G01Y426750D02*
X1292967Y427083D01*
X1292467Y427250D01*
X1291883Y427333D01*
X1291300Y427167D01*
X1290800Y426833D01*
X1290467Y426333D01*
X1290300Y425667D01*
X1290467Y425000D01*
X1290800Y424500D01*
X1291300Y424167D01*
X1291883Y424000D01*
X1292467Y424083D01*
X1292967Y424333D01*
X1293300Y424667D01*
G01X1297400Y424000D02*
Y429000D01*
G01X1303000Y424000D02*
Y429000D01*
G01X1308600Y424000D02*
X1308100Y424083D01*
X1307600Y424417D01*
X1307267Y425000D01*
X1307100Y425667D01*
X1307267Y426333D01*
X1307600Y426917D01*
X1308100Y427250D01*
X1308600Y427333D01*
X1309100Y427250D01*
X1309600Y426917D01*
X1309933Y426333D01*
X1310017Y425667D01*
X1309933Y425000D01*
X1309600Y424417D01*
X1309100Y424083D01*
X1308600Y424000D01*
G01X1312117Y427333D02*
X1313117Y424000D01*
X1314200Y427333D01*
X1315283Y424000D01*
X1316283Y427333D01*
G01X1025417Y445500D02*
X1027500Y440500D01*
X1029583Y445500D01*
G01X1033100Y443833D02*
Y440500D01*
G01Y445167D02*
X1032933Y445250D01*
Y445417D01*
X1033100Y445500D01*
X1033267Y445417D01*
Y445250D01*
X1033100Y445167D01*
G01X1040200Y440500D02*
Y443833D01*
G01Y443250D02*
X1039867Y443583D01*
X1039367Y443750D01*
X1038783Y443833D01*
X1038200Y443667D01*
X1037700Y443333D01*
X1037367Y442833D01*
X1037200Y442167D01*
X1037367Y441500D01*
X1037700Y441000D01*
X1038200Y440667D01*
X1038783Y440500D01*
X1039367Y440583D01*
X1039867Y440833D01*
X1040200Y441167D01*
G01X1048650Y441083D02*
X1049067Y440750D01*
X1049650Y440500D01*
X1050150D01*
X1050650Y440667D01*
X1050983Y440917D01*
X1051150Y441250D01*
X1051067Y441750D01*
X1050733Y442000D01*
X1049233Y442500D01*
X1048900Y443083D01*
X1049067Y443500D01*
X1049400Y443750D01*
X1049900Y443833D01*
X1050400Y443750D01*
X1050900Y443500D01*
G01X1054083Y440500D02*
Y445500D01*
G01Y443083D02*
X1054500Y443500D01*
X1054917Y443750D01*
X1055583Y443833D01*
X1056083Y443750D01*
X1056667Y443417D01*
X1056917Y442917D01*
Y440500D01*
G01X1061100D02*
X1060600Y440583D01*
X1060100Y440917D01*
X1059767Y441500D01*
X1059600Y442167D01*
X1059767Y442833D01*
X1060100Y443417D01*
X1060600Y443750D01*
X1061100Y443833D01*
X1061600Y443750D01*
X1062100Y443417D01*
X1062433Y442833D01*
X1062517Y442167D01*
X1062433Y441500D01*
X1062100Y440917D01*
X1061600Y440583D01*
X1061100Y440500D01*
G01X1065283Y443833D02*
Y441500D01*
X1065617Y440917D01*
X1066117Y440583D01*
X1066700Y440500D01*
X1067283Y440583D01*
X1067783Y440917D01*
X1068117Y441500D01*
G01Y440500D02*
Y443833D01*
G01X1072300Y440500D02*
Y445500D01*
G01X1079400D02*
Y440500D01*
G01Y441250D02*
X1079067Y440833D01*
X1078567Y440583D01*
X1077983Y440500D01*
X1077317Y440667D01*
X1076817Y441083D01*
X1076483Y441583D01*
X1076400Y442167D01*
X1076483Y442750D01*
X1076817Y443250D01*
X1077317Y443667D01*
X1077983Y443833D01*
X1078567Y443750D01*
X1078983Y443583D01*
X1079400Y443250D01*
G01X1087600Y440500D02*
Y445500D01*
G01Y443000D02*
X1088017Y443500D01*
X1088517Y443750D01*
X1089017Y443833D01*
X1089767Y443667D01*
X1090267Y443333D01*
X1090600Y442750D01*
Y442083D01*
X1090433Y441417D01*
X1090100Y440917D01*
X1089517Y440583D01*
X1089017Y440500D01*
X1088517Y440583D01*
X1088017Y440833D01*
X1087600Y441250D01*
G01X1093450Y442750D02*
X1096117D01*
X1095867Y443333D01*
X1095450Y443667D01*
X1094867Y443833D01*
X1094283Y443750D01*
X1093783Y443500D01*
X1093450Y442917D01*
X1093283Y442417D01*
Y441917D01*
X1093450Y441417D01*
X1093867Y440917D01*
X1094367Y440583D01*
X1094950Y440500D01*
X1095533Y440667D01*
X1096117Y441167D01*
G01X1104400Y438833D02*
Y443833D01*
G01Y443083D02*
X1104817Y443500D01*
X1105233Y443750D01*
X1105900Y443833D01*
X1106483Y443750D01*
X1107067Y443333D01*
X1107317Y442750D01*
X1107400Y442167D01*
X1107317Y441583D01*
X1107067Y441000D01*
X1106567Y440667D01*
X1105900Y440500D01*
X1105317Y440583D01*
X1104733Y440833D01*
X1104400Y441167D01*
G01X1111500Y440500D02*
Y445500D01*
G01X1115683Y443833D02*
Y441500D01*
X1116017Y440917D01*
X1116517Y440583D01*
X1117100Y440500D01*
X1117683Y440583D01*
X1118183Y440917D01*
X1118517Y441500D01*
G01Y440500D02*
Y443833D01*
G01X1121533Y439250D02*
X1122117Y438917D01*
X1122783Y438833D01*
X1123367Y438917D01*
X1123867Y439333D01*
X1124200Y439917D01*
Y443833D01*
G01Y443167D02*
X1123867Y443500D01*
X1123367Y443750D01*
X1122783Y443833D01*
X1122117Y443667D01*
X1121700Y443333D01*
X1121367Y442750D01*
X1121200Y442167D01*
X1121283Y441667D01*
X1121617Y441083D01*
X1122117Y440667D01*
X1122783Y440500D01*
X1123283Y440583D01*
X1123867Y440917D01*
X1124200Y441250D01*
G01X1127133Y439250D02*
X1127717Y438917D01*
X1128383Y438833D01*
X1128967Y438917D01*
X1129467Y439333D01*
X1129800Y439917D01*
Y443833D01*
G01Y443167D02*
X1129467Y443500D01*
X1128967Y443750D01*
X1128383Y443833D01*
X1127717Y443667D01*
X1127300Y443333D01*
X1126967Y442750D01*
X1126800Y442167D01*
X1126883Y441667D01*
X1127217Y441083D01*
X1127717Y440667D01*
X1128383Y440500D01*
X1128883Y440583D01*
X1129467Y440917D01*
X1129800Y441250D01*
G01X1132650Y442750D02*
X1135317D01*
X1135067Y443333D01*
X1134650Y443667D01*
X1134067Y443833D01*
X1133483Y443750D01*
X1132983Y443500D01*
X1132650Y442917D01*
X1132483Y442417D01*
Y441917D01*
X1132650Y441417D01*
X1133067Y440917D01*
X1133567Y440583D01*
X1134150Y440500D01*
X1134733Y440667D01*
X1135317Y441167D01*
G01X1141000Y445500D02*
Y440500D01*
G01Y441250D02*
X1140667Y440833D01*
X1140167Y440583D01*
X1139583Y440500D01*
X1138917Y440667D01*
X1138417Y441083D01*
X1138083Y441583D01*
X1138000Y442167D01*
X1138083Y442750D01*
X1138417Y443250D01*
X1138917Y443667D01*
X1139583Y443833D01*
X1140167Y443750D01*
X1140583Y443583D01*
X1141000Y443250D01*
G01X1148617Y443833D02*
X1149617Y440500D01*
X1150700Y443833D01*
X1151783Y440500D01*
X1152783Y443833D01*
G01X1156300D02*
Y440500D01*
G01Y445167D02*
X1156133Y445250D01*
Y445417D01*
X1156300Y445500D01*
X1156467Y445417D01*
Y445250D01*
X1156300Y445167D01*
G01X1161900Y445500D02*
Y440500D01*
G01X1160733Y443833D02*
X1163067D01*
G01X1166083Y440500D02*
Y445500D01*
G01Y443083D02*
X1166500Y443500D01*
X1166917Y443750D01*
X1167583Y443833D01*
X1168083Y443750D01*
X1168667Y443417D01*
X1168917Y442917D01*
Y440500D01*
G01X1177033D02*
X1180367Y442167D01*
X1177033Y443833D01*
G01X1182883Y441083D02*
X1183467Y440667D01*
X1184133Y440500D01*
X1184800Y440667D01*
X1185383Y441167D01*
X1185800Y441917D01*
X1185967Y442667D01*
Y443583D01*
X1185800Y444333D01*
X1185383Y445000D01*
X1184883Y445333D01*
X1184300Y445500D01*
X1183633Y445333D01*
X1183133Y445000D01*
X1182800Y444500D01*
X1182633Y443833D01*
X1182800Y443250D01*
X1183217Y442667D01*
X1183717Y442333D01*
X1184300Y442250D01*
X1184967Y442417D01*
X1185467Y442833D01*
X1185967Y443583D01*
G01X1189900Y445500D02*
X1189233Y445333D01*
X1188733Y444917D01*
X1188400Y444417D01*
X1188150Y443750D01*
X1188067Y443000D01*
X1188150Y442250D01*
X1188400Y441583D01*
X1188733Y441083D01*
X1189233Y440667D01*
X1189900Y440500D01*
X1190567Y440667D01*
X1191067Y441083D01*
X1191400Y441583D01*
X1191650Y442250D01*
X1191733Y443000D01*
X1191650Y443750D01*
X1191400Y444417D01*
X1191067Y444917D01*
X1190567Y445333D01*
X1189900Y445500D01*
G01X1194000Y440333D02*
X1197000Y445500D01*
G01X1194000D02*
X1193500Y445333D01*
X1193250Y445083D01*
X1193083Y444583D01*
X1193250Y444083D01*
X1193500Y443833D01*
X1194000Y443667D01*
X1194500Y443833D01*
X1194750Y444083D01*
X1194917Y444583D01*
X1194750Y445083D01*
X1194500Y445333D01*
X1194000Y445500D01*
G01X1197000Y442167D02*
X1196500Y442000D01*
X1196250Y441750D01*
X1196083Y441250D01*
X1196250Y440750D01*
X1196500Y440500D01*
X1197000Y440333D01*
X1197500Y440500D01*
X1197750Y440750D01*
X1197917Y441250D01*
X1197750Y441750D01*
X1197500Y442000D01*
X1197000Y442167D01*
G01X1205533Y440500D02*
Y443833D01*
G01Y443167D02*
X1205950Y443500D01*
X1206367Y443750D01*
X1206950Y443833D01*
X1207367Y443750D01*
X1207867Y443500D01*
G01X1211050Y442750D02*
X1213717D01*
X1213467Y443333D01*
X1213050Y443667D01*
X1212467Y443833D01*
X1211883Y443750D01*
X1211383Y443500D01*
X1211050Y442917D01*
X1210883Y442417D01*
Y441917D01*
X1211050Y441417D01*
X1211467Y440917D01*
X1211967Y440583D01*
X1212550Y440500D01*
X1213133Y440667D01*
X1213717Y441167D01*
G01X1216650Y441083D02*
X1217067Y440750D01*
X1217650Y440500D01*
X1218150D01*
X1218650Y440667D01*
X1218983Y440917D01*
X1219150Y441250D01*
X1219067Y441750D01*
X1218733Y442000D01*
X1217233Y442500D01*
X1216900Y443083D01*
X1217067Y443500D01*
X1217400Y443750D01*
X1217900Y443833D01*
X1218400Y443750D01*
X1218900Y443500D01*
G01X1223500Y443833D02*
Y440500D01*
G01Y445167D02*
X1223333Y445250D01*
Y445417D01*
X1223500Y445500D01*
X1223667Y445417D01*
Y445250D01*
X1223500Y445167D01*
G01X1227683Y440500D02*
Y443833D01*
G01Y443000D02*
X1228017Y443417D01*
X1228517Y443750D01*
X1229183Y443833D01*
X1229767Y443750D01*
X1230267Y443417D01*
X1230517Y442833D01*
Y440500D01*
G01X1023917Y466500D02*
X1026000Y461500D01*
X1028083Y466500D01*
G01X1031600Y464833D02*
Y461500D01*
G01Y466167D02*
X1031433Y466250D01*
Y466417D01*
X1031600Y466500D01*
X1031767Y466417D01*
Y466250D01*
X1031600Y466167D01*
G01X1038700Y461500D02*
Y464833D01*
G01Y464250D02*
X1038367Y464583D01*
X1037867Y464750D01*
X1037283Y464833D01*
X1036700Y464667D01*
X1036200Y464333D01*
X1035867Y463833D01*
X1035700Y463167D01*
X1035867Y462500D01*
X1036200Y462000D01*
X1036700Y461667D01*
X1037283Y461500D01*
X1037867Y461583D01*
X1038367Y461833D01*
X1038700Y462167D01*
G01X1047150Y462083D02*
X1047567Y461750D01*
X1048150Y461500D01*
X1048650D01*
X1049150Y461667D01*
X1049483Y461917D01*
X1049650Y462250D01*
X1049567Y462750D01*
X1049233Y463000D01*
X1047733Y463500D01*
X1047400Y464083D01*
X1047567Y464500D01*
X1047900Y464750D01*
X1048400Y464833D01*
X1048900Y464750D01*
X1049400Y464500D01*
G01X1052583Y461500D02*
Y466500D01*
G01Y464083D02*
X1053000Y464500D01*
X1053417Y464750D01*
X1054083Y464833D01*
X1054583Y464750D01*
X1055167Y464417D01*
X1055417Y463917D01*
Y461500D01*
G01X1059600D02*
X1059100Y461583D01*
X1058600Y461917D01*
X1058267Y462500D01*
X1058100Y463167D01*
X1058267Y463833D01*
X1058600Y464417D01*
X1059100Y464750D01*
X1059600Y464833D01*
X1060100Y464750D01*
X1060600Y464417D01*
X1060933Y463833D01*
X1061017Y463167D01*
X1060933Y462500D01*
X1060600Y461917D01*
X1060100Y461583D01*
X1059600Y461500D01*
G01X1063783Y464833D02*
Y462500D01*
X1064117Y461917D01*
X1064617Y461583D01*
X1065200Y461500D01*
X1065783Y461583D01*
X1066283Y461917D01*
X1066617Y462500D01*
G01Y461500D02*
Y464833D01*
G01X1070800Y461500D02*
Y466500D01*
G01X1077900D02*
Y461500D01*
G01Y462250D02*
X1077567Y461833D01*
X1077067Y461583D01*
X1076483Y461500D01*
X1075817Y461667D01*
X1075317Y462083D01*
X1074983Y462583D01*
X1074900Y463167D01*
X1074983Y463750D01*
X1075317Y464250D01*
X1075817Y464667D01*
X1076483Y464833D01*
X1077067Y464750D01*
X1077483Y464583D01*
X1077900Y464250D01*
G01X1086100Y461500D02*
Y466500D01*
G01Y464000D02*
X1086517Y464500D01*
X1087017Y464750D01*
X1087517Y464833D01*
X1088267Y464667D01*
X1088767Y464333D01*
X1089100Y463750D01*
Y463083D01*
X1088933Y462417D01*
X1088600Y461917D01*
X1088017Y461583D01*
X1087517Y461500D01*
X1087017Y461583D01*
X1086517Y461833D01*
X1086100Y462250D01*
G01X1091950Y463750D02*
X1094617D01*
X1094367Y464333D01*
X1093950Y464667D01*
X1093367Y464833D01*
X1092783Y464750D01*
X1092283Y464500D01*
X1091950Y463917D01*
X1091783Y463417D01*
Y462917D01*
X1091950Y462417D01*
X1092367Y461917D01*
X1092867Y461583D01*
X1093450Y461500D01*
X1094033Y461667D01*
X1094617Y462167D01*
G01X1102900Y459833D02*
Y464833D01*
G01Y464083D02*
X1103317Y464500D01*
X1103733Y464750D01*
X1104400Y464833D01*
X1104983Y464750D01*
X1105567Y464333D01*
X1105817Y463750D01*
X1105900Y463167D01*
X1105817Y462583D01*
X1105567Y462000D01*
X1105067Y461667D01*
X1104400Y461500D01*
X1103817Y461583D01*
X1103233Y461833D01*
X1102900Y462167D01*
G01X1110000Y461500D02*
Y466500D01*
G01X1114183Y464833D02*
Y462500D01*
X1114517Y461917D01*
X1115017Y461583D01*
X1115600Y461500D01*
X1116183Y461583D01*
X1116683Y461917D01*
X1117017Y462500D01*
G01Y461500D02*
Y464833D01*
G01X1120033Y460250D02*
X1120617Y459917D01*
X1121283Y459833D01*
X1121867Y459917D01*
X1122367Y460333D01*
X1122700Y460917D01*
Y464833D01*
G01Y464167D02*
X1122367Y464500D01*
X1121867Y464750D01*
X1121283Y464833D01*
X1120617Y464667D01*
X1120200Y464333D01*
X1119867Y463750D01*
X1119700Y463167D01*
X1119783Y462667D01*
X1120117Y462083D01*
X1120617Y461667D01*
X1121283Y461500D01*
X1121783Y461583D01*
X1122367Y461917D01*
X1122700Y462250D01*
G01X1125633Y460250D02*
X1126217Y459917D01*
X1126883Y459833D01*
X1127467Y459917D01*
X1127967Y460333D01*
X1128300Y460917D01*
Y464833D01*
G01Y464167D02*
X1127967Y464500D01*
X1127467Y464750D01*
X1126883Y464833D01*
X1126217Y464667D01*
X1125800Y464333D01*
X1125467Y463750D01*
X1125300Y463167D01*
X1125383Y462667D01*
X1125717Y462083D01*
X1126217Y461667D01*
X1126883Y461500D01*
X1127383Y461583D01*
X1127967Y461917D01*
X1128300Y462250D01*
G01X1131150Y463750D02*
X1133817D01*
X1133567Y464333D01*
X1133150Y464667D01*
X1132567Y464833D01*
X1131983Y464750D01*
X1131483Y464500D01*
X1131150Y463917D01*
X1130983Y463417D01*
Y462917D01*
X1131150Y462417D01*
X1131567Y461917D01*
X1132067Y461583D01*
X1132650Y461500D01*
X1133233Y461667D01*
X1133817Y462167D01*
G01X1139500Y466500D02*
Y461500D01*
G01Y462250D02*
X1139167Y461833D01*
X1138667Y461583D01*
X1138083Y461500D01*
X1137417Y461667D01*
X1136917Y462083D01*
X1136583Y462583D01*
X1136500Y463167D01*
X1136583Y463750D01*
X1136917Y464250D01*
X1137417Y464667D01*
X1138083Y464833D01*
X1138667Y464750D01*
X1139083Y464583D01*
X1139500Y464250D01*
G01X1150200Y461500D02*
Y466500D01*
X1147117Y462917D01*
X1151283D01*
G01X1154800Y466500D02*
X1154133Y466333D01*
X1153633Y465917D01*
X1153300Y465417D01*
X1153050Y464750D01*
X1152967Y464000D01*
X1153050Y463250D01*
X1153300Y462583D01*
X1153633Y462083D01*
X1154133Y461667D01*
X1154800Y461500D01*
X1155467Y461667D01*
X1155967Y462083D01*
X1156300Y462583D01*
X1156550Y463250D01*
X1156633Y464000D01*
X1156550Y464750D01*
X1156300Y465417D01*
X1155967Y465917D01*
X1155467Y466333D01*
X1154800Y466500D01*
G01X1158900Y461333D02*
X1161900Y466500D01*
G01X1158900D02*
X1158400Y466333D01*
X1158150Y466083D01*
X1157983Y465583D01*
X1158150Y465083D01*
X1158400Y464833D01*
X1158900Y464667D01*
X1159400Y464833D01*
X1159650Y465083D01*
X1159817Y465583D01*
X1159650Y466083D01*
X1159400Y466333D01*
X1158900Y466500D01*
G01X1161900Y463167D02*
X1161400Y463000D01*
X1161150Y462750D01*
X1160983Y462250D01*
X1161150Y461750D01*
X1161400Y461500D01*
X1161900Y461333D01*
X1162400Y461500D01*
X1162650Y461750D01*
X1162817Y462250D01*
X1162650Y462750D01*
X1162400Y463000D01*
X1161900Y463167D01*
G01X1169100D02*
X1169933Y464833D01*
X1170767D01*
X1172433Y461500D01*
X1173267D01*
X1174100Y463167D01*
G01X1182800Y461500D02*
Y466500D01*
X1181800Y465500D01*
G01Y461500D02*
X1183800D01*
G01X1188400Y466500D02*
X1187733Y466333D01*
X1187233Y465917D01*
X1186900Y465417D01*
X1186650Y464750D01*
X1186567Y464000D01*
X1186650Y463250D01*
X1186900Y462583D01*
X1187233Y462083D01*
X1187733Y461667D01*
X1188400Y461500D01*
X1189067Y461667D01*
X1189567Y462083D01*
X1189900Y462583D01*
X1190150Y463250D01*
X1190233Y464000D01*
X1190150Y464750D01*
X1189900Y465417D01*
X1189567Y465917D01*
X1189067Y466333D01*
X1188400Y466500D01*
G01X1194000D02*
X1193333Y466333D01*
X1192833Y465917D01*
X1192500Y465417D01*
X1192250Y464750D01*
X1192167Y464000D01*
X1192250Y463250D01*
X1192500Y462583D01*
X1192833Y462083D01*
X1193333Y461667D01*
X1194000Y461500D01*
X1194667Y461667D01*
X1195167Y462083D01*
X1195500Y462583D01*
X1195750Y463250D01*
X1195833Y464000D01*
X1195750Y464750D01*
X1195500Y465417D01*
X1195167Y465917D01*
X1194667Y466333D01*
X1194000Y466500D01*
G01X1198100Y461333D02*
X1201100Y466500D01*
G01X1198100D02*
X1197600Y466333D01*
X1197350Y466083D01*
X1197183Y465583D01*
X1197350Y465083D01*
X1197600Y464833D01*
X1198100Y464667D01*
X1198600Y464833D01*
X1198850Y465083D01*
X1199017Y465583D01*
X1198850Y466083D01*
X1198600Y466333D01*
X1198100Y466500D01*
G01X1201100Y463167D02*
X1200600Y463000D01*
X1200350Y462750D01*
X1200183Y462250D01*
X1200350Y461750D01*
X1200600Y461500D01*
X1201100Y461333D01*
X1201600Y461500D01*
X1201850Y461750D01*
X1202017Y462250D01*
X1201850Y462750D01*
X1201600Y463000D01*
X1201100Y463167D01*
G01X1209550Y462083D02*
X1209967Y461750D01*
X1210550Y461500D01*
X1211050D01*
X1211550Y461667D01*
X1211883Y461917D01*
X1212050Y462250D01*
X1211967Y462750D01*
X1211633Y463000D01*
X1210133Y463500D01*
X1209800Y464083D01*
X1209967Y464500D01*
X1210300Y464750D01*
X1210800Y464833D01*
X1211300Y464750D01*
X1211800Y464500D01*
G01X1216400Y461500D02*
X1215900Y461583D01*
X1215400Y461917D01*
X1215067Y462500D01*
X1214900Y463167D01*
X1215067Y463833D01*
X1215400Y464417D01*
X1215900Y464750D01*
X1216400Y464833D01*
X1216900Y464750D01*
X1217400Y464417D01*
X1217733Y463833D01*
X1217817Y463167D01*
X1217733Y462500D01*
X1217400Y461917D01*
X1216900Y461583D01*
X1216400Y461500D01*
G01X1222000D02*
Y466500D01*
G01X1229100D02*
Y461500D01*
G01Y462250D02*
X1228767Y461833D01*
X1228267Y461583D01*
X1227683Y461500D01*
X1227017Y461667D01*
X1226517Y462083D01*
X1226183Y462583D01*
X1226100Y463167D01*
X1226183Y463750D01*
X1226517Y464250D01*
X1227017Y464667D01*
X1227683Y464833D01*
X1228267Y464750D01*
X1228683Y464583D01*
X1229100Y464250D01*
G01X1231950Y463750D02*
X1234617D01*
X1234367Y464333D01*
X1233950Y464667D01*
X1233367Y464833D01*
X1232783Y464750D01*
X1232283Y464500D01*
X1231950Y463917D01*
X1231783Y463417D01*
Y462917D01*
X1231950Y462417D01*
X1232367Y461917D01*
X1232867Y461583D01*
X1233450Y461500D01*
X1234033Y461667D01*
X1234617Y462167D01*
G01X1237633Y461500D02*
Y464833D01*
G01Y464167D02*
X1238050Y464500D01*
X1238467Y464750D01*
X1239050Y464833D01*
X1239467Y464750D01*
X1239967Y464500D01*
G01X1247500Y461500D02*
Y464833D01*
G01Y463917D02*
X1247750Y464333D01*
X1248167Y464667D01*
X1248750Y464833D01*
X1249333Y464667D01*
X1249750Y464333D01*
X1250000Y463917D01*
Y461500D01*
G01Y463917D02*
X1250250Y464333D01*
X1250667Y464667D01*
X1251250Y464833D01*
X1251833Y464667D01*
X1252250Y464333D01*
X1252500Y463833D01*
Y461500D01*
G01X1257100D02*
Y464833D01*
G01Y464250D02*
X1256767Y464583D01*
X1256267Y464750D01*
X1255683Y464833D01*
X1255100Y464667D01*
X1254600Y464333D01*
X1254267Y463833D01*
X1254100Y463167D01*
X1254267Y462500D01*
X1254600Y462000D01*
X1255100Y461667D01*
X1255683Y461500D01*
X1256267Y461583D01*
X1256767Y461833D01*
X1257100Y462167D01*
G01X1259950Y462083D02*
X1260367Y461750D01*
X1260950Y461500D01*
X1261450D01*
X1261950Y461667D01*
X1262283Y461917D01*
X1262450Y462250D01*
X1262367Y462750D01*
X1262033Y463000D01*
X1260533Y463500D01*
X1260200Y464083D01*
X1260367Y464500D01*
X1260700Y464750D01*
X1261200Y464833D01*
X1261700Y464750D01*
X1262200Y464500D01*
G01X1265383Y461500D02*
Y466500D01*
G01X1268050Y464833D02*
X1265383Y462917D01*
G01X1266467Y463667D02*
X1268217Y461500D01*
G01X1035500Y491500D02*
Y496500D01*
G01Y494000D02*
X1035917Y494500D01*
X1036417Y494750D01*
X1036917Y494833D01*
X1037667Y494667D01*
X1038167Y494333D01*
X1038500Y493750D01*
Y493083D01*
X1038333Y492417D01*
X1038000Y491917D01*
X1037417Y491583D01*
X1036917Y491500D01*
X1036417Y491583D01*
X1035917Y491833D01*
X1035500Y492250D01*
G01X1042600Y491333D02*
X1042433Y491417D01*
Y491583D01*
X1042600Y491667D01*
X1042767Y491583D01*
Y491417D01*
X1042600Y491333D01*
G01X1048867Y494167D02*
X1049200Y494417D01*
X1049450Y494833D01*
X1049617Y495417D01*
X1049450Y495917D01*
X1049117Y496250D01*
X1048533Y496500D01*
X1046283D01*
Y491500D01*
X1049033D01*
X1049617Y491833D01*
X1049950Y492333D01*
X1050117Y492917D01*
X1049950Y493500D01*
X1049450Y494000D01*
X1048867Y494167D01*
X1046283D01*
G01X1053800Y491500D02*
X1053300Y491583D01*
X1052800Y491917D01*
X1052467Y492500D01*
X1052300Y493167D01*
X1052467Y493833D01*
X1052800Y494417D01*
X1053300Y494750D01*
X1053800Y494833D01*
X1054300Y494750D01*
X1054800Y494417D01*
X1055133Y493833D01*
X1055217Y493167D01*
X1055133Y492500D01*
X1054800Y491917D01*
X1054300Y491583D01*
X1053800Y491500D01*
G01X1060900D02*
Y494833D01*
G01Y494250D02*
X1060567Y494583D01*
X1060067Y494750D01*
X1059483Y494833D01*
X1058900Y494667D01*
X1058400Y494333D01*
X1058067Y493833D01*
X1057900Y493167D01*
X1058067Y492500D01*
X1058400Y492000D01*
X1058900Y491667D01*
X1059483Y491500D01*
X1060067Y491583D01*
X1060567Y491833D01*
X1060900Y492167D01*
G01X1063833Y491500D02*
Y494833D01*
G01Y494167D02*
X1064250Y494500D01*
X1064667Y494750D01*
X1065250Y494833D01*
X1065667Y494750D01*
X1066167Y494500D01*
G01X1072100Y496500D02*
Y491500D01*
G01Y492250D02*
X1071767Y491833D01*
X1071267Y491583D01*
X1070683Y491500D01*
X1070017Y491667D01*
X1069517Y492083D01*
X1069183Y492583D01*
X1069100Y493167D01*
X1069183Y493750D01*
X1069517Y494250D01*
X1070017Y494667D01*
X1070683Y494833D01*
X1071267Y494750D01*
X1071683Y494583D01*
X1072100Y494250D01*
G01X1081800Y496500D02*
Y491500D01*
G01X1080633Y494833D02*
X1082967D01*
G01X1085983Y491500D02*
Y496500D01*
G01Y494083D02*
X1086400Y494500D01*
X1086817Y494750D01*
X1087483Y494833D01*
X1087983Y494750D01*
X1088567Y494417D01*
X1088817Y493917D01*
Y491500D01*
G01X1093000Y494833D02*
Y491500D01*
G01Y496167D02*
X1092833Y496250D01*
Y496417D01*
X1093000Y496500D01*
X1093167Y496417D01*
Y496250D01*
X1093000Y496167D01*
G01X1099933Y494417D02*
X1099350Y494750D01*
X1098850Y494833D01*
X1098183Y494667D01*
X1097683Y494333D01*
X1097350Y493750D01*
X1097267Y493167D01*
X1097350Y492583D01*
X1097683Y492083D01*
X1098183Y491667D01*
X1098850Y491500D01*
X1099433Y491667D01*
X1099933Y492000D01*
G01X1102783Y491500D02*
Y496500D01*
G01X1105450Y494833D02*
X1102783Y492917D01*
G01X1103867Y493667D02*
X1105617Y491500D01*
G01X1108383D02*
Y494833D01*
G01Y494000D02*
X1108717Y494417D01*
X1109217Y494750D01*
X1109883Y494833D01*
X1110467Y494750D01*
X1110967Y494417D01*
X1111217Y493833D01*
Y491500D01*
G01X1114150Y493750D02*
X1116817D01*
X1116567Y494333D01*
X1116150Y494667D01*
X1115567Y494833D01*
X1114983Y494750D01*
X1114483Y494500D01*
X1114150Y493917D01*
X1113983Y493417D01*
Y492917D01*
X1114150Y492417D01*
X1114567Y491917D01*
X1115067Y491583D01*
X1115650Y491500D01*
X1116233Y491667D01*
X1116817Y492167D01*
G01X1119750Y492083D02*
X1120167Y491750D01*
X1120750Y491500D01*
X1121250D01*
X1121750Y491667D01*
X1122083Y491917D01*
X1122250Y492250D01*
X1122167Y492750D01*
X1121833Y493000D01*
X1120333Y493500D01*
X1120000Y494083D01*
X1120167Y494500D01*
X1120500Y494750D01*
X1121000Y494833D01*
X1121500Y494750D01*
X1122000Y494500D01*
G01X1125350Y492083D02*
X1125767Y491750D01*
X1126350Y491500D01*
X1126850D01*
X1127350Y491667D01*
X1127683Y491917D01*
X1127850Y492250D01*
X1127767Y492750D01*
X1127433Y493000D01*
X1125933Y493500D01*
X1125600Y494083D01*
X1125767Y494500D01*
X1126100Y494750D01*
X1126600Y494833D01*
X1127100Y494750D01*
X1127600Y494500D01*
G01X1139467Y491500D02*
X1136133Y493167D01*
X1139467Y494833D01*
G01X1149000Y496500D02*
X1148333Y496333D01*
X1147833Y495917D01*
X1147500Y495417D01*
X1147250Y494750D01*
X1147167Y494000D01*
X1147250Y493250D01*
X1147500Y492583D01*
X1147833Y492083D01*
X1148333Y491667D01*
X1149000Y491500D01*
X1149667Y491667D01*
X1150167Y492083D01*
X1150500Y492583D01*
X1150750Y493250D01*
X1150833Y494000D01*
X1150750Y494750D01*
X1150500Y495417D01*
X1150167Y495917D01*
X1149667Y496333D01*
X1149000Y496500D01*
G01X1154600Y491333D02*
X1154433Y491417D01*
Y491583D01*
X1154600Y491667D01*
X1154767Y491583D01*
Y491417D01*
X1154600Y491333D01*
G01X1158783Y492083D02*
X1159367Y491667D01*
X1160033Y491500D01*
X1160700Y491667D01*
X1161283Y492167D01*
X1161700Y492917D01*
X1161867Y493667D01*
Y494583D01*
X1161700Y495333D01*
X1161283Y496000D01*
X1160783Y496333D01*
X1160200Y496500D01*
X1159533Y496333D01*
X1159033Y496000D01*
X1158700Y495500D01*
X1158533Y494833D01*
X1158700Y494250D01*
X1159117Y493667D01*
X1159617Y493333D01*
X1160200Y493250D01*
X1160867Y493417D01*
X1161367Y493833D01*
X1161867Y494583D01*
G01X1163300Y491500D02*
Y494833D01*
G01Y493917D02*
X1163550Y494333D01*
X1163967Y494667D01*
X1164550Y494833D01*
X1165133Y494667D01*
X1165550Y494333D01*
X1165800Y493917D01*
Y491500D01*
G01Y493917D02*
X1166050Y494333D01*
X1166467Y494667D01*
X1167050Y494833D01*
X1167633Y494667D01*
X1168050Y494333D01*
X1168300Y493833D01*
Y491500D01*
G01X1168900D02*
Y494833D01*
G01Y493917D02*
X1169150Y494333D01*
X1169567Y494667D01*
X1170150Y494833D01*
X1170733Y494667D01*
X1171150Y494333D01*
X1171400Y493917D01*
Y491500D01*
G01Y493917D02*
X1171650Y494333D01*
X1172067Y494667D01*
X1172650Y494833D01*
X1173233Y494667D01*
X1173650Y494333D01*
X1173900Y493833D01*
Y491500D01*
G01X1177000Y491333D02*
X1176833Y491417D01*
Y491583D01*
X1177000Y491667D01*
X1177167Y491583D01*
Y491417D01*
X1177000Y491333D01*
G01Y493583D02*
X1176833Y493667D01*
Y493833D01*
X1177000Y493917D01*
X1177167Y493833D01*
Y493667D01*
X1177000Y493583D01*
G01X1038500Y510500D02*
Y513833D01*
G01Y513250D02*
X1038167Y513583D01*
X1037667Y513750D01*
X1037083Y513833D01*
X1036500Y513667D01*
X1036000Y513333D01*
X1035667Y512833D01*
X1035500Y512167D01*
X1035667Y511500D01*
X1036000Y511000D01*
X1036500Y510667D01*
X1037083Y510500D01*
X1037667Y510583D01*
X1038167Y510833D01*
X1038500Y511167D01*
G01X1042600Y510333D02*
X1042433Y510417D01*
Y510583D01*
X1042600Y510667D01*
X1042767Y510583D01*
Y510417D01*
X1042600Y510333D01*
G01X1048867Y513167D02*
X1049200Y513417D01*
X1049450Y513833D01*
X1049617Y514417D01*
X1049450Y514917D01*
X1049117Y515250D01*
X1048533Y515500D01*
X1046283D01*
Y510500D01*
X1049033D01*
X1049617Y510833D01*
X1049950Y511333D01*
X1050117Y511917D01*
X1049950Y512500D01*
X1049450Y513000D01*
X1048867Y513167D01*
X1046283D01*
G01X1053800Y510500D02*
X1053300Y510583D01*
X1052800Y510917D01*
X1052467Y511500D01*
X1052300Y512167D01*
X1052467Y512833D01*
X1052800Y513417D01*
X1053300Y513750D01*
X1053800Y513833D01*
X1054300Y513750D01*
X1054800Y513417D01*
X1055133Y512833D01*
X1055217Y512167D01*
X1055133Y511500D01*
X1054800Y510917D01*
X1054300Y510583D01*
X1053800Y510500D01*
G01X1060900D02*
Y513833D01*
G01Y513250D02*
X1060567Y513583D01*
X1060067Y513750D01*
X1059483Y513833D01*
X1058900Y513667D01*
X1058400Y513333D01*
X1058067Y512833D01*
X1057900Y512167D01*
X1058067Y511500D01*
X1058400Y511000D01*
X1058900Y510667D01*
X1059483Y510500D01*
X1060067Y510583D01*
X1060567Y510833D01*
X1060900Y511167D01*
G01X1063833Y510500D02*
Y513833D01*
G01Y513167D02*
X1064250Y513500D01*
X1064667Y513750D01*
X1065250Y513833D01*
X1065667Y513750D01*
X1066167Y513500D01*
G01X1072100Y515500D02*
Y510500D01*
G01Y511250D02*
X1071767Y510833D01*
X1071267Y510583D01*
X1070683Y510500D01*
X1070017Y510667D01*
X1069517Y511083D01*
X1069183Y511583D01*
X1069100Y512167D01*
X1069183Y512750D01*
X1069517Y513250D01*
X1070017Y513667D01*
X1070683Y513833D01*
X1071267Y513750D01*
X1071683Y513583D01*
X1072100Y513250D01*
G01X1081800Y515500D02*
Y510500D01*
G01X1080633Y513833D02*
X1082967D01*
G01X1085983Y510500D02*
Y515500D01*
G01Y513083D02*
X1086400Y513500D01*
X1086817Y513750D01*
X1087483Y513833D01*
X1087983Y513750D01*
X1088567Y513417D01*
X1088817Y512917D01*
Y510500D01*
G01X1093000Y513833D02*
Y510500D01*
G01Y515167D02*
X1092833Y515250D01*
Y515417D01*
X1093000Y515500D01*
X1093167Y515417D01*
Y515250D01*
X1093000Y515167D01*
G01X1099933Y513417D02*
X1099350Y513750D01*
X1098850Y513833D01*
X1098183Y513667D01*
X1097683Y513333D01*
X1097350Y512750D01*
X1097267Y512167D01*
X1097350Y511583D01*
X1097683Y511083D01*
X1098183Y510667D01*
X1098850Y510500D01*
X1099433Y510667D01*
X1099933Y511000D01*
G01X1102783Y510500D02*
Y515500D01*
G01X1105450Y513833D02*
X1102783Y511917D01*
G01X1103867Y512667D02*
X1105617Y510500D01*
G01X1108383D02*
Y513833D01*
G01Y513000D02*
X1108717Y513417D01*
X1109217Y513750D01*
X1109883Y513833D01*
X1110467Y513750D01*
X1110967Y513417D01*
X1111217Y512833D01*
Y510500D01*
G01X1114150Y512750D02*
X1116817D01*
X1116567Y513333D01*
X1116150Y513667D01*
X1115567Y513833D01*
X1114983Y513750D01*
X1114483Y513500D01*
X1114150Y512917D01*
X1113983Y512417D01*
Y511917D01*
X1114150Y511417D01*
X1114567Y510917D01*
X1115067Y510583D01*
X1115650Y510500D01*
X1116233Y510667D01*
X1116817Y511167D01*
G01X1119750Y511083D02*
X1120167Y510750D01*
X1120750Y510500D01*
X1121250D01*
X1121750Y510667D01*
X1122083Y510917D01*
X1122250Y511250D01*
X1122167Y511750D01*
X1121833Y512000D01*
X1120333Y512500D01*
X1120000Y513083D01*
X1120167Y513500D01*
X1120500Y513750D01*
X1121000Y513833D01*
X1121500Y513750D01*
X1122000Y513500D01*
G01X1125350Y511083D02*
X1125767Y510750D01*
X1126350Y510500D01*
X1126850D01*
X1127350Y510667D01*
X1127683Y510917D01*
X1127850Y511250D01*
X1127767Y511750D01*
X1127433Y512000D01*
X1125933Y512500D01*
X1125600Y513083D01*
X1125767Y513500D01*
X1126100Y513750D01*
X1126600Y513833D01*
X1127100Y513750D01*
X1127600Y513500D01*
G01X1130533Y510500D02*
X1133867Y512167D01*
X1130533Y513833D01*
G01X1136717Y511417D02*
X1138883D01*
G01Y512917D02*
X1136717D01*
G01X1149000Y515500D02*
X1148333Y515333D01*
X1147833Y514917D01*
X1147500Y514417D01*
X1147250Y513750D01*
X1147167Y513000D01*
X1147250Y512250D01*
X1147500Y511583D01*
X1147833Y511083D01*
X1148333Y510667D01*
X1149000Y510500D01*
X1149667Y510667D01*
X1150167Y511083D01*
X1150500Y511583D01*
X1150750Y512250D01*
X1150833Y513000D01*
X1150750Y513750D01*
X1150500Y514417D01*
X1150167Y514917D01*
X1149667Y515333D01*
X1149000Y515500D01*
G01X1154600Y510333D02*
X1154433Y510417D01*
Y510583D01*
X1154600Y510667D01*
X1154767Y510583D01*
Y510417D01*
X1154600Y510333D01*
G01X1158783Y511083D02*
X1159367Y510667D01*
X1160033Y510500D01*
X1160700Y510667D01*
X1161283Y511167D01*
X1161700Y511917D01*
X1161867Y512667D01*
Y513583D01*
X1161700Y514333D01*
X1161283Y515000D01*
X1160783Y515333D01*
X1160200Y515500D01*
X1159533Y515333D01*
X1159033Y515000D01*
X1158700Y514500D01*
X1158533Y513833D01*
X1158700Y513250D01*
X1159117Y512667D01*
X1159617Y512333D01*
X1160200Y512250D01*
X1160867Y512417D01*
X1161367Y512833D01*
X1161867Y513583D01*
G01X1163300Y510500D02*
Y513833D01*
G01Y512917D02*
X1163550Y513333D01*
X1163967Y513667D01*
X1164550Y513833D01*
X1165133Y513667D01*
X1165550Y513333D01*
X1165800Y512917D01*
Y510500D01*
G01Y512917D02*
X1166050Y513333D01*
X1166467Y513667D01*
X1167050Y513833D01*
X1167633Y513667D01*
X1168050Y513333D01*
X1168300Y512833D01*
Y510500D01*
G01X1171400Y510333D02*
X1171233Y510417D01*
Y510583D01*
X1171400Y510667D01*
X1171567Y510583D01*
Y510417D01*
X1171400Y510333D01*
G01Y512583D02*
X1171233Y512667D01*
Y512833D01*
X1171400Y512917D01*
X1171567Y512833D01*
Y512667D01*
X1171400Y512583D01*
G01X1034250Y520500D02*
Y525500D01*
G01X1037750D02*
Y520500D01*
G01Y523000D02*
X1034250D01*
G01X1043100Y520500D02*
Y523833D01*
G01Y523250D02*
X1042767Y523583D01*
X1042267Y523750D01*
X1041683Y523833D01*
X1041100Y523667D01*
X1040600Y523333D01*
X1040267Y522833D01*
X1040100Y522167D01*
X1040267Y521500D01*
X1040600Y521000D01*
X1041100Y520667D01*
X1041683Y520500D01*
X1042267Y520583D01*
X1042767Y520833D01*
X1043100Y521167D01*
G01X1047200Y520500D02*
Y525500D01*
G01X1052300Y520500D02*
Y524750D01*
X1052467Y525167D01*
X1052800Y525417D01*
X1053300Y525500D01*
X1053800Y525333D01*
X1054050Y524917D01*
G01X1053050Y523500D02*
X1051383D01*
G01X1057317Y522167D02*
X1059483D01*
G01X1062500Y518833D02*
Y523833D01*
G01Y523083D02*
X1062917Y523500D01*
X1063333Y523750D01*
X1064000Y523833D01*
X1064583Y523750D01*
X1065167Y523333D01*
X1065417Y522750D01*
X1065500Y522167D01*
X1065417Y521583D01*
X1065167Y521000D01*
X1064667Y520667D01*
X1064000Y520500D01*
X1063417Y520583D01*
X1062833Y520833D01*
X1062500Y521167D01*
G01X1069600Y520500D02*
Y525500D01*
G01X1073783Y523833D02*
Y521500D01*
X1074117Y520917D01*
X1074617Y520583D01*
X1075200Y520500D01*
X1075783Y520583D01*
X1076283Y520917D01*
X1076617Y521500D01*
G01Y520500D02*
Y523833D01*
G01X1079633Y519250D02*
X1080217Y518917D01*
X1080883Y518833D01*
X1081467Y518917D01*
X1081967Y519333D01*
X1082300Y519917D01*
Y523833D01*
G01Y523167D02*
X1081967Y523500D01*
X1081467Y523750D01*
X1080883Y523833D01*
X1080217Y523667D01*
X1079800Y523333D01*
X1079467Y522750D01*
X1079300Y522167D01*
X1079383Y521667D01*
X1079717Y521083D01*
X1080217Y520667D01*
X1080883Y520500D01*
X1081383Y520583D01*
X1081967Y520917D01*
X1082300Y521250D01*
G01X1085233Y519250D02*
X1085817Y518917D01*
X1086483Y518833D01*
X1087067Y518917D01*
X1087567Y519333D01*
X1087900Y519917D01*
Y523833D01*
G01Y523167D02*
X1087567Y523500D01*
X1087067Y523750D01*
X1086483Y523833D01*
X1085817Y523667D01*
X1085400Y523333D01*
X1085067Y522750D01*
X1084900Y522167D01*
X1084983Y521667D01*
X1085317Y521083D01*
X1085817Y520667D01*
X1086483Y520500D01*
X1086983Y520583D01*
X1087567Y520917D01*
X1087900Y521250D01*
G01X1092000Y523833D02*
Y520500D01*
G01Y525167D02*
X1091833Y525250D01*
Y525417D01*
X1092000Y525500D01*
X1092167Y525417D01*
Y525250D01*
X1092000Y525167D01*
G01X1096183Y520500D02*
Y523833D01*
G01Y523000D02*
X1096517Y523417D01*
X1097017Y523750D01*
X1097683Y523833D01*
X1098267Y523750D01*
X1098767Y523417D01*
X1099017Y522833D01*
Y520500D01*
G01X1102033Y519250D02*
X1102617Y518917D01*
X1103283Y518833D01*
X1103867Y518917D01*
X1104367Y519333D01*
X1104700Y519917D01*
Y523833D01*
G01Y523167D02*
X1104367Y523500D01*
X1103867Y523750D01*
X1103283Y523833D01*
X1102617Y523667D01*
X1102200Y523333D01*
X1101867Y522750D01*
X1101700Y522167D01*
X1101783Y521667D01*
X1102117Y521083D01*
X1102617Y520667D01*
X1103283Y520500D01*
X1103783Y520583D01*
X1104367Y520917D01*
X1104700Y521250D01*
G01X1114400Y520333D02*
X1114233Y520417D01*
Y520583D01*
X1114400Y520667D01*
X1114567Y520583D01*
Y520417D01*
X1114400Y520333D01*
G01Y522583D02*
X1114233Y522667D01*
Y522833D01*
X1114400Y522917D01*
X1114567Y522833D01*
Y522667D01*
X1114400Y522583D01*
G01X1125600Y525500D02*
Y520500D01*
G01X1124433Y523833D02*
X1126767D01*
G01X1129783Y520500D02*
Y525500D01*
G01Y523083D02*
X1130200Y523500D01*
X1130617Y523750D01*
X1131283Y523833D01*
X1131783Y523750D01*
X1132367Y523417D01*
X1132617Y522917D01*
Y520500D01*
G01X1135550Y522750D02*
X1138217D01*
X1137967Y523333D01*
X1137550Y523667D01*
X1136967Y523833D01*
X1136383Y523750D01*
X1135883Y523500D01*
X1135550Y522917D01*
X1135383Y522417D01*
Y521917D01*
X1135550Y521417D01*
X1135967Y520917D01*
X1136467Y520583D01*
X1137050Y520500D01*
X1137633Y520667D01*
X1138217Y521167D01*
G01X1146500Y518833D02*
Y523833D01*
G01Y523083D02*
X1146917Y523500D01*
X1147333Y523750D01*
X1148000Y523833D01*
X1148583Y523750D01*
X1149167Y523333D01*
X1149417Y522750D01*
X1149500Y522167D01*
X1149417Y521583D01*
X1149167Y521000D01*
X1148667Y520667D01*
X1148000Y520500D01*
X1147417Y520583D01*
X1146833Y520833D01*
X1146500Y521167D01*
G01X1153600Y520500D02*
Y525500D01*
G01X1157783Y523833D02*
Y521500D01*
X1158117Y520917D01*
X1158617Y520583D01*
X1159200Y520500D01*
X1159783Y520583D01*
X1160283Y520917D01*
X1160617Y521500D01*
G01Y520500D02*
Y523833D01*
G01X1163633Y519250D02*
X1164217Y518917D01*
X1164883Y518833D01*
X1165467Y518917D01*
X1165967Y519333D01*
X1166300Y519917D01*
Y523833D01*
G01Y523167D02*
X1165967Y523500D01*
X1165467Y523750D01*
X1164883Y523833D01*
X1164217Y523667D01*
X1163800Y523333D01*
X1163467Y522750D01*
X1163300Y522167D01*
X1163383Y521667D01*
X1163717Y521083D01*
X1164217Y520667D01*
X1164883Y520500D01*
X1165383Y520583D01*
X1165967Y520917D01*
X1166300Y521250D01*
G01X1169233Y519250D02*
X1169817Y518917D01*
X1170483Y518833D01*
X1171067Y518917D01*
X1171567Y519333D01*
X1171900Y519917D01*
Y523833D01*
G01Y523167D02*
X1171567Y523500D01*
X1171067Y523750D01*
X1170483Y523833D01*
X1169817Y523667D01*
X1169400Y523333D01*
X1169067Y522750D01*
X1168900Y522167D01*
X1168983Y521667D01*
X1169317Y521083D01*
X1169817Y520667D01*
X1170483Y520500D01*
X1170983Y520583D01*
X1171567Y520917D01*
X1171900Y521250D01*
G01X1176000Y523833D02*
Y520500D01*
G01Y525167D02*
X1175833Y525250D01*
Y525417D01*
X1176000Y525500D01*
X1176167Y525417D01*
Y525250D01*
X1176000Y525167D01*
G01X1180183Y520500D02*
Y523833D01*
G01Y523000D02*
X1180517Y523417D01*
X1181017Y523750D01*
X1181683Y523833D01*
X1182267Y523750D01*
X1182767Y523417D01*
X1183017Y522833D01*
Y520500D01*
G01X1186033Y519250D02*
X1186617Y518917D01*
X1187283Y518833D01*
X1187867Y518917D01*
X1188367Y519333D01*
X1188700Y519917D01*
Y523833D01*
G01Y523167D02*
X1188367Y523500D01*
X1187867Y523750D01*
X1187283Y523833D01*
X1186617Y523667D01*
X1186200Y523333D01*
X1185867Y522750D01*
X1185700Y522167D01*
X1185783Y521667D01*
X1186117Y521083D01*
X1186617Y520667D01*
X1187283Y520500D01*
X1187783Y520583D01*
X1188367Y520917D01*
X1188700Y521250D01*
G01X1197233Y520500D02*
Y523833D01*
G01Y523167D02*
X1197650Y523500D01*
X1198067Y523750D01*
X1198650Y523833D01*
X1199067Y523750D01*
X1199567Y523500D01*
G01X1205500Y520500D02*
Y523833D01*
G01Y523250D02*
X1205167Y523583D01*
X1204667Y523750D01*
X1204083Y523833D01*
X1203500Y523667D01*
X1203000Y523333D01*
X1202667Y522833D01*
X1202500Y522167D01*
X1202667Y521500D01*
X1203000Y521000D01*
X1203500Y520667D01*
X1204083Y520500D01*
X1204667Y520583D01*
X1205167Y520833D01*
X1205500Y521167D01*
G01X1209600Y525500D02*
Y520500D01*
G01X1208433Y523833D02*
X1210767D01*
G01X1215200D02*
Y520500D01*
G01Y525167D02*
X1215033Y525250D01*
Y525417D01*
X1215200Y525500D01*
X1215367Y525417D01*
Y525250D01*
X1215200Y525167D01*
G01X1220800Y520500D02*
X1220300Y520583D01*
X1219800Y520917D01*
X1219467Y521500D01*
X1219300Y522167D01*
X1219467Y522833D01*
X1219800Y523417D01*
X1220300Y523750D01*
X1220800Y523833D01*
X1221300Y523750D01*
X1221800Y523417D01*
X1222133Y522833D01*
X1222217Y522167D01*
X1222133Y521500D01*
X1221800Y520917D01*
X1221300Y520583D01*
X1220800Y520500D01*
G01X1230500Y518833D02*
Y523833D01*
G01Y523083D02*
X1230917Y523500D01*
X1231333Y523750D01*
X1232000Y523833D01*
X1232583Y523750D01*
X1233167Y523333D01*
X1233417Y522750D01*
X1233500Y522167D01*
X1233417Y521583D01*
X1233167Y521000D01*
X1232667Y520667D01*
X1232000Y520500D01*
X1231417Y520583D01*
X1230833Y520833D01*
X1230500Y521167D01*
G01X1236350Y522750D02*
X1239017D01*
X1238767Y523333D01*
X1238350Y523667D01*
X1237767Y523833D01*
X1237183Y523750D01*
X1236683Y523500D01*
X1236350Y522917D01*
X1236183Y522417D01*
Y521917D01*
X1236350Y521417D01*
X1236767Y520917D01*
X1237267Y520583D01*
X1237850Y520500D01*
X1238433Y520667D01*
X1239017Y521167D01*
G01X1242033Y520500D02*
Y523833D01*
G01Y523167D02*
X1242450Y523500D01*
X1242867Y523750D01*
X1243450Y523833D01*
X1243867Y523750D01*
X1244367Y523500D01*
G01X1253900Y520500D02*
Y524750D01*
X1254067Y525167D01*
X1254400Y525417D01*
X1254900Y525500D01*
X1255400Y525333D01*
X1255650Y524917D01*
G01X1254650Y523500D02*
X1252983D01*
G01X1260000Y520500D02*
X1259500Y520583D01*
X1259000Y520917D01*
X1258667Y521500D01*
X1258500Y522167D01*
X1258667Y522833D01*
X1259000Y523417D01*
X1259500Y523750D01*
X1260000Y523833D01*
X1260500Y523750D01*
X1261000Y523417D01*
X1261333Y522833D01*
X1261417Y522167D01*
X1261333Y521500D01*
X1261000Y520917D01*
X1260500Y520583D01*
X1260000Y520500D01*
G01X1265600D02*
Y525500D01*
G01X1271200Y520500D02*
Y525500D01*
G01X1276800Y520500D02*
X1276300Y520583D01*
X1275800Y520917D01*
X1275467Y521500D01*
X1275300Y522167D01*
X1275467Y522833D01*
X1275800Y523417D01*
X1276300Y523750D01*
X1276800Y523833D01*
X1277300Y523750D01*
X1277800Y523417D01*
X1278133Y522833D01*
X1278217Y522167D01*
X1278133Y521500D01*
X1277800Y520917D01*
X1277300Y520583D01*
X1276800Y520500D01*
G01X1280317Y523833D02*
X1281317Y520500D01*
X1282400Y523833D01*
X1283483Y520500D01*
X1284483Y523833D01*
G01X1288000D02*
Y520500D01*
G01Y525167D02*
X1287833Y525250D01*
Y525417D01*
X1288000Y525500D01*
X1288167Y525417D01*
Y525250D01*
X1288000Y525167D01*
G01X1292183Y520500D02*
Y523833D01*
G01Y523000D02*
X1292517Y523417D01*
X1293017Y523750D01*
X1293683Y523833D01*
X1294267Y523750D01*
X1294767Y523417D01*
X1295017Y522833D01*
Y520500D01*
G01X1298033Y519250D02*
X1298617Y518917D01*
X1299283Y518833D01*
X1299867Y518917D01*
X1300367Y519333D01*
X1300700Y519917D01*
Y523833D01*
G01Y523167D02*
X1300367Y523500D01*
X1299867Y523750D01*
X1299283Y523833D01*
X1298617Y523667D01*
X1298200Y523333D01*
X1297867Y522750D01*
X1297700Y522167D01*
X1297783Y521667D01*
X1298117Y521083D01*
X1298617Y520667D01*
X1299283Y520500D01*
X1299783Y520583D01*
X1300367Y520917D01*
X1300700Y521250D01*
G01X1304800Y520333D02*
X1304633Y520417D01*
Y520583D01*
X1304800Y520667D01*
X1304967Y520583D01*
Y520417D01*
X1304800Y520333D01*
G01Y522583D02*
X1304633Y522667D01*
Y522833D01*
X1304800Y522917D01*
X1304967Y522833D01*
Y522667D01*
X1304800Y522583D01*
G01X1033500Y529500D02*
Y534500D01*
G01Y532000D02*
X1033917Y532500D01*
X1034417Y532750D01*
X1034917Y532833D01*
X1035667Y532667D01*
X1036167Y532333D01*
X1036500Y531750D01*
Y531083D01*
X1036333Y530417D01*
X1036000Y529917D01*
X1035417Y529583D01*
X1034917Y529500D01*
X1034417Y529583D01*
X1033917Y529833D01*
X1033500Y530250D01*
G01X1039350Y531750D02*
X1042017D01*
X1041767Y532333D01*
X1041350Y532667D01*
X1040767Y532833D01*
X1040183Y532750D01*
X1039683Y532500D01*
X1039350Y531917D01*
X1039183Y531417D01*
Y530917D01*
X1039350Y530417D01*
X1039767Y529917D01*
X1040267Y529583D01*
X1040850Y529500D01*
X1041433Y529667D01*
X1042017Y530167D01*
G01X1051300Y529500D02*
Y533750D01*
X1051467Y534167D01*
X1051800Y534417D01*
X1052300Y534500D01*
X1052800Y534333D01*
X1053050Y533917D01*
G01X1052050Y532500D02*
X1050383D01*
G01X1056233Y529500D02*
Y532833D01*
G01Y532167D02*
X1056650Y532500D01*
X1057067Y532750D01*
X1057650Y532833D01*
X1058067Y532750D01*
X1058567Y532500D01*
G01X1061750Y531750D02*
X1064417D01*
X1064167Y532333D01*
X1063750Y532667D01*
X1063167Y532833D01*
X1062583Y532750D01*
X1062083Y532500D01*
X1061750Y531917D01*
X1061583Y531417D01*
Y530917D01*
X1061750Y530417D01*
X1062167Y529917D01*
X1062667Y529583D01*
X1063250Y529500D01*
X1063833Y529667D01*
X1064417Y530167D01*
G01X1067350Y531750D02*
X1070017D01*
X1069767Y532333D01*
X1069350Y532667D01*
X1068767Y532833D01*
X1068183Y532750D01*
X1067683Y532500D01*
X1067350Y531917D01*
X1067183Y531417D01*
Y530917D01*
X1067350Y530417D01*
X1067767Y529917D01*
X1068267Y529583D01*
X1068850Y529500D01*
X1069433Y529667D01*
X1070017Y530167D01*
G01X1079300Y529500D02*
Y533750D01*
X1079467Y534167D01*
X1079800Y534417D01*
X1080300Y534500D01*
X1080800Y534333D01*
X1081050Y533917D01*
G01X1080050Y532500D02*
X1078383D01*
G01X1084233Y529500D02*
Y532833D01*
G01Y532167D02*
X1084650Y532500D01*
X1085067Y532750D01*
X1085650Y532833D01*
X1086067Y532750D01*
X1086567Y532500D01*
G01X1091000Y529500D02*
X1090500Y529583D01*
X1090000Y529917D01*
X1089667Y530500D01*
X1089500Y531167D01*
X1089667Y531833D01*
X1090000Y532417D01*
X1090500Y532750D01*
X1091000Y532833D01*
X1091500Y532750D01*
X1092000Y532417D01*
X1092333Y531833D01*
X1092417Y531167D01*
X1092333Y530500D01*
X1092000Y529917D01*
X1091500Y529583D01*
X1091000Y529500D01*
G01X1094100D02*
Y532833D01*
G01Y531917D02*
X1094350Y532333D01*
X1094767Y532667D01*
X1095350Y532833D01*
X1095933Y532667D01*
X1096350Y532333D01*
X1096600Y531917D01*
Y529500D01*
G01Y531917D02*
X1096850Y532333D01*
X1097267Y532667D01*
X1097850Y532833D01*
X1098433Y532667D01*
X1098850Y532333D01*
X1099100Y531833D01*
Y529500D01*
G01X1106550Y530083D02*
X1106967Y529750D01*
X1107550Y529500D01*
X1108050D01*
X1108550Y529667D01*
X1108883Y529917D01*
X1109050Y530250D01*
X1108967Y530750D01*
X1108633Y531000D01*
X1107133Y531500D01*
X1106800Y532083D01*
X1106967Y532500D01*
X1107300Y532750D01*
X1107800Y532833D01*
X1108300Y532750D01*
X1108800Y532500D01*
G01X1113400Y529500D02*
X1112900Y529583D01*
X1112400Y529917D01*
X1112067Y530500D01*
X1111900Y531167D01*
X1112067Y531833D01*
X1112400Y532417D01*
X1112900Y532750D01*
X1113400Y532833D01*
X1113900Y532750D01*
X1114400Y532417D01*
X1114733Y531833D01*
X1114817Y531167D01*
X1114733Y530500D01*
X1114400Y529917D01*
X1113900Y529583D01*
X1113400Y529500D01*
G01X1119000D02*
Y534500D01*
G01X1126100D02*
Y529500D01*
G01Y530250D02*
X1125767Y529833D01*
X1125267Y529583D01*
X1124683Y529500D01*
X1124017Y529667D01*
X1123517Y530083D01*
X1123183Y530583D01*
X1123100Y531167D01*
X1123183Y531750D01*
X1123517Y532250D01*
X1124017Y532667D01*
X1124683Y532833D01*
X1125267Y532750D01*
X1125683Y532583D01*
X1126100Y532250D01*
G01X1128950Y531750D02*
X1131617D01*
X1131367Y532333D01*
X1130950Y532667D01*
X1130367Y532833D01*
X1129783Y532750D01*
X1129283Y532500D01*
X1128950Y531917D01*
X1128783Y531417D01*
Y530917D01*
X1128950Y530417D01*
X1129367Y529917D01*
X1129867Y529583D01*
X1130450Y529500D01*
X1131033Y529667D01*
X1131617Y530167D01*
G01X1134633Y529500D02*
Y532833D01*
G01Y532167D02*
X1135050Y532500D01*
X1135467Y532750D01*
X1136050Y532833D01*
X1136467Y532750D01*
X1136967Y532500D01*
G01X1144500Y529500D02*
Y532833D01*
G01Y531917D02*
X1144750Y532333D01*
X1145167Y532667D01*
X1145750Y532833D01*
X1146333Y532667D01*
X1146750Y532333D01*
X1147000Y531917D01*
Y529500D01*
G01Y531917D02*
X1147250Y532333D01*
X1147667Y532667D01*
X1148250Y532833D01*
X1148833Y532667D01*
X1149250Y532333D01*
X1149500Y531833D01*
Y529500D01*
G01X1154100D02*
Y532833D01*
G01Y532250D02*
X1153767Y532583D01*
X1153267Y532750D01*
X1152683Y532833D01*
X1152100Y532667D01*
X1151600Y532333D01*
X1151267Y531833D01*
X1151100Y531167D01*
X1151267Y530500D01*
X1151600Y530000D01*
X1152100Y529667D01*
X1152683Y529500D01*
X1153267Y529583D01*
X1153767Y529833D01*
X1154100Y530167D01*
G01X1156950Y530083D02*
X1157367Y529750D01*
X1157950Y529500D01*
X1158450D01*
X1158950Y529667D01*
X1159283Y529917D01*
X1159450Y530250D01*
X1159367Y530750D01*
X1159033Y531000D01*
X1157533Y531500D01*
X1157200Y532083D01*
X1157367Y532500D01*
X1157700Y532750D01*
X1158200Y532833D01*
X1158700Y532750D01*
X1159200Y532500D01*
G01X1162383Y529500D02*
Y534500D01*
G01X1165050Y532833D02*
X1162383Y530917D01*
G01X1163467Y531667D02*
X1165217Y529500D01*
G01X1169400Y529333D02*
X1169233Y529417D01*
Y529583D01*
X1169400Y529667D01*
X1169567Y529583D01*
Y529417D01*
X1169400Y529333D01*
G01X1020417Y542667D02*
X1020917Y543167D01*
X1021500Y543417D01*
X1022167Y543500D01*
X1023000Y543333D01*
X1023583Y542917D01*
X1023750Y542417D01*
X1023667Y541917D01*
X1023333Y541500D01*
X1021667Y540667D01*
X1020917Y540083D01*
X1020417Y539250D01*
X1020250Y538500D01*
X1023750D01*
G01X1027600Y538333D02*
X1027433Y538417D01*
Y538583D01*
X1027600Y538667D01*
X1027767Y538583D01*
Y538417D01*
X1027600Y538333D01*
G01X1033200Y543500D02*
Y538500D01*
G01X1031283Y543500D02*
X1035117D01*
G01X1037383Y538500D02*
Y543500D01*
G01Y541083D02*
X1037800Y541500D01*
X1038217Y541750D01*
X1038883Y541833D01*
X1039383Y541750D01*
X1039967Y541417D01*
X1040217Y540917D01*
Y538500D01*
G01X1043150Y540750D02*
X1045817D01*
X1045567Y541333D01*
X1045150Y541667D01*
X1044567Y541833D01*
X1043983Y541750D01*
X1043483Y541500D01*
X1043150Y540917D01*
X1042983Y540417D01*
Y539917D01*
X1043150Y539417D01*
X1043567Y538917D01*
X1044067Y538583D01*
X1044650Y538500D01*
X1045233Y538667D01*
X1045817Y539167D01*
G01X1054350Y539083D02*
X1054767Y538750D01*
X1055350Y538500D01*
X1055850D01*
X1056350Y538667D01*
X1056683Y538917D01*
X1056850Y539250D01*
X1056767Y539750D01*
X1056433Y540000D01*
X1054933Y540500D01*
X1054600Y541083D01*
X1054767Y541500D01*
X1055100Y541750D01*
X1055600Y541833D01*
X1056100Y541750D01*
X1056600Y541500D01*
G01X1061200Y541833D02*
Y538500D01*
G01Y543167D02*
X1061033Y543250D01*
Y543417D01*
X1061200Y543500D01*
X1061367Y543417D01*
Y543250D01*
X1061200Y543167D01*
G01X1068300Y543500D02*
Y538500D01*
G01Y539250D02*
X1067967Y538833D01*
X1067467Y538583D01*
X1066883Y538500D01*
X1066217Y538667D01*
X1065717Y539083D01*
X1065383Y539583D01*
X1065300Y540167D01*
X1065383Y540750D01*
X1065717Y541250D01*
X1066217Y541667D01*
X1066883Y541833D01*
X1067467Y541750D01*
X1067883Y541583D01*
X1068300Y541250D01*
G01X1071150Y540750D02*
X1073817D01*
X1073567Y541333D01*
X1073150Y541667D01*
X1072567Y541833D01*
X1071983Y541750D01*
X1071483Y541500D01*
X1071150Y540917D01*
X1070983Y540417D01*
Y539917D01*
X1071150Y539417D01*
X1071567Y538917D01*
X1072067Y538583D01*
X1072650Y538500D01*
X1073233Y538667D01*
X1073817Y539167D01*
G01X1081517Y541833D02*
X1082517Y538500D01*
X1083600Y541833D01*
X1084683Y538500D01*
X1085683Y541833D01*
G01X1089200D02*
Y538500D01*
G01Y543167D02*
X1089033Y543250D01*
Y543417D01*
X1089200Y543500D01*
X1089367Y543417D01*
Y543250D01*
X1089200Y543167D01*
G01X1094800Y543500D02*
Y538500D01*
G01X1093633Y541833D02*
X1095967D01*
G01X1098983Y538500D02*
Y543500D01*
G01Y541083D02*
X1099400Y541500D01*
X1099817Y541750D01*
X1100483Y541833D01*
X1100983Y541750D01*
X1101567Y541417D01*
X1101817Y540917D01*
Y538500D01*
G01X1110350Y539083D02*
X1110767Y538750D01*
X1111350Y538500D01*
X1111850D01*
X1112350Y538667D01*
X1112683Y538917D01*
X1112850Y539250D01*
X1112767Y539750D01*
X1112433Y540000D01*
X1110933Y540500D01*
X1110600Y541083D01*
X1110767Y541500D01*
X1111100Y541750D01*
X1111600Y541833D01*
X1112100Y541750D01*
X1112600Y541500D01*
G01X1117200Y538500D02*
X1116700Y538583D01*
X1116200Y538917D01*
X1115867Y539500D01*
X1115700Y540167D01*
X1115867Y540833D01*
X1116200Y541417D01*
X1116700Y541750D01*
X1117200Y541833D01*
X1117700Y541750D01*
X1118200Y541417D01*
X1118533Y540833D01*
X1118617Y540167D01*
X1118533Y539500D01*
X1118200Y538917D01*
X1117700Y538583D01*
X1117200Y538500D01*
G01X1122800D02*
Y543500D01*
G01X1129900D02*
Y538500D01*
G01Y539250D02*
X1129567Y538833D01*
X1129067Y538583D01*
X1128483Y538500D01*
X1127817Y538667D01*
X1127317Y539083D01*
X1126983Y539583D01*
X1126900Y540167D01*
X1126983Y540750D01*
X1127317Y541250D01*
X1127817Y541667D01*
X1128483Y541833D01*
X1129067Y541750D01*
X1129483Y541583D01*
X1129900Y541250D01*
G01X1132750Y540750D02*
X1135417D01*
X1135167Y541333D01*
X1134750Y541667D01*
X1134167Y541833D01*
X1133583Y541750D01*
X1133083Y541500D01*
X1132750Y540917D01*
X1132583Y540417D01*
Y539917D01*
X1132750Y539417D01*
X1133167Y538917D01*
X1133667Y538583D01*
X1134250Y538500D01*
X1134833Y538667D01*
X1135417Y539167D01*
G01X1138433Y538500D02*
Y541833D01*
G01Y541167D02*
X1138850Y541500D01*
X1139267Y541750D01*
X1139850Y541833D01*
X1140267Y541750D01*
X1140767Y541500D01*
G01X1148300Y538500D02*
Y541833D01*
G01Y540917D02*
X1148550Y541333D01*
X1148967Y541667D01*
X1149550Y541833D01*
X1150133Y541667D01*
X1150550Y541333D01*
X1150800Y540917D01*
Y538500D01*
G01Y540917D02*
X1151050Y541333D01*
X1151467Y541667D01*
X1152050Y541833D01*
X1152633Y541667D01*
X1153050Y541333D01*
X1153300Y540833D01*
Y538500D01*
G01X1157900D02*
Y541833D01*
G01Y541250D02*
X1157567Y541583D01*
X1157067Y541750D01*
X1156483Y541833D01*
X1155900Y541667D01*
X1155400Y541333D01*
X1155067Y540833D01*
X1154900Y540167D01*
X1155067Y539500D01*
X1155400Y539000D01*
X1155900Y538667D01*
X1156483Y538500D01*
X1157067Y538583D01*
X1157567Y538833D01*
X1157900Y539167D01*
G01X1160750Y539083D02*
X1161167Y538750D01*
X1161750Y538500D01*
X1162250D01*
X1162750Y538667D01*
X1163083Y538917D01*
X1163250Y539250D01*
X1163167Y539750D01*
X1162833Y540000D01*
X1161333Y540500D01*
X1161000Y541083D01*
X1161167Y541500D01*
X1161500Y541750D01*
X1162000Y541833D01*
X1162500Y541750D01*
X1163000Y541500D01*
G01X1166183Y538500D02*
Y543500D01*
G01X1168850Y541833D02*
X1166183Y539917D01*
G01X1167267Y540667D02*
X1169017Y538500D01*
G01X1177300Y536833D02*
Y541833D01*
G01Y541083D02*
X1177717Y541500D01*
X1178133Y541750D01*
X1178800Y541833D01*
X1179383Y541750D01*
X1179967Y541333D01*
X1180217Y540750D01*
X1180300Y540167D01*
X1180217Y539583D01*
X1179967Y539000D01*
X1179467Y538667D01*
X1178800Y538500D01*
X1178217Y538583D01*
X1177633Y538833D01*
X1177300Y539167D01*
G01X1185900Y538500D02*
Y541833D01*
G01Y541250D02*
X1185567Y541583D01*
X1185067Y541750D01*
X1184483Y541833D01*
X1183900Y541667D01*
X1183400Y541333D01*
X1183067Y540833D01*
X1182900Y540167D01*
X1183067Y539500D01*
X1183400Y539000D01*
X1183900Y538667D01*
X1184483Y538500D01*
X1185067Y538583D01*
X1185567Y538833D01*
X1185900Y539167D01*
G01X1191500Y543500D02*
Y538500D01*
G01Y539250D02*
X1191167Y538833D01*
X1190667Y538583D01*
X1190083Y538500D01*
X1189417Y538667D01*
X1188917Y539083D01*
X1188583Y539583D01*
X1188500Y540167D01*
X1188583Y540750D01*
X1188917Y541250D01*
X1189417Y541667D01*
X1190083Y541833D01*
X1190667Y541750D01*
X1191083Y541583D01*
X1191500Y541250D01*
G01X1195433Y537583D02*
X1195767Y538667D01*
G01X1206800Y543500D02*
Y538500D01*
G01X1205633Y541833D02*
X1207967D01*
G01X1210983Y538500D02*
Y543500D01*
G01Y541083D02*
X1211400Y541500D01*
X1211817Y541750D01*
X1212483Y541833D01*
X1212983Y541750D01*
X1213567Y541417D01*
X1213817Y540917D01*
Y538500D01*
G01X1216750Y540750D02*
X1219417D01*
X1219167Y541333D01*
X1218750Y541667D01*
X1218167Y541833D01*
X1217583Y541750D01*
X1217083Y541500D01*
X1216750Y540917D01*
X1216583Y540417D01*
Y539917D01*
X1216750Y539417D01*
X1217167Y538917D01*
X1217667Y538583D01*
X1218250Y538500D01*
X1218833Y538667D01*
X1219417Y539167D01*
G01X1230700Y538500D02*
Y541833D01*
G01Y541250D02*
X1230367Y541583D01*
X1229867Y541750D01*
X1229283Y541833D01*
X1228700Y541667D01*
X1228200Y541333D01*
X1227867Y540833D01*
X1227700Y540167D01*
X1227867Y539500D01*
X1228200Y539000D01*
X1228700Y538667D01*
X1229283Y538500D01*
X1229867Y538583D01*
X1230367Y538833D01*
X1230700Y539167D01*
G01X1233383Y538500D02*
Y541833D01*
G01Y541000D02*
X1233717Y541417D01*
X1234217Y541750D01*
X1234883Y541833D01*
X1235467Y541750D01*
X1235967Y541417D01*
X1236217Y540833D01*
Y538500D01*
G01X1238983D02*
Y541833D01*
G01Y541000D02*
X1239317Y541417D01*
X1239817Y541750D01*
X1240483Y541833D01*
X1241067Y541750D01*
X1241567Y541417D01*
X1241817Y540833D01*
Y538500D01*
G01X1244583Y541833D02*
Y539500D01*
X1244917Y538917D01*
X1245417Y538583D01*
X1246000Y538500D01*
X1246583Y538583D01*
X1247083Y538917D01*
X1247417Y539500D01*
G01Y538500D02*
Y541833D01*
G01X1253100Y538500D02*
Y541833D01*
G01Y541250D02*
X1252767Y541583D01*
X1252267Y541750D01*
X1251683Y541833D01*
X1251100Y541667D01*
X1250600Y541333D01*
X1250267Y540833D01*
X1250100Y540167D01*
X1250267Y539500D01*
X1250600Y539000D01*
X1251100Y538667D01*
X1251683Y538500D01*
X1252267Y538583D01*
X1252767Y538833D01*
X1253100Y539167D01*
G01X1257200Y538500D02*
Y543500D01*
G01X1267233Y538500D02*
Y541833D01*
G01Y541167D02*
X1267650Y541500D01*
X1268067Y541750D01*
X1268650Y541833D01*
X1269067Y541750D01*
X1269567Y541500D01*
G01X1274000Y541833D02*
Y538500D01*
G01Y543167D02*
X1273833Y543250D01*
Y543417D01*
X1274000Y543500D01*
X1274167Y543417D01*
Y543250D01*
X1274000Y543167D01*
G01X1278183Y538500D02*
Y541833D01*
G01Y541000D02*
X1278517Y541417D01*
X1279017Y541750D01*
X1279683Y541833D01*
X1280267Y541750D01*
X1280767Y541417D01*
X1281017Y540833D01*
Y538500D01*
G01X1284033Y537250D02*
X1284617Y536917D01*
X1285283Y536833D01*
X1285867Y536917D01*
X1286367Y537333D01*
X1286700Y537917D01*
Y541833D01*
G01Y541167D02*
X1286367Y541500D01*
X1285867Y541750D01*
X1285283Y541833D01*
X1284617Y541667D01*
X1284200Y541333D01*
X1283867Y540750D01*
X1283700Y540167D01*
X1283783Y539667D01*
X1284117Y539083D01*
X1284617Y538667D01*
X1285283Y538500D01*
X1285783Y538583D01*
X1286367Y538917D01*
X1286700Y539250D01*
G01X1295150Y539083D02*
X1295567Y538750D01*
X1296150Y538500D01*
X1296650D01*
X1297150Y538667D01*
X1297483Y538917D01*
X1297650Y539250D01*
X1297567Y539750D01*
X1297233Y540000D01*
X1295733Y540500D01*
X1295400Y541083D01*
X1295567Y541500D01*
X1295900Y541750D01*
X1296400Y541833D01*
X1296900Y541750D01*
X1297400Y541500D01*
G01X1300583Y538500D02*
Y543500D01*
G01Y541083D02*
X1301000Y541500D01*
X1301417Y541750D01*
X1302083Y541833D01*
X1302583Y541750D01*
X1303167Y541417D01*
X1303417Y540917D01*
Y538500D01*
G01X1307600D02*
X1307100Y538583D01*
X1306600Y538917D01*
X1306267Y539500D01*
X1306100Y540167D01*
X1306267Y540833D01*
X1306600Y541417D01*
X1307100Y541750D01*
X1307600Y541833D01*
X1308100Y541750D01*
X1308600Y541417D01*
X1308933Y540833D01*
X1309017Y540167D01*
X1308933Y539500D01*
X1308600Y538917D01*
X1308100Y538583D01*
X1307600Y538500D01*
G01X1311783Y541833D02*
Y539500D01*
X1312117Y538917D01*
X1312617Y538583D01*
X1313200Y538500D01*
X1313783Y538583D01*
X1314283Y538917D01*
X1314617Y539500D01*
G01Y538500D02*
Y541833D01*
G01X1318800Y538500D02*
Y543500D01*
G01X1325900D02*
Y538500D01*
G01Y539250D02*
X1325567Y538833D01*
X1325067Y538583D01*
X1324483Y538500D01*
X1323817Y538667D01*
X1323317Y539083D01*
X1322983Y539583D01*
X1322900Y540167D01*
X1322983Y540750D01*
X1323317Y541250D01*
X1323817Y541667D01*
X1324483Y541833D01*
X1325067Y541750D01*
X1325483Y541583D01*
X1325900Y541250D01*
G01X1032500Y552500D02*
Y557500D01*
G01Y555000D02*
X1032917Y555500D01*
X1033417Y555750D01*
X1033917Y555833D01*
X1034667Y555667D01*
X1035167Y555333D01*
X1035500Y554750D01*
Y554083D01*
X1035333Y553417D01*
X1035000Y552917D01*
X1034417Y552583D01*
X1033917Y552500D01*
X1033417Y552583D01*
X1032917Y552833D01*
X1032500Y553250D01*
G01X1038350Y554750D02*
X1041017D01*
X1040767Y555333D01*
X1040350Y555667D01*
X1039767Y555833D01*
X1039183Y555750D01*
X1038683Y555500D01*
X1038350Y554917D01*
X1038183Y554417D01*
Y553917D01*
X1038350Y553417D01*
X1038767Y552917D01*
X1039267Y552583D01*
X1039850Y552500D01*
X1040433Y552667D01*
X1041017Y553167D01*
G01X1050800Y557500D02*
Y552500D01*
G01X1049633Y555833D02*
X1051967D01*
G01X1055150Y554750D02*
X1057817D01*
X1057567Y555333D01*
X1057150Y555667D01*
X1056567Y555833D01*
X1055983Y555750D01*
X1055483Y555500D01*
X1055150Y554917D01*
X1054983Y554417D01*
Y553917D01*
X1055150Y553417D01*
X1055567Y552917D01*
X1056067Y552583D01*
X1056650Y552500D01*
X1057233Y552667D01*
X1057817Y553167D01*
G01X1060583Y552500D02*
Y555833D01*
G01Y555000D02*
X1060917Y555417D01*
X1061417Y555750D01*
X1062083Y555833D01*
X1062667Y555750D01*
X1063167Y555417D01*
X1063417Y554833D01*
Y552500D01*
G01X1067600Y557500D02*
Y552500D01*
G01X1066433Y555833D02*
X1068767D01*
G01X1071950Y554750D02*
X1074617D01*
X1074367Y555333D01*
X1073950Y555667D01*
X1073367Y555833D01*
X1072783Y555750D01*
X1072283Y555500D01*
X1071950Y554917D01*
X1071783Y554417D01*
Y553917D01*
X1071950Y553417D01*
X1072367Y552917D01*
X1072867Y552583D01*
X1073450Y552500D01*
X1074033Y552667D01*
X1074617Y553167D01*
G01X1080300Y557500D02*
Y552500D01*
G01Y553250D02*
X1079967Y552833D01*
X1079467Y552583D01*
X1078883Y552500D01*
X1078217Y552667D01*
X1077717Y553083D01*
X1077383Y553583D01*
X1077300Y554167D01*
X1077383Y554750D01*
X1077717Y555250D01*
X1078217Y555667D01*
X1078883Y555833D01*
X1079467Y555750D01*
X1079883Y555583D01*
X1080300Y555250D01*
G01X1087917Y555833D02*
X1088917Y552500D01*
X1090000Y555833D01*
X1091083Y552500D01*
X1092083Y555833D01*
G01X1095600D02*
Y552500D01*
G01Y557167D02*
X1095433Y557250D01*
Y557417D01*
X1095600Y557500D01*
X1095767Y557417D01*
Y557250D01*
X1095600Y557167D01*
G01X1101200Y557500D02*
Y552500D01*
G01X1100033Y555833D02*
X1102367D01*
G01X1105383Y552500D02*
Y557500D01*
G01Y555083D02*
X1105800Y555500D01*
X1106217Y555750D01*
X1106883Y555833D01*
X1107383Y555750D01*
X1107967Y555417D01*
X1108217Y554917D01*
Y552500D01*
G01X1116750Y553083D02*
X1117167Y552750D01*
X1117750Y552500D01*
X1118250D01*
X1118750Y552667D01*
X1119083Y552917D01*
X1119250Y553250D01*
X1119167Y553750D01*
X1118833Y554000D01*
X1117333Y554500D01*
X1117000Y555083D01*
X1117167Y555500D01*
X1117500Y555750D01*
X1118000Y555833D01*
X1118500Y555750D01*
X1119000Y555500D01*
G01X1123600Y552500D02*
X1123100Y552583D01*
X1122600Y552917D01*
X1122267Y553500D01*
X1122100Y554167D01*
X1122267Y554833D01*
X1122600Y555417D01*
X1123100Y555750D01*
X1123600Y555833D01*
X1124100Y555750D01*
X1124600Y555417D01*
X1124933Y554833D01*
X1125017Y554167D01*
X1124933Y553500D01*
X1124600Y552917D01*
X1124100Y552583D01*
X1123600Y552500D01*
G01X1129200D02*
Y557500D01*
G01X1136300D02*
Y552500D01*
G01Y553250D02*
X1135967Y552833D01*
X1135467Y552583D01*
X1134883Y552500D01*
X1134217Y552667D01*
X1133717Y553083D01*
X1133383Y553583D01*
X1133300Y554167D01*
X1133383Y554750D01*
X1133717Y555250D01*
X1134217Y555667D01*
X1134883Y555833D01*
X1135467Y555750D01*
X1135883Y555583D01*
X1136300Y555250D01*
G01X1139150Y554750D02*
X1141817D01*
X1141567Y555333D01*
X1141150Y555667D01*
X1140567Y555833D01*
X1139983Y555750D01*
X1139483Y555500D01*
X1139150Y554917D01*
X1138983Y554417D01*
Y553917D01*
X1139150Y553417D01*
X1139567Y552917D01*
X1140067Y552583D01*
X1140650Y552500D01*
X1141233Y552667D01*
X1141817Y553167D01*
G01X1144833Y552500D02*
Y555833D01*
G01Y555167D02*
X1145250Y555500D01*
X1145667Y555750D01*
X1146250Y555833D01*
X1146667Y555750D01*
X1147167Y555500D01*
G01X1154700Y552500D02*
Y555833D01*
G01Y554917D02*
X1154950Y555333D01*
X1155367Y555667D01*
X1155950Y555833D01*
X1156533Y555667D01*
X1156950Y555333D01*
X1157200Y554917D01*
Y552500D01*
G01Y554917D02*
X1157450Y555333D01*
X1157867Y555667D01*
X1158450Y555833D01*
X1159033Y555667D01*
X1159450Y555333D01*
X1159700Y554833D01*
Y552500D01*
G01X1164300D02*
Y555833D01*
G01Y555250D02*
X1163967Y555583D01*
X1163467Y555750D01*
X1162883Y555833D01*
X1162300Y555667D01*
X1161800Y555333D01*
X1161467Y554833D01*
X1161300Y554167D01*
X1161467Y553500D01*
X1161800Y553000D01*
X1162300Y552667D01*
X1162883Y552500D01*
X1163467Y552583D01*
X1163967Y552833D01*
X1164300Y553167D01*
G01X1167150Y553083D02*
X1167567Y552750D01*
X1168150Y552500D01*
X1168650D01*
X1169150Y552667D01*
X1169483Y552917D01*
X1169650Y553250D01*
X1169567Y553750D01*
X1169233Y554000D01*
X1167733Y554500D01*
X1167400Y555083D01*
X1167567Y555500D01*
X1167900Y555750D01*
X1168400Y555833D01*
X1168900Y555750D01*
X1169400Y555500D01*
G01X1172583Y552500D02*
Y557500D01*
G01X1175250Y555833D02*
X1172583Y553917D01*
G01X1173667Y554667D02*
X1175417Y552500D01*
G01X1179600Y552333D02*
X1179433Y552417D01*
Y552583D01*
X1179600Y552667D01*
X1179767Y552583D01*
Y552417D01*
X1179600Y552333D01*
G01X1034000Y566500D02*
Y561500D01*
G01X1032833Y564833D02*
X1035167D01*
G01X1039600Y561500D02*
X1039100Y561583D01*
X1038600Y561917D01*
X1038267Y562500D01*
X1038100Y563167D01*
X1038267Y563833D01*
X1038600Y564417D01*
X1039100Y564750D01*
X1039600Y564833D01*
X1040100Y564750D01*
X1040600Y564417D01*
X1040933Y563833D01*
X1041017Y563167D01*
X1040933Y562500D01*
X1040600Y561917D01*
X1040100Y561583D01*
X1039600Y561500D01*
G01X1049300D02*
Y566500D01*
G01Y564000D02*
X1049717Y564500D01*
X1050217Y564750D01*
X1050717Y564833D01*
X1051467Y564667D01*
X1051967Y564333D01*
X1052300Y563750D01*
Y563083D01*
X1052133Y562417D01*
X1051800Y561917D01*
X1051217Y561583D01*
X1050717Y561500D01*
X1050217Y561583D01*
X1049717Y561833D01*
X1049300Y562250D01*
G01X1055150Y563750D02*
X1057817D01*
X1057567Y564333D01*
X1057150Y564667D01*
X1056567Y564833D01*
X1055983Y564750D01*
X1055483Y564500D01*
X1055150Y563917D01*
X1054983Y563417D01*
Y562917D01*
X1055150Y562417D01*
X1055567Y561917D01*
X1056067Y561583D01*
X1056650Y561500D01*
X1057233Y561667D01*
X1057817Y562167D01*
G01X1068933Y564417D02*
X1068350Y564750D01*
X1067850Y564833D01*
X1067183Y564667D01*
X1066683Y564333D01*
X1066350Y563750D01*
X1066267Y563167D01*
X1066350Y562583D01*
X1066683Y562083D01*
X1067183Y561667D01*
X1067850Y561500D01*
X1068433Y561667D01*
X1068933Y562000D01*
G01X1073200Y561500D02*
X1072700Y561583D01*
X1072200Y561917D01*
X1071867Y562500D01*
X1071700Y563167D01*
X1071867Y563833D01*
X1072200Y564417D01*
X1072700Y564750D01*
X1073200Y564833D01*
X1073700Y564750D01*
X1074200Y564417D01*
X1074533Y563833D01*
X1074617Y563167D01*
X1074533Y562500D01*
X1074200Y561917D01*
X1073700Y561583D01*
X1073200Y561500D01*
G01X1077300Y564833D02*
X1078800Y561500D01*
X1080300Y564833D01*
G01X1083150Y563750D02*
X1085817D01*
X1085567Y564333D01*
X1085150Y564667D01*
X1084567Y564833D01*
X1083983Y564750D01*
X1083483Y564500D01*
X1083150Y563917D01*
X1082983Y563417D01*
Y562917D01*
X1083150Y562417D01*
X1083567Y561917D01*
X1084067Y561583D01*
X1084650Y561500D01*
X1085233Y561667D01*
X1085817Y562167D01*
G01X1088833Y561500D02*
Y564833D01*
G01Y564167D02*
X1089250Y564500D01*
X1089667Y564750D01*
X1090250Y564833D01*
X1090667Y564750D01*
X1091167Y564500D01*
G01X1094350Y563750D02*
X1097017D01*
X1096767Y564333D01*
X1096350Y564667D01*
X1095767Y564833D01*
X1095183Y564750D01*
X1094683Y564500D01*
X1094350Y563917D01*
X1094183Y563417D01*
Y562917D01*
X1094350Y562417D01*
X1094767Y561917D01*
X1095267Y561583D01*
X1095850Y561500D01*
X1096433Y561667D01*
X1097017Y562167D01*
G01X1102700Y566500D02*
Y561500D01*
G01Y562250D02*
X1102367Y561833D01*
X1101867Y561583D01*
X1101283Y561500D01*
X1100617Y561667D01*
X1100117Y562083D01*
X1099783Y562583D01*
X1099700Y563167D01*
X1099783Y563750D01*
X1100117Y564250D01*
X1100617Y564667D01*
X1101283Y564833D01*
X1101867Y564750D01*
X1102283Y564583D01*
X1102700Y564250D01*
G01X1110900Y561500D02*
Y566500D01*
G01Y564000D02*
X1111317Y564500D01*
X1111817Y564750D01*
X1112317Y564833D01*
X1113067Y564667D01*
X1113567Y564333D01*
X1113900Y563750D01*
Y563083D01*
X1113733Y562417D01*
X1113400Y561917D01*
X1112817Y561583D01*
X1112317Y561500D01*
X1111817Y561583D01*
X1111317Y561833D01*
X1110900Y562250D01*
G01X1116250Y560000D02*
X1116750Y559833D01*
X1117417Y560000D01*
X1117833Y560333D01*
X1118167Y560750D01*
X1118667Y562083D01*
X1119750Y564833D01*
G01X1117083D02*
X1118667Y562083D01*
G01X1127950D02*
X1128367Y561750D01*
X1128950Y561500D01*
X1129450D01*
X1129950Y561667D01*
X1130283Y561917D01*
X1130450Y562250D01*
X1130367Y562750D01*
X1130033Y563000D01*
X1128533Y563500D01*
X1128200Y564083D01*
X1128367Y564500D01*
X1128700Y564750D01*
X1129200Y564833D01*
X1129700Y564750D01*
X1130200Y564500D01*
G01X1134800Y561500D02*
X1134300Y561583D01*
X1133800Y561917D01*
X1133467Y562500D01*
X1133300Y563167D01*
X1133467Y563833D01*
X1133800Y564417D01*
X1134300Y564750D01*
X1134800Y564833D01*
X1135300Y564750D01*
X1135800Y564417D01*
X1136133Y563833D01*
X1136217Y563167D01*
X1136133Y562500D01*
X1135800Y561917D01*
X1135300Y561583D01*
X1134800Y561500D01*
G01X1140400D02*
Y566500D01*
G01X1147500D02*
Y561500D01*
G01Y562250D02*
X1147167Y561833D01*
X1146667Y561583D01*
X1146083Y561500D01*
X1145417Y561667D01*
X1144917Y562083D01*
X1144583Y562583D01*
X1144500Y563167D01*
X1144583Y563750D01*
X1144917Y564250D01*
X1145417Y564667D01*
X1146083Y564833D01*
X1146667Y564750D01*
X1147083Y564583D01*
X1147500Y564250D01*
G01X1150350Y563750D02*
X1153017D01*
X1152767Y564333D01*
X1152350Y564667D01*
X1151767Y564833D01*
X1151183Y564750D01*
X1150683Y564500D01*
X1150350Y563917D01*
X1150183Y563417D01*
Y562917D01*
X1150350Y562417D01*
X1150767Y561917D01*
X1151267Y561583D01*
X1151850Y561500D01*
X1152433Y561667D01*
X1153017Y562167D01*
G01X1156033Y561500D02*
Y564833D01*
G01Y564167D02*
X1156450Y564500D01*
X1156867Y564750D01*
X1157450Y564833D01*
X1157867Y564750D01*
X1158367Y564500D01*
G01X1165900Y561500D02*
Y564833D01*
G01Y563917D02*
X1166150Y564333D01*
X1166567Y564667D01*
X1167150Y564833D01*
X1167733Y564667D01*
X1168150Y564333D01*
X1168400Y563917D01*
Y561500D01*
G01Y563917D02*
X1168650Y564333D01*
X1169067Y564667D01*
X1169650Y564833D01*
X1170233Y564667D01*
X1170650Y564333D01*
X1170900Y563833D01*
Y561500D01*
G01X1175500D02*
Y564833D01*
G01Y564250D02*
X1175167Y564583D01*
X1174667Y564750D01*
X1174083Y564833D01*
X1173500Y564667D01*
X1173000Y564333D01*
X1172667Y563833D01*
X1172500Y563167D01*
X1172667Y562500D01*
X1173000Y562000D01*
X1173500Y561667D01*
X1174083Y561500D01*
X1174667Y561583D01*
X1175167Y561833D01*
X1175500Y562167D01*
G01X1178350Y562083D02*
X1178767Y561750D01*
X1179350Y561500D01*
X1179850D01*
X1180350Y561667D01*
X1180683Y561917D01*
X1180850Y562250D01*
X1180767Y562750D01*
X1180433Y563000D01*
X1178933Y563500D01*
X1178600Y564083D01*
X1178767Y564500D01*
X1179100Y564750D01*
X1179600Y564833D01*
X1180100Y564750D01*
X1180600Y564500D01*
G01X1183783Y561500D02*
Y566500D01*
G01X1186450Y564833D02*
X1183783Y562917D01*
G01X1184867Y563667D02*
X1186617Y561500D01*
G01X1197900D02*
Y564833D01*
G01Y564250D02*
X1197567Y564583D01*
X1197067Y564750D01*
X1196483Y564833D01*
X1195900Y564667D01*
X1195400Y564333D01*
X1195067Y563833D01*
X1194900Y563167D01*
X1195067Y562500D01*
X1195400Y562000D01*
X1195900Y561667D01*
X1196483Y561500D01*
X1197067Y561583D01*
X1197567Y561833D01*
X1197900Y562167D01*
G01X1200583Y561500D02*
Y564833D01*
G01Y564000D02*
X1200917Y564417D01*
X1201417Y564750D01*
X1202083Y564833D01*
X1202667Y564750D01*
X1203167Y564417D01*
X1203417Y563833D01*
Y561500D01*
G01X1209100Y566500D02*
Y561500D01*
G01Y562250D02*
X1208767Y561833D01*
X1208267Y561583D01*
X1207683Y561500D01*
X1207017Y561667D01*
X1206517Y562083D01*
X1206183Y562583D01*
X1206100Y563167D01*
X1206183Y563750D01*
X1206517Y564250D01*
X1207017Y564667D01*
X1207683Y564833D01*
X1208267Y564750D01*
X1208683Y564583D01*
X1209100Y564250D01*
G01X1217383Y561500D02*
Y566500D01*
G01Y564083D02*
X1217800Y564500D01*
X1218217Y564750D01*
X1218883Y564833D01*
X1219383Y564750D01*
X1219967Y564417D01*
X1220217Y563917D01*
Y561500D01*
G01X1224400D02*
X1223900Y561583D01*
X1223400Y561917D01*
X1223067Y562500D01*
X1222900Y563167D01*
X1223067Y563833D01*
X1223400Y564417D01*
X1223900Y564750D01*
X1224400Y564833D01*
X1224900Y564750D01*
X1225400Y564417D01*
X1225733Y563833D01*
X1225817Y563167D01*
X1225733Y562500D01*
X1225400Y561917D01*
X1224900Y561583D01*
X1224400Y561500D01*
G01X1230000D02*
Y566500D01*
G01X1234350Y563750D02*
X1237017D01*
X1236767Y564333D01*
X1236350Y564667D01*
X1235767Y564833D01*
X1235183Y564750D01*
X1234683Y564500D01*
X1234350Y563917D01*
X1234183Y563417D01*
Y562917D01*
X1234350Y562417D01*
X1234767Y561917D01*
X1235267Y561583D01*
X1235850Y561500D01*
X1236433Y561667D01*
X1237017Y562167D01*
G01X1248300Y561500D02*
Y564833D01*
G01Y564250D02*
X1247967Y564583D01*
X1247467Y564750D01*
X1246883Y564833D01*
X1246300Y564667D01*
X1245800Y564333D01*
X1245467Y563833D01*
X1245300Y563167D01*
X1245467Y562500D01*
X1245800Y562000D01*
X1246300Y561667D01*
X1246883Y561500D01*
X1247467Y561583D01*
X1247967Y561833D01*
X1248300Y562167D01*
G01X1252400Y561500D02*
Y566500D01*
G01X1256750Y562083D02*
X1257167Y561750D01*
X1257750Y561500D01*
X1258250D01*
X1258750Y561667D01*
X1259083Y561917D01*
X1259250Y562250D01*
X1259167Y562750D01*
X1258833Y563000D01*
X1257333Y563500D01*
X1257000Y564083D01*
X1257167Y564500D01*
X1257500Y564750D01*
X1258000Y564833D01*
X1258500Y564750D01*
X1259000Y564500D01*
G01X1263600Y561500D02*
X1263100Y561583D01*
X1262600Y561917D01*
X1262267Y562500D01*
X1262100Y563167D01*
X1262267Y563833D01*
X1262600Y564417D01*
X1263100Y564750D01*
X1263600Y564833D01*
X1264100Y564750D01*
X1264600Y564417D01*
X1264933Y563833D01*
X1265017Y563167D01*
X1264933Y562500D01*
X1264600Y561917D01*
X1264100Y561583D01*
X1263600Y561500D01*
G01X1273383D02*
Y564833D01*
G01Y564000D02*
X1273717Y564417D01*
X1274217Y564750D01*
X1274883Y564833D01*
X1275467Y564750D01*
X1275967Y564417D01*
X1276217Y563833D01*
Y561500D01*
G01X1279150Y563750D02*
X1281817D01*
X1281567Y564333D01*
X1281150Y564667D01*
X1280567Y564833D01*
X1279983Y564750D01*
X1279483Y564500D01*
X1279150Y563917D01*
X1278983Y563417D01*
Y562917D01*
X1279150Y562417D01*
X1279567Y561917D01*
X1280067Y561583D01*
X1280650Y561500D01*
X1281233Y561667D01*
X1281817Y562167D01*
G01X1284750Y563750D02*
X1287417D01*
X1287167Y564333D01*
X1286750Y564667D01*
X1286167Y564833D01*
X1285583Y564750D01*
X1285083Y564500D01*
X1284750Y563917D01*
X1284583Y563417D01*
Y562917D01*
X1284750Y562417D01*
X1285167Y561917D01*
X1285667Y561583D01*
X1286250Y561500D01*
X1286833Y561667D01*
X1287417Y562167D01*
G01X1293100Y566500D02*
Y561500D01*
G01Y562250D02*
X1292767Y561833D01*
X1292267Y561583D01*
X1291683Y561500D01*
X1291017Y561667D01*
X1290517Y562083D01*
X1290183Y562583D01*
X1290100Y563167D01*
X1290183Y563750D01*
X1290517Y564250D01*
X1291017Y564667D01*
X1291683Y564833D01*
X1292267Y564750D01*
X1292683Y564583D01*
X1293100Y564250D01*
G01X1302800Y566500D02*
Y561500D01*
G01X1301633Y564833D02*
X1303967D01*
G01X1308400Y561500D02*
X1307900Y561583D01*
X1307400Y561917D01*
X1307067Y562500D01*
X1306900Y563167D01*
X1307067Y563833D01*
X1307400Y564417D01*
X1307900Y564750D01*
X1308400Y564833D01*
X1308900Y564750D01*
X1309400Y564417D01*
X1309733Y563833D01*
X1309817Y563167D01*
X1309733Y562500D01*
X1309400Y561917D01*
X1308900Y561583D01*
X1308400Y561500D01*
G01X1022000Y569500D02*
Y574500D01*
X1021000Y573500D01*
G01Y569500D02*
X1023000D01*
G01X1027600Y569333D02*
X1027433Y569417D01*
Y569583D01*
X1027600Y569667D01*
X1027767Y569583D01*
Y569417D01*
X1027600Y569333D01*
G01X1033200Y574500D02*
Y569500D01*
G01X1031283Y574500D02*
X1035117D01*
G01X1037383Y569500D02*
Y574500D01*
G01Y572083D02*
X1037800Y572500D01*
X1038217Y572750D01*
X1038883Y572833D01*
X1039383Y572750D01*
X1039967Y572417D01*
X1040217Y571917D01*
Y569500D01*
G01X1043150Y571750D02*
X1045817D01*
X1045567Y572333D01*
X1045150Y572667D01*
X1044567Y572833D01*
X1043983Y572750D01*
X1043483Y572500D01*
X1043150Y571917D01*
X1042983Y571417D01*
Y570917D01*
X1043150Y570417D01*
X1043567Y569917D01*
X1044067Y569583D01*
X1044650Y569500D01*
X1045233Y569667D01*
X1045817Y570167D01*
G01X1054350Y570083D02*
X1054767Y569750D01*
X1055350Y569500D01*
X1055850D01*
X1056350Y569667D01*
X1056683Y569917D01*
X1056850Y570250D01*
X1056767Y570750D01*
X1056433Y571000D01*
X1054933Y571500D01*
X1054600Y572083D01*
X1054767Y572500D01*
X1055100Y572750D01*
X1055600Y572833D01*
X1056100Y572750D01*
X1056600Y572500D01*
G01X1061200Y572833D02*
Y569500D01*
G01Y574167D02*
X1061033Y574250D01*
Y574417D01*
X1061200Y574500D01*
X1061367Y574417D01*
Y574250D01*
X1061200Y574167D01*
G01X1068300Y574500D02*
Y569500D01*
G01Y570250D02*
X1067967Y569833D01*
X1067467Y569583D01*
X1066883Y569500D01*
X1066217Y569667D01*
X1065717Y570083D01*
X1065383Y570583D01*
X1065300Y571167D01*
X1065383Y571750D01*
X1065717Y572250D01*
X1066217Y572667D01*
X1066883Y572833D01*
X1067467Y572750D01*
X1067883Y572583D01*
X1068300Y572250D01*
G01X1071150Y571750D02*
X1073817D01*
X1073567Y572333D01*
X1073150Y572667D01*
X1072567Y572833D01*
X1071983Y572750D01*
X1071483Y572500D01*
X1071150Y571917D01*
X1070983Y571417D01*
Y570917D01*
X1071150Y570417D01*
X1071567Y569917D01*
X1072067Y569583D01*
X1072650Y569500D01*
X1073233Y569667D01*
X1073817Y570167D01*
G01X1081517Y572833D02*
X1082517Y569500D01*
X1083600Y572833D01*
X1084683Y569500D01*
X1085683Y572833D01*
G01X1089200D02*
Y569500D01*
G01Y574167D02*
X1089033Y574250D01*
Y574417D01*
X1089200Y574500D01*
X1089367Y574417D01*
Y574250D01*
X1089200Y574167D01*
G01X1094800Y574500D02*
Y569500D01*
G01X1093633Y572833D02*
X1095967D01*
G01X1098983Y569500D02*
Y574500D01*
G01Y572083D02*
X1099400Y572500D01*
X1099817Y572750D01*
X1100483Y572833D01*
X1100983Y572750D01*
X1101567Y572417D01*
X1101817Y571917D01*
Y569500D01*
G01X1106000D02*
X1105500Y569583D01*
X1105000Y569917D01*
X1104667Y570500D01*
X1104500Y571167D01*
X1104667Y571833D01*
X1105000Y572417D01*
X1105500Y572750D01*
X1106000Y572833D01*
X1106500Y572750D01*
X1107000Y572417D01*
X1107333Y571833D01*
X1107417Y571167D01*
X1107333Y570500D01*
X1107000Y569917D01*
X1106500Y569583D01*
X1106000Y569500D01*
G01X1110183Y572833D02*
Y570500D01*
X1110517Y569917D01*
X1111017Y569583D01*
X1111600Y569500D01*
X1112183Y569583D01*
X1112683Y569917D01*
X1113017Y570500D01*
G01Y569500D02*
Y572833D01*
G01X1117200Y574500D02*
Y569500D01*
G01X1116033Y572833D02*
X1118367D01*
G01X1127150Y570083D02*
X1127567Y569750D01*
X1128150Y569500D01*
X1128650D01*
X1129150Y569667D01*
X1129483Y569917D01*
X1129650Y570250D01*
X1129567Y570750D01*
X1129233Y571000D01*
X1127733Y571500D01*
X1127400Y572083D01*
X1127567Y572500D01*
X1127900Y572750D01*
X1128400Y572833D01*
X1128900Y572750D01*
X1129400Y572500D01*
G01X1134000Y569500D02*
X1133500Y569583D01*
X1133000Y569917D01*
X1132667Y570500D01*
X1132500Y571167D01*
X1132667Y571833D01*
X1133000Y572417D01*
X1133500Y572750D01*
X1134000Y572833D01*
X1134500Y572750D01*
X1135000Y572417D01*
X1135333Y571833D01*
X1135417Y571167D01*
X1135333Y570500D01*
X1135000Y569917D01*
X1134500Y569583D01*
X1134000Y569500D01*
G01X1139600D02*
Y574500D01*
G01X1146700D02*
Y569500D01*
G01Y570250D02*
X1146367Y569833D01*
X1145867Y569583D01*
X1145283Y569500D01*
X1144617Y569667D01*
X1144117Y570083D01*
X1143783Y570583D01*
X1143700Y571167D01*
X1143783Y571750D01*
X1144117Y572250D01*
X1144617Y572667D01*
X1145283Y572833D01*
X1145867Y572750D01*
X1146283Y572583D01*
X1146700Y572250D01*
G01X1149550Y571750D02*
X1152217D01*
X1151967Y572333D01*
X1151550Y572667D01*
X1150967Y572833D01*
X1150383Y572750D01*
X1149883Y572500D01*
X1149550Y571917D01*
X1149383Y571417D01*
Y570917D01*
X1149550Y570417D01*
X1149967Y569917D01*
X1150467Y569583D01*
X1151050Y569500D01*
X1151633Y569667D01*
X1152217Y570167D01*
G01X1155233Y569500D02*
Y572833D01*
G01Y572167D02*
X1155650Y572500D01*
X1156067Y572750D01*
X1156650Y572833D01*
X1157067Y572750D01*
X1157567Y572500D01*
G01X1165100Y569500D02*
Y572833D01*
G01Y571917D02*
X1165350Y572333D01*
X1165767Y572667D01*
X1166350Y572833D01*
X1166933Y572667D01*
X1167350Y572333D01*
X1167600Y571917D01*
Y569500D01*
G01Y571917D02*
X1167850Y572333D01*
X1168267Y572667D01*
X1168850Y572833D01*
X1169433Y572667D01*
X1169850Y572333D01*
X1170100Y571833D01*
Y569500D01*
G01X1174700D02*
Y572833D01*
G01Y572250D02*
X1174367Y572583D01*
X1173867Y572750D01*
X1173283Y572833D01*
X1172700Y572667D01*
X1172200Y572333D01*
X1171867Y571833D01*
X1171700Y571167D01*
X1171867Y570500D01*
X1172200Y570000D01*
X1172700Y569667D01*
X1173283Y569500D01*
X1173867Y569583D01*
X1174367Y569833D01*
X1174700Y570167D01*
G01X1177550Y570083D02*
X1177967Y569750D01*
X1178550Y569500D01*
X1179050D01*
X1179550Y569667D01*
X1179883Y569917D01*
X1180050Y570250D01*
X1179967Y570750D01*
X1179633Y571000D01*
X1178133Y571500D01*
X1177800Y572083D01*
X1177967Y572500D01*
X1178300Y572750D01*
X1178800Y572833D01*
X1179300Y572750D01*
X1179800Y572500D01*
G01X1182983Y569500D02*
Y574500D01*
G01X1185650Y572833D02*
X1182983Y570917D01*
G01X1184067Y571667D02*
X1185817Y569500D01*
G01X1194100Y567833D02*
Y572833D01*
G01Y572083D02*
X1194517Y572500D01*
X1194933Y572750D01*
X1195600Y572833D01*
X1196183Y572750D01*
X1196767Y572333D01*
X1197017Y571750D01*
X1197100Y571167D01*
X1197017Y570583D01*
X1196767Y570000D01*
X1196267Y569667D01*
X1195600Y569500D01*
X1195017Y569583D01*
X1194433Y569833D01*
X1194100Y570167D01*
G01X1202700Y569500D02*
Y572833D01*
G01Y572250D02*
X1202367Y572583D01*
X1201867Y572750D01*
X1201283Y572833D01*
X1200700Y572667D01*
X1200200Y572333D01*
X1199867Y571833D01*
X1199700Y571167D01*
X1199867Y570500D01*
X1200200Y570000D01*
X1200700Y569667D01*
X1201283Y569500D01*
X1201867Y569583D01*
X1202367Y569833D01*
X1202700Y570167D01*
G01X1208300Y574500D02*
Y569500D01*
G01Y570250D02*
X1207967Y569833D01*
X1207467Y569583D01*
X1206883Y569500D01*
X1206217Y569667D01*
X1205717Y570083D01*
X1205383Y570583D01*
X1205300Y571167D01*
X1205383Y571750D01*
X1205717Y572250D01*
X1206217Y572667D01*
X1206883Y572833D01*
X1207467Y572750D01*
X1207883Y572583D01*
X1208300Y572250D01*
G01X1217833Y568583D02*
X1218167Y569667D01*
G01X1230700Y569500D02*
Y572833D01*
G01Y572250D02*
X1230367Y572583D01*
X1229867Y572750D01*
X1229283Y572833D01*
X1228700Y572667D01*
X1228200Y572333D01*
X1227867Y571833D01*
X1227700Y571167D01*
X1227867Y570500D01*
X1228200Y570000D01*
X1228700Y569667D01*
X1229283Y569500D01*
X1229867Y569583D01*
X1230367Y569833D01*
X1230700Y570167D01*
G01X1233383Y569500D02*
Y572833D01*
G01Y572000D02*
X1233717Y572417D01*
X1234217Y572750D01*
X1234883Y572833D01*
X1235467Y572750D01*
X1235967Y572417D01*
X1236217Y571833D01*
Y569500D01*
G01X1238983D02*
Y572833D01*
G01Y572000D02*
X1239317Y572417D01*
X1239817Y572750D01*
X1240483Y572833D01*
X1241067Y572750D01*
X1241567Y572417D01*
X1241817Y571833D01*
Y569500D01*
G01X1244583Y572833D02*
Y570500D01*
X1244917Y569917D01*
X1245417Y569583D01*
X1246000Y569500D01*
X1246583Y569583D01*
X1247083Y569917D01*
X1247417Y570500D01*
G01Y569500D02*
Y572833D01*
G01X1253100Y569500D02*
Y572833D01*
G01Y572250D02*
X1252767Y572583D01*
X1252267Y572750D01*
X1251683Y572833D01*
X1251100Y572667D01*
X1250600Y572333D01*
X1250267Y571833D01*
X1250100Y571167D01*
X1250267Y570500D01*
X1250600Y570000D01*
X1251100Y569667D01*
X1251683Y569500D01*
X1252267Y569583D01*
X1252767Y569833D01*
X1253100Y570167D01*
G01X1257200Y569500D02*
Y574500D01*
G01X1267233Y569500D02*
Y572833D01*
G01Y572167D02*
X1267650Y572500D01*
X1268067Y572750D01*
X1268650Y572833D01*
X1269067Y572750D01*
X1269567Y572500D01*
G01X1274000Y572833D02*
Y569500D01*
G01Y574167D02*
X1273833Y574250D01*
Y574417D01*
X1274000Y574500D01*
X1274167Y574417D01*
Y574250D01*
X1274000Y574167D01*
G01X1278183Y569500D02*
Y572833D01*
G01Y572000D02*
X1278517Y572417D01*
X1279017Y572750D01*
X1279683Y572833D01*
X1280267Y572750D01*
X1280767Y572417D01*
X1281017Y571833D01*
Y569500D01*
G01X1284033Y568250D02*
X1284617Y567917D01*
X1285283Y567833D01*
X1285867Y567917D01*
X1286367Y568333D01*
X1286700Y568917D01*
Y572833D01*
G01Y572167D02*
X1286367Y572500D01*
X1285867Y572750D01*
X1285283Y572833D01*
X1284617Y572667D01*
X1284200Y572333D01*
X1283867Y571750D01*
X1283700Y571167D01*
X1283783Y570667D01*
X1284117Y570083D01*
X1284617Y569667D01*
X1285283Y569500D01*
X1285783Y569583D01*
X1286367Y569917D01*
X1286700Y570250D01*
G01X1294983Y569500D02*
Y572833D01*
G01Y572000D02*
X1295317Y572417D01*
X1295817Y572750D01*
X1296483Y572833D01*
X1297067Y572750D01*
X1297567Y572417D01*
X1297817Y571833D01*
Y569500D01*
G01X1300750Y571750D02*
X1303417D01*
X1303167Y572333D01*
X1302750Y572667D01*
X1302167Y572833D01*
X1301583Y572750D01*
X1301083Y572500D01*
X1300750Y571917D01*
X1300583Y571417D01*
Y570917D01*
X1300750Y570417D01*
X1301167Y569917D01*
X1301667Y569583D01*
X1302250Y569500D01*
X1302833Y569667D01*
X1303417Y570167D01*
G01X1306350Y571750D02*
X1309017D01*
X1308767Y572333D01*
X1308350Y572667D01*
X1307767Y572833D01*
X1307183Y572750D01*
X1306683Y572500D01*
X1306350Y571917D01*
X1306183Y571417D01*
Y570917D01*
X1306350Y570417D01*
X1306767Y569917D01*
X1307267Y569583D01*
X1307850Y569500D01*
X1308433Y569667D01*
X1309017Y570167D01*
G01X1314700Y574500D02*
Y569500D01*
G01Y570250D02*
X1314367Y569833D01*
X1313867Y569583D01*
X1313283Y569500D01*
X1312617Y569667D01*
X1312117Y570083D01*
X1311783Y570583D01*
X1311700Y571167D01*
X1311783Y571750D01*
X1312117Y572250D01*
X1312617Y572667D01*
X1313283Y572833D01*
X1313867Y572750D01*
X1314283Y572583D01*
X1314700Y572250D01*
G01X1012083Y730500D02*
Y733833D01*
G01Y733000D02*
X1012417Y733417D01*
X1012917Y733750D01*
X1013583Y733833D01*
X1014167Y733750D01*
X1014667Y733417D01*
X1014917Y732833D01*
Y730500D01*
G01X1019100D02*
X1018600Y730583D01*
X1018100Y730917D01*
X1017767Y731500D01*
X1017600Y732167D01*
X1017767Y732833D01*
X1018100Y733417D01*
X1018600Y733750D01*
X1019100Y733833D01*
X1019600Y733750D01*
X1020100Y733417D01*
X1020433Y732833D01*
X1020517Y732167D01*
X1020433Y731500D01*
X1020100Y730917D01*
X1019600Y730583D01*
X1019100Y730500D01*
G01X1028800Y728833D02*
Y733833D01*
G01Y733083D02*
X1029217Y733500D01*
X1029633Y733750D01*
X1030300Y733833D01*
X1030883Y733750D01*
X1031467Y733333D01*
X1031717Y732750D01*
X1031800Y732167D01*
X1031717Y731583D01*
X1031467Y731000D01*
X1030967Y730667D01*
X1030300Y730500D01*
X1029717Y730583D01*
X1029133Y730833D01*
X1028800Y731167D01*
G01X1035900Y730500D02*
Y735500D01*
G01X1040083Y733833D02*
Y731500D01*
X1040417Y730917D01*
X1040917Y730583D01*
X1041500Y730500D01*
X1042083Y730583D01*
X1042583Y730917D01*
X1042917Y731500D01*
G01Y730500D02*
Y733833D01*
G01X1045933Y729250D02*
X1046517Y728917D01*
X1047183Y728833D01*
X1047767Y728917D01*
X1048267Y729333D01*
X1048600Y729917D01*
Y733833D01*
G01Y733167D02*
X1048267Y733500D01*
X1047767Y733750D01*
X1047183Y733833D01*
X1046517Y733667D01*
X1046100Y733333D01*
X1045767Y732750D01*
X1045600Y732167D01*
X1045683Y731667D01*
X1046017Y731083D01*
X1046517Y730667D01*
X1047183Y730500D01*
X1047683Y730583D01*
X1048267Y730917D01*
X1048600Y731250D01*
G01X1051533Y729250D02*
X1052117Y728917D01*
X1052783Y728833D01*
X1053367Y728917D01*
X1053867Y729333D01*
X1054200Y729917D01*
Y733833D01*
G01Y733167D02*
X1053867Y733500D01*
X1053367Y733750D01*
X1052783Y733833D01*
X1052117Y733667D01*
X1051700Y733333D01*
X1051367Y732750D01*
X1051200Y732167D01*
X1051283Y731667D01*
X1051617Y731083D01*
X1052117Y730667D01*
X1052783Y730500D01*
X1053283Y730583D01*
X1053867Y730917D01*
X1054200Y731250D01*
G01X1058300Y733833D02*
Y730500D01*
G01Y735167D02*
X1058133Y735250D01*
Y735417D01*
X1058300Y735500D01*
X1058467Y735417D01*
Y735250D01*
X1058300Y735167D01*
G01X1062483Y730500D02*
Y733833D01*
G01Y733000D02*
X1062817Y733417D01*
X1063317Y733750D01*
X1063983Y733833D01*
X1064567Y733750D01*
X1065067Y733417D01*
X1065317Y732833D01*
Y730500D01*
G01X1068333Y729250D02*
X1068917Y728917D01*
X1069583Y728833D01*
X1070167Y728917D01*
X1070667Y729333D01*
X1071000Y729917D01*
Y733833D01*
G01Y733167D02*
X1070667Y733500D01*
X1070167Y733750D01*
X1069583Y733833D01*
X1068917Y733667D01*
X1068500Y733333D01*
X1068167Y732750D01*
X1068000Y732167D01*
X1068083Y731667D01*
X1068417Y731083D01*
X1068917Y730667D01*
X1069583Y730500D01*
X1070083Y730583D01*
X1070667Y730917D01*
X1071000Y731250D01*
G01X1046500Y485833D02*
X1048000Y482500D01*
X1049500Y485833D01*
G01X1053600D02*
Y482500D01*
G01Y487167D02*
X1053433Y487250D01*
Y487417D01*
X1053600Y487500D01*
X1053767Y487417D01*
Y487250D01*
X1053600Y487167D01*
G01X1060700Y482500D02*
Y485833D01*
G01Y485250D02*
X1060367Y485583D01*
X1059867Y485750D01*
X1059283Y485833D01*
X1058700Y485667D01*
X1058200Y485333D01*
X1057867Y484833D01*
X1057700Y484167D01*
X1057867Y483500D01*
X1058200Y483000D01*
X1058700Y482667D01*
X1059283Y482500D01*
X1059867Y482583D01*
X1060367Y482833D01*
X1060700Y483167D01*
G01X1069150Y483083D02*
X1069567Y482750D01*
X1070150Y482500D01*
X1070650D01*
X1071150Y482667D01*
X1071483Y482917D01*
X1071650Y483250D01*
X1071567Y483750D01*
X1071233Y484000D01*
X1069733Y484500D01*
X1069400Y485083D01*
X1069567Y485500D01*
X1069900Y485750D01*
X1070400Y485833D01*
X1070900Y485750D01*
X1071400Y485500D01*
G01X1074583Y482500D02*
Y487500D01*
G01Y485083D02*
X1075000Y485500D01*
X1075417Y485750D01*
X1076083Y485833D01*
X1076583Y485750D01*
X1077167Y485417D01*
X1077417Y484917D01*
Y482500D01*
G01X1083100D02*
Y485833D01*
G01Y485250D02*
X1082767Y485583D01*
X1082267Y485750D01*
X1081683Y485833D01*
X1081100Y485667D01*
X1080600Y485333D01*
X1080267Y484833D01*
X1080100Y484167D01*
X1080267Y483500D01*
X1080600Y483000D01*
X1081100Y482667D01*
X1081683Y482500D01*
X1082267Y482583D01*
X1082767Y482833D01*
X1083100Y483167D01*
G01X1087200Y482500D02*
Y487500D01*
G01X1092800Y482500D02*
Y487500D01*
G01X1102500Y482500D02*
Y487500D01*
G01Y485000D02*
X1102917Y485500D01*
X1103417Y485750D01*
X1103917Y485833D01*
X1104667Y485667D01*
X1105167Y485333D01*
X1105500Y484750D01*
Y484083D01*
X1105333Y483417D01*
X1105000Y482917D01*
X1104417Y482583D01*
X1103917Y482500D01*
X1103417Y482583D01*
X1102917Y482833D01*
X1102500Y483250D01*
G01X1108350Y484750D02*
X1111017D01*
X1110767Y485333D01*
X1110350Y485667D01*
X1109767Y485833D01*
X1109183Y485750D01*
X1108683Y485500D01*
X1108350Y484917D01*
X1108183Y484417D01*
Y483917D01*
X1108350Y483417D01*
X1108767Y482917D01*
X1109267Y482583D01*
X1109850Y482500D01*
X1110433Y482667D01*
X1111017Y483167D01*
G01X1118717Y485833D02*
X1119717Y482500D01*
X1120800Y485833D01*
X1121883Y482500D01*
X1122883Y485833D01*
G01X1126400D02*
Y482500D01*
G01Y487167D02*
X1126233Y487250D01*
Y487417D01*
X1126400Y487500D01*
X1126567Y487417D01*
Y487250D01*
X1126400Y487167D01*
G01X1132000Y487500D02*
Y482500D01*
G01X1130833Y485833D02*
X1133167D01*
G01X1136183Y482500D02*
Y487500D01*
G01Y485083D02*
X1136600Y485500D01*
X1137017Y485750D01*
X1137683Y485833D01*
X1138183Y485750D01*
X1138767Y485417D01*
X1139017Y484917D01*
Y482500D01*
G01X1150467D02*
X1147133Y484167D01*
X1150467Y485833D01*
G01X1160000Y482500D02*
X1160583Y482583D01*
X1161250Y482833D01*
X1161667Y483250D01*
X1161833Y483833D01*
X1161667Y484417D01*
X1161167Y484917D01*
X1160417Y485167D01*
X1159583D01*
X1159083Y485333D01*
X1158667Y485750D01*
X1158500Y486333D01*
X1158750Y486917D01*
X1159333Y487333D01*
X1160000Y487500D01*
X1160667Y487333D01*
X1161250Y486917D01*
X1161500Y486333D01*
X1161333Y485750D01*
X1160917Y485333D01*
X1160417Y485167D01*
X1159583D01*
X1158833Y484917D01*
X1158333Y484417D01*
X1158167Y483833D01*
X1158333Y483250D01*
X1158750Y482833D01*
X1159417Y482583D01*
X1160000Y482500D01*
G01X1165600Y487500D02*
X1164933Y487333D01*
X1164433Y486917D01*
X1164100Y486417D01*
X1163850Y485750D01*
X1163767Y485000D01*
X1163850Y484250D01*
X1164100Y483583D01*
X1164433Y483083D01*
X1164933Y482667D01*
X1165600Y482500D01*
X1166267Y482667D01*
X1166767Y483083D01*
X1167100Y483583D01*
X1167350Y484250D01*
X1167433Y485000D01*
X1167350Y485750D01*
X1167100Y486417D01*
X1166767Y486917D01*
X1166267Y487333D01*
X1165600Y487500D01*
G01X1175300Y482333D02*
X1178300Y487500D01*
G01X1175300D02*
X1174800Y487333D01*
X1174550Y487083D01*
X1174383Y486583D01*
X1174550Y486083D01*
X1174800Y485833D01*
X1175300Y485667D01*
X1175800Y485833D01*
X1176050Y486083D01*
X1176217Y486583D01*
X1176050Y487083D01*
X1175800Y487333D01*
X1175300Y487500D01*
G01X1178300Y484167D02*
X1177800Y484000D01*
X1177550Y483750D01*
X1177383Y483250D01*
X1177550Y482750D01*
X1177800Y482500D01*
X1178300Y482333D01*
X1178800Y482500D01*
X1179050Y482750D01*
X1179217Y483250D01*
X1179050Y483750D01*
X1178800Y484000D01*
X1178300Y484167D01*
G01X1186750Y483083D02*
X1187167Y482750D01*
X1187750Y482500D01*
X1188250D01*
X1188750Y482667D01*
X1189083Y482917D01*
X1189250Y483250D01*
X1189167Y483750D01*
X1188833Y484000D01*
X1187333Y484500D01*
X1187000Y485083D01*
X1187167Y485500D01*
X1187500Y485750D01*
X1188000Y485833D01*
X1188500Y485750D01*
X1189000Y485500D01*
G01X1193600Y482500D02*
X1193100Y482583D01*
X1192600Y482917D01*
X1192267Y483500D01*
X1192100Y484167D01*
X1192267Y484833D01*
X1192600Y485417D01*
X1193100Y485750D01*
X1193600Y485833D01*
X1194100Y485750D01*
X1194600Y485417D01*
X1194933Y484833D01*
X1195017Y484167D01*
X1194933Y483500D01*
X1194600Y482917D01*
X1194100Y482583D01*
X1193600Y482500D01*
G01X1199200D02*
Y487500D01*
G01X1206300D02*
Y482500D01*
G01Y483250D02*
X1205967Y482833D01*
X1205467Y482583D01*
X1204883Y482500D01*
X1204217Y482667D01*
X1203717Y483083D01*
X1203383Y483583D01*
X1203300Y484167D01*
X1203383Y484750D01*
X1203717Y485250D01*
X1204217Y485667D01*
X1204883Y485833D01*
X1205467Y485750D01*
X1205883Y485583D01*
X1206300Y485250D01*
G01X1209150Y484750D02*
X1211817D01*
X1211567Y485333D01*
X1211150Y485667D01*
X1210567Y485833D01*
X1209983Y485750D01*
X1209483Y485500D01*
X1209150Y484917D01*
X1208983Y484417D01*
Y483917D01*
X1209150Y483417D01*
X1209567Y482917D01*
X1210067Y482583D01*
X1210650Y482500D01*
X1211233Y482667D01*
X1211817Y483167D01*
G01X1214833Y482500D02*
Y485833D01*
G01Y485167D02*
X1215250Y485500D01*
X1215667Y485750D01*
X1216250Y485833D01*
X1216667Y485750D01*
X1217167Y485500D01*
G01X1224700Y482500D02*
Y485833D01*
G01Y484917D02*
X1224950Y485333D01*
X1225367Y485667D01*
X1225950Y485833D01*
X1226533Y485667D01*
X1226950Y485333D01*
X1227200Y484917D01*
Y482500D01*
G01Y484917D02*
X1227450Y485333D01*
X1227867Y485667D01*
X1228450Y485833D01*
X1229033Y485667D01*
X1229450Y485333D01*
X1229700Y484833D01*
Y482500D01*
G01X1234300D02*
Y485833D01*
G01Y485250D02*
X1233967Y485583D01*
X1233467Y485750D01*
X1232883Y485833D01*
X1232300Y485667D01*
X1231800Y485333D01*
X1231467Y484833D01*
X1231300Y484167D01*
X1231467Y483500D01*
X1231800Y483000D01*
X1232300Y482667D01*
X1232883Y482500D01*
X1233467Y482583D01*
X1233967Y482833D01*
X1234300Y483167D01*
G01X1237150Y483083D02*
X1237567Y482750D01*
X1238150Y482500D01*
X1238650D01*
X1239150Y482667D01*
X1239483Y482917D01*
X1239650Y483250D01*
X1239567Y483750D01*
X1239233Y484000D01*
X1237733Y484500D01*
X1237400Y485083D01*
X1237567Y485500D01*
X1237900Y485750D01*
X1238400Y485833D01*
X1238900Y485750D01*
X1239400Y485500D01*
G01X1242583Y482500D02*
Y487500D01*
G01X1245250Y485833D02*
X1242583Y483917D01*
G01X1243667Y484667D02*
X1245417Y482500D01*
G01X1045500Y504833D02*
X1047000Y501500D01*
X1048500Y504833D01*
G01X1052600D02*
Y501500D01*
G01Y506167D02*
X1052433Y506250D01*
Y506417D01*
X1052600Y506500D01*
X1052767Y506417D01*
Y506250D01*
X1052600Y506167D01*
G01X1059700Y501500D02*
Y504833D01*
G01Y504250D02*
X1059367Y504583D01*
X1058867Y504750D01*
X1058283Y504833D01*
X1057700Y504667D01*
X1057200Y504333D01*
X1056867Y503833D01*
X1056700Y503167D01*
X1056867Y502500D01*
X1057200Y502000D01*
X1057700Y501667D01*
X1058283Y501500D01*
X1058867Y501583D01*
X1059367Y501833D01*
X1059700Y502167D01*
G01X1068150Y502083D02*
X1068567Y501750D01*
X1069150Y501500D01*
X1069650D01*
X1070150Y501667D01*
X1070483Y501917D01*
X1070650Y502250D01*
X1070567Y502750D01*
X1070233Y503000D01*
X1068733Y503500D01*
X1068400Y504083D01*
X1068567Y504500D01*
X1068900Y504750D01*
X1069400Y504833D01*
X1069900Y504750D01*
X1070400Y504500D01*
G01X1073583Y501500D02*
Y506500D01*
G01Y504083D02*
X1074000Y504500D01*
X1074417Y504750D01*
X1075083Y504833D01*
X1075583Y504750D01*
X1076167Y504417D01*
X1076417Y503917D01*
Y501500D01*
G01X1082100D02*
Y504833D01*
G01Y504250D02*
X1081767Y504583D01*
X1081267Y504750D01*
X1080683Y504833D01*
X1080100Y504667D01*
X1079600Y504333D01*
X1079267Y503833D01*
X1079100Y503167D01*
X1079267Y502500D01*
X1079600Y502000D01*
X1080100Y501667D01*
X1080683Y501500D01*
X1081267Y501583D01*
X1081767Y501833D01*
X1082100Y502167D01*
G01X1086200Y501500D02*
Y506500D01*
G01X1091800Y501500D02*
Y506500D01*
G01X1101500Y501500D02*
Y506500D01*
G01Y504000D02*
X1101917Y504500D01*
X1102417Y504750D01*
X1102917Y504833D01*
X1103667Y504667D01*
X1104167Y504333D01*
X1104500Y503750D01*
Y503083D01*
X1104333Y502417D01*
X1104000Y501917D01*
X1103417Y501583D01*
X1102917Y501500D01*
X1102417Y501583D01*
X1101917Y501833D01*
X1101500Y502250D01*
G01X1107350Y503750D02*
X1110017D01*
X1109767Y504333D01*
X1109350Y504667D01*
X1108767Y504833D01*
X1108183Y504750D01*
X1107683Y504500D01*
X1107350Y503917D01*
X1107183Y503417D01*
Y502917D01*
X1107350Y502417D01*
X1107767Y501917D01*
X1108267Y501583D01*
X1108850Y501500D01*
X1109433Y501667D01*
X1110017Y502167D01*
G01X1118300Y499833D02*
Y504833D01*
G01Y504083D02*
X1118717Y504500D01*
X1119133Y504750D01*
X1119800Y504833D01*
X1120383Y504750D01*
X1120967Y504333D01*
X1121217Y503750D01*
X1121300Y503167D01*
X1121217Y502583D01*
X1120967Y502000D01*
X1120467Y501667D01*
X1119800Y501500D01*
X1119217Y501583D01*
X1118633Y501833D01*
X1118300Y502167D01*
G01X1125400Y501500D02*
Y506500D01*
G01X1129583Y504833D02*
Y502500D01*
X1129917Y501917D01*
X1130417Y501583D01*
X1131000Y501500D01*
X1131583Y501583D01*
X1132083Y501917D01*
X1132417Y502500D01*
G01Y501500D02*
Y504833D01*
G01X1135433Y500250D02*
X1136017Y499917D01*
X1136683Y499833D01*
X1137267Y499917D01*
X1137767Y500333D01*
X1138100Y500917D01*
Y504833D01*
G01Y504167D02*
X1137767Y504500D01*
X1137267Y504750D01*
X1136683Y504833D01*
X1136017Y504667D01*
X1135600Y504333D01*
X1135267Y503750D01*
X1135100Y503167D01*
X1135183Y502667D01*
X1135517Y502083D01*
X1136017Y501667D01*
X1136683Y501500D01*
X1137183Y501583D01*
X1137767Y501917D01*
X1138100Y502250D01*
G01X1141033Y500250D02*
X1141617Y499917D01*
X1142283Y499833D01*
X1142867Y499917D01*
X1143367Y500333D01*
X1143700Y500917D01*
Y504833D01*
G01Y504167D02*
X1143367Y504500D01*
X1142867Y504750D01*
X1142283Y504833D01*
X1141617Y504667D01*
X1141200Y504333D01*
X1140867Y503750D01*
X1140700Y503167D01*
X1140783Y502667D01*
X1141117Y502083D01*
X1141617Y501667D01*
X1142283Y501500D01*
X1142783Y501583D01*
X1143367Y501917D01*
X1143700Y502250D01*
G01X1146550Y503750D02*
X1149217D01*
X1148967Y504333D01*
X1148550Y504667D01*
X1147967Y504833D01*
X1147383Y504750D01*
X1146883Y504500D01*
X1146550Y503917D01*
X1146383Y503417D01*
Y502917D01*
X1146550Y502417D01*
X1146967Y501917D01*
X1147467Y501583D01*
X1148050Y501500D01*
X1148633Y501667D01*
X1149217Y502167D01*
G01X1154900Y506500D02*
Y501500D01*
G01Y502250D02*
X1154567Y501833D01*
X1154067Y501583D01*
X1153483Y501500D01*
X1152817Y501667D01*
X1152317Y502083D01*
X1151983Y502583D01*
X1151900Y503167D01*
X1151983Y503750D01*
X1152317Y504250D01*
X1152817Y504667D01*
X1153483Y504833D01*
X1154067Y504750D01*
X1154483Y504583D01*
X1154900Y504250D01*
G01X1162517Y504833D02*
X1163517Y501500D01*
X1164600Y504833D01*
X1165683Y501500D01*
X1166683Y504833D01*
G01X1170200D02*
Y501500D01*
G01Y506167D02*
X1170033Y506250D01*
Y506417D01*
X1170200Y506500D01*
X1170367Y506417D01*
Y506250D01*
X1170200Y506167D01*
G01X1175800Y506500D02*
Y501500D01*
G01X1174633Y504833D02*
X1176967D01*
G01X1179983Y501500D02*
Y506500D01*
G01Y504083D02*
X1180400Y504500D01*
X1180817Y504750D01*
X1181483Y504833D01*
X1181983Y504750D01*
X1182567Y504417D01*
X1182817Y503917D01*
Y501500D01*
G01X1194267D02*
X1190933Y503167D01*
X1194267Y504833D01*
G01X1201967Y502250D02*
X1202467Y501833D01*
X1203050Y501583D01*
X1203800Y501500D01*
X1204550Y501667D01*
X1205133Y502000D01*
X1205550Y502583D01*
X1205633Y503250D01*
X1205467Y503917D01*
X1205050Y504333D01*
X1204467Y504667D01*
X1203883Y504750D01*
X1203300Y504667D01*
X1202550Y504333D01*
X1202800Y506500D01*
X1205050D01*
G01X1209400D02*
X1208733Y506333D01*
X1208233Y505917D01*
X1207900Y505417D01*
X1207650Y504750D01*
X1207567Y504000D01*
X1207650Y503250D01*
X1207900Y502583D01*
X1208233Y502083D01*
X1208733Y501667D01*
X1209400Y501500D01*
X1210067Y501667D01*
X1210567Y502083D01*
X1210900Y502583D01*
X1211150Y503250D01*
X1211233Y504000D01*
X1211150Y504750D01*
X1210900Y505417D01*
X1210567Y505917D01*
X1210067Y506333D01*
X1209400Y506500D01*
G01X1219100Y501333D02*
X1222100Y506500D01*
G01X1219100D02*
X1218600Y506333D01*
X1218350Y506083D01*
X1218183Y505583D01*
X1218350Y505083D01*
X1218600Y504833D01*
X1219100Y504667D01*
X1219600Y504833D01*
X1219850Y505083D01*
X1220017Y505583D01*
X1219850Y506083D01*
X1219600Y506333D01*
X1219100Y506500D01*
G01X1222100Y503167D02*
X1221600Y503000D01*
X1221350Y502750D01*
X1221183Y502250D01*
X1221350Y501750D01*
X1221600Y501500D01*
X1222100Y501333D01*
X1222600Y501500D01*
X1222850Y501750D01*
X1223017Y502250D01*
X1222850Y502750D01*
X1222600Y503000D01*
X1222100Y503167D01*
G01X1230550Y502083D02*
X1230967Y501750D01*
X1231550Y501500D01*
X1232050D01*
X1232550Y501667D01*
X1232883Y501917D01*
X1233050Y502250D01*
X1232967Y502750D01*
X1232633Y503000D01*
X1231133Y503500D01*
X1230800Y504083D01*
X1230967Y504500D01*
X1231300Y504750D01*
X1231800Y504833D01*
X1232300Y504750D01*
X1232800Y504500D01*
G01X1237400Y501500D02*
X1236900Y501583D01*
X1236400Y501917D01*
X1236067Y502500D01*
X1235900Y503167D01*
X1236067Y503833D01*
X1236400Y504417D01*
X1236900Y504750D01*
X1237400Y504833D01*
X1237900Y504750D01*
X1238400Y504417D01*
X1238733Y503833D01*
X1238817Y503167D01*
X1238733Y502500D01*
X1238400Y501917D01*
X1237900Y501583D01*
X1237400Y501500D01*
G01X1243000D02*
Y506500D01*
G01X1250100D02*
Y501500D01*
G01Y502250D02*
X1249767Y501833D01*
X1249267Y501583D01*
X1248683Y501500D01*
X1248017Y501667D01*
X1247517Y502083D01*
X1247183Y502583D01*
X1247100Y503167D01*
X1247183Y503750D01*
X1247517Y504250D01*
X1248017Y504667D01*
X1248683Y504833D01*
X1249267Y504750D01*
X1249683Y504583D01*
X1250100Y504250D01*
G01X1252950Y503750D02*
X1255617D01*
X1255367Y504333D01*
X1254950Y504667D01*
X1254367Y504833D01*
X1253783Y504750D01*
X1253283Y504500D01*
X1252950Y503917D01*
X1252783Y503417D01*
Y502917D01*
X1252950Y502417D01*
X1253367Y501917D01*
X1253867Y501583D01*
X1254450Y501500D01*
X1255033Y501667D01*
X1255617Y502167D01*
G01X1258633Y501500D02*
Y504833D01*
G01Y504167D02*
X1259050Y504500D01*
X1259467Y504750D01*
X1260050Y504833D01*
X1260467Y504750D01*
X1260967Y504500D01*
G01X1268500Y501500D02*
Y504833D01*
G01Y503917D02*
X1268750Y504333D01*
X1269167Y504667D01*
X1269750Y504833D01*
X1270333Y504667D01*
X1270750Y504333D01*
X1271000Y503917D01*
Y501500D01*
G01Y503917D02*
X1271250Y504333D01*
X1271667Y504667D01*
X1272250Y504833D01*
X1272833Y504667D01*
X1273250Y504333D01*
X1273500Y503833D01*
Y501500D01*
G01X1278100D02*
Y504833D01*
G01Y504250D02*
X1277767Y504583D01*
X1277267Y504750D01*
X1276683Y504833D01*
X1276100Y504667D01*
X1275600Y504333D01*
X1275267Y503833D01*
X1275100Y503167D01*
X1275267Y502500D01*
X1275600Y502000D01*
X1276100Y501667D01*
X1276683Y501500D01*
X1277267Y501583D01*
X1277767Y501833D01*
X1278100Y502167D01*
G01X1280950Y502083D02*
X1281367Y501750D01*
X1281950Y501500D01*
X1282450D01*
X1282950Y501667D01*
X1283283Y501917D01*
X1283450Y502250D01*
X1283367Y502750D01*
X1283033Y503000D01*
X1281533Y503500D01*
X1281200Y504083D01*
X1281367Y504500D01*
X1281700Y504750D01*
X1282200Y504833D01*
X1282700Y504750D01*
X1283200Y504500D01*
G01X1286383Y501500D02*
Y506500D01*
G01X1289050Y504833D02*
X1286383Y502917D01*
G01X1287467Y503667D02*
X1289217Y501500D01*
G01X1293233Y500583D02*
X1293567Y501667D01*
G01X1089493Y104700D02*
Y99700D01*
X1092827D01*
G01X1095510Y103033D02*
X1098010Y99700D01*
G01Y103033D02*
X1095510Y99700D01*
G01X1102360Y99533D02*
X1102193Y99617D01*
Y99783D01*
X1102360Y99867D01*
X1102527Y99783D01*
Y99617D01*
X1102360Y99533D01*
G01Y101783D02*
X1102193Y101867D01*
Y102033D01*
X1102360Y102117D01*
X1102527Y102033D01*
Y101867D01*
X1102360Y101783D01*
G01X1111060Y99700D02*
Y103033D01*
G01Y102117D02*
X1111310Y102533D01*
X1111727Y102867D01*
X1112310Y103033D01*
X1112893Y102867D01*
X1113310Y102533D01*
X1113560Y102117D01*
Y99700D01*
G01Y102117D02*
X1113810Y102533D01*
X1114227Y102867D01*
X1114810Y103033D01*
X1115393Y102867D01*
X1115810Y102533D01*
X1116060Y102033D01*
Y99700D01*
G01X1117743Y103033D02*
Y100700D01*
X1118077Y100117D01*
X1118577Y99783D01*
X1119160Y99700D01*
X1119743Y99783D01*
X1120243Y100117D01*
X1120577Y100700D01*
G01Y99700D02*
Y103033D01*
G01X1123510Y100283D02*
X1123927Y99950D01*
X1124510Y99700D01*
X1125010D01*
X1125510Y99867D01*
X1125843Y100117D01*
X1126010Y100450D01*
X1125927Y100950D01*
X1125593Y101200D01*
X1124093Y101700D01*
X1123760Y102283D01*
X1123927Y102700D01*
X1124260Y102950D01*
X1124760Y103033D01*
X1125260Y102950D01*
X1125760Y102700D01*
G01X1130360Y104700D02*
Y99700D01*
G01X1129193Y103033D02*
X1131527D01*
G01X1140060Y99700D02*
Y104700D01*
G01Y102200D02*
X1140477Y102700D01*
X1140977Y102950D01*
X1141477Y103033D01*
X1142227Y102867D01*
X1142727Y102533D01*
X1143060Y101950D01*
Y101283D01*
X1142893Y100617D01*
X1142560Y100117D01*
X1141977Y99783D01*
X1141477Y99700D01*
X1140977Y99783D01*
X1140477Y100033D01*
X1140060Y100450D01*
G01X1145910Y101950D02*
X1148577D01*
X1148327Y102533D01*
X1147910Y102867D01*
X1147327Y103033D01*
X1146743Y102950D01*
X1146243Y102700D01*
X1145910Y102117D01*
X1145743Y101617D01*
Y101117D01*
X1145910Y100617D01*
X1146327Y100117D01*
X1146827Y99783D01*
X1147410Y99700D01*
X1147993Y99867D01*
X1148577Y100367D01*
G01X1156860Y99700D02*
Y104700D01*
G01Y102200D02*
X1157277Y102700D01*
X1157777Y102950D01*
X1158277Y103033D01*
X1159027Y102867D01*
X1159527Y102533D01*
X1159860Y101950D01*
Y101283D01*
X1159693Y100617D01*
X1159360Y100117D01*
X1158777Y99783D01*
X1158277Y99700D01*
X1157777Y99783D01*
X1157277Y100033D01*
X1156860Y100450D01*
G01X1162793Y99700D02*
Y103033D01*
G01Y102367D02*
X1163210Y102700D01*
X1163627Y102950D01*
X1164210Y103033D01*
X1164627Y102950D01*
X1165127Y102700D01*
G01X1169560Y99700D02*
X1169060Y99783D01*
X1168560Y100117D01*
X1168227Y100700D01*
X1168060Y101367D01*
X1168227Y102033D01*
X1168560Y102617D01*
X1169060Y102950D01*
X1169560Y103033D01*
X1170060Y102950D01*
X1170560Y102617D01*
X1170893Y102033D01*
X1170977Y101367D01*
X1170893Y100700D01*
X1170560Y100117D01*
X1170060Y99783D01*
X1169560Y99700D01*
G01X1173743D02*
Y104700D01*
G01X1176410Y103033D02*
X1173743Y101117D01*
G01X1174827Y101867D02*
X1176577Y99700D01*
G01X1179510Y101950D02*
X1182177D01*
X1181927Y102533D01*
X1181510Y102867D01*
X1180927Y103033D01*
X1180343Y102950D01*
X1179843Y102700D01*
X1179510Y102117D01*
X1179343Y101617D01*
Y101117D01*
X1179510Y100617D01*
X1179927Y100117D01*
X1180427Y99783D01*
X1181010Y99700D01*
X1181593Y99867D01*
X1182177Y100367D01*
G01X1184943Y99700D02*
Y103033D01*
G01Y102200D02*
X1185277Y102617D01*
X1185777Y102950D01*
X1186443Y103033D01*
X1187027Y102950D01*
X1187527Y102617D01*
X1187777Y102033D01*
Y99700D01*
G01X1197560D02*
Y104700D01*
G01X1204660Y99700D02*
Y103033D01*
G01Y102450D02*
X1204327Y102783D01*
X1203827Y102950D01*
X1203243Y103033D01*
X1202660Y102867D01*
X1202160Y102533D01*
X1201827Y102033D01*
X1201660Y101367D01*
X1201827Y100700D01*
X1202160Y100200D01*
X1202660Y99867D01*
X1203243Y99700D01*
X1203827Y99783D01*
X1204327Y100033D01*
X1204660Y100367D01*
G01X1207010Y98200D02*
X1207510Y98033D01*
X1208177Y98200D01*
X1208593Y98533D01*
X1208927Y98950D01*
X1209427Y100283D01*
X1210510Y103033D01*
G01X1207843D02*
X1209427Y100283D01*
G01X1213110Y101950D02*
X1215777D01*
X1215527Y102533D01*
X1215110Y102867D01*
X1214527Y103033D01*
X1213943Y102950D01*
X1213443Y102700D01*
X1213110Y102117D01*
X1212943Y101617D01*
Y101117D01*
X1213110Y100617D01*
X1213527Y100117D01*
X1214027Y99783D01*
X1214610Y99700D01*
X1215193Y99867D01*
X1215777Y100367D01*
G01X1218793Y99700D02*
Y103033D01*
G01Y102367D02*
X1219210Y102700D01*
X1219627Y102950D01*
X1220210Y103033D01*
X1220627Y102950D01*
X1221127Y102700D01*
G01X1087667Y124000D02*
Y129000D01*
X1089333D01*
X1090000Y128750D01*
X1090500Y128417D01*
X1090917Y127917D01*
X1091250Y127333D01*
X1091333Y126500D01*
X1091250Y125667D01*
X1090917Y125083D01*
X1090500Y124583D01*
X1090000Y124250D01*
X1089333Y124000D01*
X1087667D01*
G01X1093933D02*
Y127333D01*
G01Y126667D02*
X1094350Y127000D01*
X1094767Y127250D01*
X1095350Y127333D01*
X1095767Y127250D01*
X1096267Y127000D01*
G01X1100700Y127333D02*
Y124000D01*
G01Y128667D02*
X1100533Y128750D01*
Y128917D01*
X1100700Y129000D01*
X1100867Y128917D01*
Y128750D01*
X1100700Y128667D01*
G01X1106300Y124000D02*
Y129000D01*
G01X1111900Y124000D02*
Y129000D01*
G01X1121517Y124000D02*
Y129000D01*
X1124683D01*
G01X1123517Y126583D02*
X1121517D01*
G01X1127533Y124000D02*
Y127333D01*
G01Y126667D02*
X1127950Y127000D01*
X1128367Y127250D01*
X1128950Y127333D01*
X1129367Y127250D01*
X1129867Y127000D01*
G01X1134300Y124000D02*
X1133800Y124083D01*
X1133300Y124417D01*
X1132967Y125000D01*
X1132800Y125667D01*
X1132967Y126333D01*
X1133300Y126917D01*
X1133800Y127250D01*
X1134300Y127333D01*
X1134800Y127250D01*
X1135300Y126917D01*
X1135633Y126333D01*
X1135717Y125667D01*
X1135633Y125000D01*
X1135300Y124417D01*
X1134800Y124083D01*
X1134300Y124000D01*
G01X1137400D02*
Y127333D01*
G01Y126417D02*
X1137650Y126833D01*
X1138067Y127167D01*
X1138650Y127333D01*
X1139233Y127167D01*
X1139650Y126833D01*
X1139900Y126417D01*
Y124000D01*
G01Y126417D02*
X1140150Y126833D01*
X1140567Y127167D01*
X1141150Y127333D01*
X1141733Y127167D01*
X1142150Y126833D01*
X1142400Y126333D01*
Y124000D01*
G01X1167483Y122333D02*
X1166650Y123167D01*
X1166233Y124000D01*
Y127333D01*
X1166650Y128167D01*
X1167483Y129000D01*
G01X1174167Y126667D02*
X1174500Y126917D01*
X1174750Y127333D01*
X1174917Y127917D01*
X1174750Y128417D01*
X1174417Y128750D01*
X1173833Y129000D01*
X1171583D01*
Y124000D01*
X1174333D01*
X1174917Y124333D01*
X1175250Y124833D01*
X1175417Y125417D01*
X1175250Y126000D01*
X1174750Y126500D01*
X1174167Y126667D01*
X1171583D01*
G01X1179100Y124000D02*
X1178433Y124083D01*
X1177850Y124417D01*
X1177350Y124917D01*
X1177017Y125500D01*
X1176850Y126167D01*
Y126833D01*
X1177017Y127500D01*
X1177350Y128083D01*
X1177850Y128583D01*
X1178433Y128917D01*
X1179100Y129000D01*
X1179767Y128917D01*
X1180350Y128583D01*
X1180850Y128083D01*
X1181183Y127500D01*
X1181350Y126833D01*
Y126167D01*
X1181183Y125500D01*
X1180850Y124917D01*
X1180350Y124417D01*
X1179767Y124083D01*
X1179100Y124000D01*
G01X1184700Y129000D02*
Y124000D01*
G01X1182783Y129000D02*
X1186617D01*
G01X1190300D02*
Y124000D01*
G01X1188383Y129000D02*
X1192217D01*
G01X1195900Y124000D02*
X1195233Y124083D01*
X1194650Y124417D01*
X1194150Y124917D01*
X1193817Y125500D01*
X1193650Y126167D01*
Y126833D01*
X1193817Y127500D01*
X1194150Y128083D01*
X1194650Y128583D01*
X1195233Y128917D01*
X1195900Y129000D01*
X1196567Y128917D01*
X1197150Y128583D01*
X1197650Y128083D01*
X1197983Y127500D01*
X1198150Y126833D01*
Y126167D01*
X1197983Y125500D01*
X1197650Y124917D01*
X1197150Y124417D01*
X1196567Y124083D01*
X1195900Y124000D01*
G01X1199333D02*
Y129000D01*
X1201500Y124833D01*
X1203667Y129000D01*
Y124000D01*
G01X1207517Y122333D02*
X1208350Y123167D01*
X1208767Y124000D01*
Y127333D01*
X1208350Y128167D01*
X1207517Y129000D01*
G01X1218300D02*
Y124000D01*
G01X1217133Y127333D02*
X1219467D01*
G01X1223900Y124000D02*
X1223400Y124083D01*
X1222900Y124417D01*
X1222567Y125000D01*
X1222400Y125667D01*
X1222567Y126333D01*
X1222900Y126917D01*
X1223400Y127250D01*
X1223900Y127333D01*
X1224400Y127250D01*
X1224900Y126917D01*
X1225233Y126333D01*
X1225317Y125667D01*
X1225233Y125000D01*
X1224900Y124417D01*
X1224400Y124083D01*
X1223900Y124000D01*
G01X1233433Y129000D02*
Y124000D01*
X1236767D01*
G01X1239450Y127333D02*
X1241950Y124000D01*
G01Y127333D02*
X1239450Y124000D01*
G01X1088893Y117200D02*
Y112200D01*
X1092227D01*
G01X1094743D02*
Y115533D01*
G01Y114700D02*
X1095077Y115117D01*
X1095577Y115450D01*
X1096243Y115533D01*
X1096827Y115450D01*
X1097327Y115117D01*
X1097577Y114533D01*
Y112200D01*
G01X1101760Y112033D02*
X1101593Y112117D01*
Y112283D01*
X1101760Y112367D01*
X1101927Y112283D01*
Y112117D01*
X1101760Y112033D01*
G01Y114283D02*
X1101593Y114367D01*
Y114533D01*
X1101760Y114617D01*
X1101927Y114533D01*
Y114367D01*
X1101760Y114283D01*
G01X1114293Y115117D02*
X1113710Y115450D01*
X1113210Y115533D01*
X1112543Y115367D01*
X1112043Y115033D01*
X1111710Y114450D01*
X1111627Y113867D01*
X1111710Y113283D01*
X1112043Y112783D01*
X1112543Y112367D01*
X1113210Y112200D01*
X1113793Y112367D01*
X1114293Y112700D01*
G01X1120060Y112200D02*
Y115533D01*
G01Y114950D02*
X1119727Y115283D01*
X1119227Y115450D01*
X1118643Y115533D01*
X1118060Y115367D01*
X1117560Y115033D01*
X1117227Y114533D01*
X1117060Y113867D01*
X1117227Y113200D01*
X1117560Y112700D01*
X1118060Y112367D01*
X1118643Y112200D01*
X1119227Y112283D01*
X1119727Y112533D01*
X1120060Y112867D01*
G01X1122743Y112200D02*
Y115533D01*
G01Y114700D02*
X1123077Y115117D01*
X1123577Y115450D01*
X1124243Y115533D01*
X1124827Y115450D01*
X1125327Y115117D01*
X1125577Y114533D01*
Y112200D01*
G01X1129760Y115533D02*
X1130593Y116575D01*
Y117200D01*
X1129968D01*
Y116575D01*
X1130593D01*
G01X1135360Y117200D02*
Y112200D01*
G01X1134193Y115533D02*
X1136527D01*
G01X1145060Y112200D02*
Y117200D01*
G01Y114700D02*
X1145477Y115200D01*
X1145977Y115450D01*
X1146477Y115533D01*
X1147227Y115367D01*
X1147727Y115033D01*
X1148060Y114450D01*
Y113783D01*
X1147893Y113117D01*
X1147560Y112617D01*
X1146977Y112283D01*
X1146477Y112200D01*
X1145977Y112283D01*
X1145477Y112533D01*
X1145060Y112950D01*
G01X1150910Y114450D02*
X1153577D01*
X1153327Y115033D01*
X1152910Y115367D01*
X1152327Y115533D01*
X1151743Y115450D01*
X1151243Y115200D01*
X1150910Y114617D01*
X1150743Y114117D01*
Y113617D01*
X1150910Y113117D01*
X1151327Y112617D01*
X1151827Y112283D01*
X1152410Y112200D01*
X1152993Y112367D01*
X1153577Y112867D01*
G01X1161860Y112200D02*
Y117200D01*
G01Y114700D02*
X1162277Y115200D01*
X1162777Y115450D01*
X1163277Y115533D01*
X1164027Y115367D01*
X1164527Y115033D01*
X1164860Y114450D01*
Y113783D01*
X1164693Y113117D01*
X1164360Y112617D01*
X1163777Y112283D01*
X1163277Y112200D01*
X1162777Y112283D01*
X1162277Y112533D01*
X1161860Y112950D01*
G01X1167793Y112200D02*
Y115533D01*
G01Y114867D02*
X1168210Y115200D01*
X1168627Y115450D01*
X1169210Y115533D01*
X1169627Y115450D01*
X1170127Y115200D01*
G01X1174560Y112200D02*
X1174060Y112283D01*
X1173560Y112617D01*
X1173227Y113200D01*
X1173060Y113867D01*
X1173227Y114533D01*
X1173560Y115117D01*
X1174060Y115450D01*
X1174560Y115533D01*
X1175060Y115450D01*
X1175560Y115117D01*
X1175893Y114533D01*
X1175977Y113867D01*
X1175893Y113200D01*
X1175560Y112617D01*
X1175060Y112283D01*
X1174560Y112200D01*
G01X1178743D02*
Y117200D01*
G01X1181410Y115533D02*
X1178743Y113617D01*
G01X1179827Y114367D02*
X1181577Y112200D01*
G01X1184510Y114450D02*
X1187177D01*
X1186927Y115033D01*
X1186510Y115367D01*
X1185927Y115533D01*
X1185343Y115450D01*
X1184843Y115200D01*
X1184510Y114617D01*
X1184343Y114117D01*
Y113617D01*
X1184510Y113117D01*
X1184927Y112617D01*
X1185427Y112283D01*
X1186010Y112200D01*
X1186593Y112367D01*
X1187177Y112867D01*
G01X1189943Y112200D02*
Y115533D01*
G01Y114700D02*
X1190277Y115117D01*
X1190777Y115450D01*
X1191443Y115533D01*
X1192027Y115450D01*
X1192527Y115117D01*
X1192777Y114533D01*
Y112200D01*
G01X1202560D02*
Y117200D01*
G01X1209660Y112200D02*
Y115533D01*
G01Y114950D02*
X1209327Y115283D01*
X1208827Y115450D01*
X1208243Y115533D01*
X1207660Y115367D01*
X1207160Y115033D01*
X1206827Y114533D01*
X1206660Y113867D01*
X1206827Y113200D01*
X1207160Y112700D01*
X1207660Y112367D01*
X1208243Y112200D01*
X1208827Y112283D01*
X1209327Y112533D01*
X1209660Y112867D01*
G01X1212010Y110700D02*
X1212510Y110533D01*
X1213177Y110700D01*
X1213593Y111033D01*
X1213927Y111450D01*
X1214427Y112783D01*
X1215510Y115533D01*
G01X1212843D02*
X1214427Y112783D01*
G01X1218110Y114450D02*
X1220777D01*
X1220527Y115033D01*
X1220110Y115367D01*
X1219527Y115533D01*
X1218943Y115450D01*
X1218443Y115200D01*
X1218110Y114617D01*
X1217943Y114117D01*
Y113617D01*
X1218110Y113117D01*
X1218527Y112617D01*
X1219027Y112283D01*
X1219610Y112200D01*
X1220193Y112367D01*
X1220777Y112867D01*
G01X1223793Y112200D02*
Y115533D01*
G01Y114867D02*
X1224210Y115200D01*
X1224627Y115450D01*
X1225210Y115533D01*
X1225627Y115450D01*
X1226127Y115200D01*
G01X1109833Y590500D02*
Y595500D01*
X1111833D01*
X1112500Y595250D01*
X1113000Y594667D01*
X1113167Y594000D01*
X1113000Y593333D01*
X1112583Y592833D01*
X1111833Y592583D01*
X1109833D01*
G01X1117100Y590500D02*
Y595500D01*
G01X1121283Y593833D02*
Y591500D01*
X1121617Y590917D01*
X1122117Y590583D01*
X1122700Y590500D01*
X1123283Y590583D01*
X1123783Y590917D01*
X1124117Y591500D01*
G01Y590500D02*
Y593833D01*
G01X1127133Y589250D02*
X1127717Y588917D01*
X1128383Y588833D01*
X1128967Y588917D01*
X1129467Y589333D01*
X1129800Y589917D01*
Y593833D01*
G01Y593167D02*
X1129467Y593500D01*
X1128967Y593750D01*
X1128383Y593833D01*
X1127717Y593667D01*
X1127300Y593333D01*
X1126967Y592750D01*
X1126800Y592167D01*
X1126883Y591667D01*
X1127217Y591083D01*
X1127717Y590667D01*
X1128383Y590500D01*
X1128883Y590583D01*
X1129467Y590917D01*
X1129800Y591250D01*
G01X1132733Y589250D02*
X1133317Y588917D01*
X1133983Y588833D01*
X1134567Y588917D01*
X1135067Y589333D01*
X1135400Y589917D01*
Y593833D01*
G01Y593167D02*
X1135067Y593500D01*
X1134567Y593750D01*
X1133983Y593833D01*
X1133317Y593667D01*
X1132900Y593333D01*
X1132567Y592750D01*
X1132400Y592167D01*
X1132483Y591667D01*
X1132817Y591083D01*
X1133317Y590667D01*
X1133983Y590500D01*
X1134483Y590583D01*
X1135067Y590917D01*
X1135400Y591250D01*
G01X1139500Y593833D02*
Y590500D01*
G01Y595167D02*
X1139333Y595250D01*
Y595417D01*
X1139500Y595500D01*
X1139667Y595417D01*
Y595250D01*
X1139500Y595167D01*
G01X1143683Y590500D02*
Y593833D01*
G01Y593000D02*
X1144017Y593417D01*
X1144517Y593750D01*
X1145183Y593833D01*
X1145767Y593750D01*
X1146267Y593417D01*
X1146517Y592833D01*
Y590500D01*
G01X1149533Y589250D02*
X1150117Y588917D01*
X1150783Y588833D01*
X1151367Y588917D01*
X1151867Y589333D01*
X1152200Y589917D01*
Y593833D01*
G01Y593167D02*
X1151867Y593500D01*
X1151367Y593750D01*
X1150783Y593833D01*
X1150117Y593667D01*
X1149700Y593333D01*
X1149367Y592750D01*
X1149200Y592167D01*
X1149283Y591667D01*
X1149617Y591083D01*
X1150117Y590667D01*
X1150783Y590500D01*
X1151283Y590583D01*
X1151867Y590917D01*
X1152200Y591250D01*
G01X1163233Y593417D02*
X1162650Y593750D01*
X1162150Y593833D01*
X1161483Y593667D01*
X1160983Y593333D01*
X1160650Y592750D01*
X1160567Y592167D01*
X1160650Y591583D01*
X1160983Y591083D01*
X1161483Y590667D01*
X1162150Y590500D01*
X1162733Y590667D01*
X1163233Y591000D01*
G01X1166333Y590500D02*
Y593833D01*
G01Y593167D02*
X1166750Y593500D01*
X1167167Y593750D01*
X1167750Y593833D01*
X1168167Y593750D01*
X1168667Y593500D01*
G01X1173100Y593833D02*
Y590500D01*
G01Y595167D02*
X1172933Y595250D01*
Y595417D01*
X1173100Y595500D01*
X1173267Y595417D01*
Y595250D01*
X1173100Y595167D01*
G01X1178700Y595500D02*
Y590500D01*
G01X1177533Y593833D02*
X1179867D01*
G01X1183050Y592750D02*
X1185717D01*
X1185467Y593333D01*
X1185050Y593667D01*
X1184467Y593833D01*
X1183883Y593750D01*
X1183383Y593500D01*
X1183050Y592917D01*
X1182883Y592417D01*
Y591917D01*
X1183050Y591417D01*
X1183467Y590917D01*
X1183967Y590583D01*
X1184550Y590500D01*
X1185133Y590667D01*
X1185717Y591167D01*
G01X1188733Y590500D02*
Y593833D01*
G01Y593167D02*
X1189150Y593500D01*
X1189567Y593750D01*
X1190150Y593833D01*
X1190567Y593750D01*
X1191067Y593500D01*
G01X1195500Y593833D02*
Y590500D01*
G01Y595167D02*
X1195333Y595250D01*
Y595417D01*
X1195500Y595500D01*
X1195667Y595417D01*
Y595250D01*
X1195500Y595167D01*
G01X1202600Y590500D02*
Y593833D01*
G01Y593250D02*
X1202267Y593583D01*
X1201767Y593750D01*
X1201183Y593833D01*
X1200600Y593667D01*
X1200100Y593333D01*
X1199767Y592833D01*
X1199600Y592167D01*
X1199767Y591500D01*
X1200100Y591000D01*
X1200600Y590667D01*
X1201183Y590500D01*
X1201767Y590583D01*
X1202267Y590833D01*
X1202600Y591167D01*
G01X1106417Y735500D02*
X1108500Y730500D01*
X1110583Y735500D01*
G01X1113100D02*
X1115100D01*
G01X1114100D02*
Y730500D01*
G01X1113100D02*
X1115100D01*
G01X1118033D02*
Y735500D01*
X1120033D01*
X1120700Y735250D01*
X1121200Y734667D01*
X1121367Y734000D01*
X1121200Y733333D01*
X1120783Y732833D01*
X1120033Y732583D01*
X1118033D01*
G01X1136167Y157700D02*
Y162700D01*
X1137833D01*
X1138500Y162450D01*
X1139000Y162117D01*
X1139417Y161617D01*
X1139750Y161033D01*
X1139833Y160200D01*
X1139750Y159367D01*
X1139417Y158783D01*
X1139000Y158283D01*
X1138500Y157950D01*
X1137833Y157700D01*
X1136167D01*
G01X1142017Y161867D02*
X1142517Y162367D01*
X1143100Y162617D01*
X1143767Y162700D01*
X1144600Y162533D01*
X1145183Y162117D01*
X1145350Y161617D01*
X1145267Y161117D01*
X1144933Y160700D01*
X1143267Y159867D01*
X1142517Y159283D01*
X1142017Y158450D01*
X1141850Y157700D01*
X1145350D01*
G01X1135167Y315700D02*
Y320700D01*
X1136833D01*
X1137500Y320450D01*
X1138000Y320117D01*
X1138417Y319617D01*
X1138750Y319033D01*
X1138833Y318200D01*
X1138750Y317367D01*
X1138417Y316783D01*
X1138000Y316283D01*
X1137500Y315950D01*
X1136833Y315700D01*
X1135167D01*
G01X1142600D02*
Y320700D01*
X1141600Y319700D01*
G01Y315700D02*
X1143600D01*
G01X1136833Y619917D02*
X1136250Y620250D01*
X1135750Y620333D01*
X1135083Y620167D01*
X1134583Y619833D01*
X1134250Y619250D01*
X1134167Y618667D01*
X1134250Y618083D01*
X1134583Y617583D01*
X1135083Y617167D01*
X1135750Y617000D01*
X1136333Y617167D01*
X1136833Y617500D01*
G01X1141100Y617000D02*
X1140600Y617083D01*
X1140100Y617417D01*
X1139767Y618000D01*
X1139600Y618667D01*
X1139767Y619333D01*
X1140100Y619917D01*
X1140600Y620250D01*
X1141100Y620333D01*
X1141600Y620250D01*
X1142100Y619917D01*
X1142433Y619333D01*
X1142517Y618667D01*
X1142433Y618000D01*
X1142100Y617417D01*
X1141600Y617083D01*
X1141100Y617000D01*
G01X1145200Y615333D02*
Y620333D01*
G01Y619583D02*
X1145617Y620000D01*
X1146033Y620250D01*
X1146700Y620333D01*
X1147283Y620250D01*
X1147867Y619833D01*
X1148117Y619250D01*
X1148200Y618667D01*
X1148117Y618083D01*
X1147867Y617500D01*
X1147367Y617167D01*
X1146700Y617000D01*
X1146117Y617083D01*
X1145533Y617333D01*
X1145200Y617667D01*
G01X1150800Y615333D02*
Y620333D01*
G01Y619583D02*
X1151217Y620000D01*
X1151633Y620250D01*
X1152300Y620333D01*
X1152883Y620250D01*
X1153467Y619833D01*
X1153717Y619250D01*
X1153800Y618667D01*
X1153717Y618083D01*
X1153467Y617500D01*
X1152967Y617167D01*
X1152300Y617000D01*
X1151717Y617083D01*
X1151133Y617333D01*
X1150800Y617667D01*
G01X1156650Y619250D02*
X1159317D01*
X1159067Y619833D01*
X1158650Y620167D01*
X1158067Y620333D01*
X1157483Y620250D01*
X1156983Y620000D01*
X1156650Y619417D01*
X1156483Y618917D01*
Y618417D01*
X1156650Y617917D01*
X1157067Y617417D01*
X1157567Y617083D01*
X1158150Y617000D01*
X1158733Y617167D01*
X1159317Y617667D01*
G01X1162333Y617000D02*
Y620333D01*
G01Y619667D02*
X1162750Y620000D01*
X1163167Y620250D01*
X1163750Y620333D01*
X1164167Y620250D01*
X1164667Y620000D01*
G01X1184667Y150367D02*
X1185000Y150617D01*
X1185250Y151033D01*
X1185417Y151617D01*
X1185250Y152117D01*
X1184917Y152450D01*
X1184333Y152700D01*
X1182083D01*
Y147700D01*
X1184833D01*
X1185417Y148033D01*
X1185750Y148533D01*
X1185917Y149117D01*
X1185750Y149700D01*
X1185250Y150200D01*
X1184667Y150367D01*
X1182083D01*
G01X1187517Y147700D02*
X1189600Y152700D01*
X1191683Y147700D01*
G01X1190933Y149450D02*
X1188267D01*
G01X1197033Y152283D02*
X1196533Y152533D01*
X1195950Y152700D01*
X1195283D01*
X1194533Y152450D01*
X1193950Y152033D01*
X1193533Y151533D01*
X1193200Y150700D01*
X1193117Y149950D01*
X1193283Y149200D01*
X1193533Y148700D01*
X1194033Y148200D01*
X1194617Y147867D01*
X1195200Y147700D01*
X1195783D01*
X1196367Y147867D01*
X1196867Y148117D01*
X1197283Y148450D01*
G01X1198967Y147700D02*
Y152700D01*
G01X1202133D02*
X1198967Y149617D01*
G01X1202633Y147700D02*
X1200383Y151033D01*
G01X1210167Y147700D02*
Y152700D01*
X1211833D01*
X1212500Y152450D01*
X1213000Y152117D01*
X1213417Y151617D01*
X1213750Y151033D01*
X1213833Y150200D01*
X1213750Y149367D01*
X1213417Y148783D01*
X1213000Y148283D01*
X1212500Y147950D01*
X1211833Y147700D01*
X1210167D01*
G01X1215933D02*
Y152700D01*
X1218017D01*
X1218683Y152450D01*
X1219100Y152117D01*
X1219267Y151450D01*
X1219100Y150783D01*
X1218600Y150367D01*
X1218017Y150117D01*
X1215933D01*
G01X1218017D02*
X1219267Y147700D01*
G01X1222200Y152700D02*
X1224200D01*
G01X1223200D02*
Y147700D01*
G01X1222200D02*
X1224200D01*
G01X1227133Y152700D02*
Y147700D01*
X1230467D01*
G01X1232733Y152700D02*
Y147700D01*
X1236067D01*
G01X1259900D02*
Y151033D01*
G01Y150117D02*
X1260150Y150533D01*
X1260567Y150867D01*
X1261150Y151033D01*
X1261733Y150867D01*
X1262150Y150533D01*
X1262400Y150117D01*
Y147700D01*
G01Y150117D02*
X1262650Y150533D01*
X1263067Y150867D01*
X1263650Y151033D01*
X1264233Y150867D01*
X1264650Y150533D01*
X1264900Y150033D01*
Y147700D01*
G01X1268000Y151033D02*
Y147700D01*
G01Y152367D02*
X1267833Y152450D01*
Y152617D01*
X1268000Y152700D01*
X1268167Y152617D01*
Y152450D01*
X1268000Y152367D01*
G01X1273600Y147700D02*
Y152700D01*
G01X1277950Y148283D02*
X1278367Y147950D01*
X1278950Y147700D01*
X1279450D01*
X1279950Y147867D01*
X1280283Y148117D01*
X1280450Y148450D01*
X1280367Y148950D01*
X1280033Y149200D01*
X1278533Y149700D01*
X1278200Y150283D01*
X1278367Y150700D01*
X1278700Y150950D01*
X1279200Y151033D01*
X1279700Y150950D01*
X1280200Y150700D01*
G01X1284383Y146033D02*
X1283550Y146867D01*
X1283133Y147700D01*
Y151033D01*
X1283550Y151867D01*
X1284383Y152700D01*
G01X1288483Y147700D02*
Y152700D01*
X1292317Y147700D01*
Y152700D01*
G01X1294333Y147700D02*
Y152700D01*
X1296333D01*
X1297000Y152450D01*
X1297500Y151867D01*
X1297667Y151200D01*
X1297500Y150533D01*
X1297083Y150033D01*
X1296333Y149783D01*
X1294333D01*
G01X1301600Y152700D02*
Y147700D01*
G01X1299683Y152700D02*
X1303517D01*
G01X1305450Y147700D02*
Y152700D01*
G01X1308950D02*
Y147700D01*
G01Y150200D02*
X1305450D01*
G01X1313217Y146033D02*
X1314050Y146867D01*
X1314467Y147700D01*
Y151033D01*
X1314050Y151867D01*
X1313217Y152700D01*
G01X1210333Y218700D02*
Y213700D01*
X1213667D01*
G01X1216350Y217033D02*
X1218850Y213700D01*
G01Y217033D02*
X1216350Y213700D01*
G01X1207333Y260500D02*
Y255500D01*
X1210667D01*
G01X1213183D02*
Y258833D01*
G01Y258000D02*
X1213517Y258417D01*
X1214017Y258750D01*
X1214683Y258833D01*
X1215267Y258750D01*
X1215767Y258417D01*
X1216017Y257833D01*
Y255500D01*
G01X1178750Y315500D02*
Y320500D01*
G01X1182250D02*
Y315500D01*
G01Y318000D02*
X1178750D01*
G01X1186100Y315500D02*
X1185433Y315583D01*
X1184850Y315917D01*
X1184350Y316417D01*
X1184017Y317000D01*
X1183850Y317667D01*
Y318333D01*
X1184017Y319000D01*
X1184350Y319583D01*
X1184850Y320083D01*
X1185433Y320417D01*
X1186100Y320500D01*
X1186767Y320417D01*
X1187350Y320083D01*
X1187850Y319583D01*
X1188183Y319000D01*
X1188350Y318333D01*
Y317667D01*
X1188183Y317000D01*
X1187850Y316417D01*
X1187350Y315917D01*
X1186767Y315583D01*
X1186100Y315500D01*
G01X1190033Y320500D02*
Y315500D01*
X1193367D01*
G01X1198967D02*
X1195633D01*
Y320500D01*
X1198967D01*
G01X1197633Y318083D02*
X1195633D01*
G01X1222800Y315500D02*
Y318833D01*
G01Y317917D02*
X1223050Y318333D01*
X1223467Y318667D01*
X1224050Y318833D01*
X1224633Y318667D01*
X1225050Y318333D01*
X1225300Y317917D01*
Y315500D01*
G01Y317917D02*
X1225550Y318333D01*
X1225967Y318667D01*
X1226550Y318833D01*
X1227133Y318667D01*
X1227550Y318333D01*
X1227800Y317833D01*
Y315500D01*
G01X1230900Y318833D02*
Y315500D01*
G01Y320167D02*
X1230733Y320250D01*
Y320417D01*
X1230900Y320500D01*
X1231067Y320417D01*
Y320250D01*
X1230900Y320167D01*
G01X1236500Y315500D02*
Y320500D01*
G01X1240850Y316083D02*
X1241267Y315750D01*
X1241850Y315500D01*
X1242350D01*
X1242850Y315667D01*
X1243183Y315917D01*
X1243350Y316250D01*
X1243267Y316750D01*
X1242933Y317000D01*
X1241433Y317500D01*
X1241100Y318083D01*
X1241267Y318500D01*
X1241600Y318750D01*
X1242100Y318833D01*
X1242600Y318750D01*
X1243100Y318500D01*
G01X1247283Y313833D02*
X1246450Y314667D01*
X1246033Y315500D01*
Y318833D01*
X1246450Y319667D01*
X1247283Y320500D01*
G01X1251633Y315500D02*
Y320500D01*
X1253633D01*
X1254300Y320250D01*
X1254800Y319667D01*
X1254967Y319000D01*
X1254800Y318333D01*
X1254383Y317833D01*
X1253633Y317583D01*
X1251633D01*
G01X1258900Y320500D02*
Y315500D01*
G01X1256983Y320500D02*
X1260817D01*
G01X1262750Y315500D02*
Y320500D01*
G01X1266250D02*
Y315500D01*
G01Y318000D02*
X1262750D01*
G01X1270517Y313833D02*
X1271350Y314667D01*
X1271767Y315500D01*
Y318833D01*
X1271350Y319667D01*
X1270517Y320500D01*
G01X1180417Y734500D02*
X1182500Y729500D01*
X1184583Y734500D01*
G01X1188100Y729500D02*
X1187433Y729583D01*
X1186850Y729917D01*
X1186350Y730417D01*
X1186017Y731000D01*
X1185850Y731667D01*
Y732333D01*
X1186017Y733000D01*
X1186350Y733583D01*
X1186850Y734083D01*
X1187433Y734417D01*
X1188100Y734500D01*
X1188767Y734417D01*
X1189350Y734083D01*
X1189850Y733583D01*
X1190183Y733000D01*
X1190350Y732333D01*
Y731667D01*
X1190183Y731000D01*
X1189850Y730417D01*
X1189350Y729917D01*
X1188767Y729583D01*
X1188100Y729500D01*
G01X1192033D02*
Y734500D01*
X1194033D01*
X1194700Y734250D01*
X1195200Y733667D01*
X1195367Y733000D01*
X1195200Y732333D01*
X1194783Y731833D01*
X1194033Y731583D01*
X1192033D01*
G01X1218250Y281583D02*
X1218667Y281250D01*
X1219250Y281000D01*
X1219750D01*
X1220250Y281167D01*
X1220583Y281417D01*
X1220750Y281750D01*
X1220667Y282250D01*
X1220333Y282500D01*
X1218833Y283000D01*
X1218500Y283583D01*
X1218667Y284000D01*
X1219000Y284250D01*
X1219500Y284333D01*
X1220000Y284250D01*
X1220500Y284000D01*
G01X1225100Y286000D02*
Y281000D01*
G01X1223933Y284333D02*
X1226267D01*
G01X1229283D02*
Y282000D01*
X1229617Y281417D01*
X1230117Y281083D01*
X1230700Y281000D01*
X1231283Y281083D01*
X1231783Y281417D01*
X1232117Y282000D01*
G01Y281000D02*
Y284333D01*
G01X1234800Y281000D02*
Y286000D01*
G01Y283500D02*
X1235217Y284000D01*
X1235717Y284250D01*
X1236217Y284333D01*
X1236967Y284167D01*
X1237467Y283833D01*
X1237800Y283250D01*
Y282583D01*
X1237633Y281917D01*
X1237300Y281417D01*
X1236717Y281083D01*
X1236217Y281000D01*
X1235717Y281083D01*
X1235217Y281333D01*
X1234800Y281750D01*
G01X1247500Y281000D02*
Y286000D01*
G01X1251850Y283250D02*
X1254517D01*
X1254267Y283833D01*
X1253850Y284167D01*
X1253267Y284333D01*
X1252683Y284250D01*
X1252183Y284000D01*
X1251850Y283417D01*
X1251683Y282917D01*
Y282417D01*
X1251850Y281917D01*
X1252267Y281417D01*
X1252767Y281083D01*
X1253350Y281000D01*
X1253933Y281167D01*
X1254517Y281667D01*
G01X1257283Y281000D02*
Y284333D01*
G01Y283500D02*
X1257617Y283917D01*
X1258117Y284250D01*
X1258783Y284333D01*
X1259367Y284250D01*
X1259867Y283917D01*
X1260117Y283333D01*
Y281000D01*
G01X1263133Y279750D02*
X1263717Y279417D01*
X1264383Y279333D01*
X1264967Y279417D01*
X1265467Y279833D01*
X1265800Y280417D01*
Y284333D01*
G01Y283667D02*
X1265467Y284000D01*
X1264967Y284250D01*
X1264383Y284333D01*
X1263717Y284167D01*
X1263300Y283833D01*
X1262967Y283250D01*
X1262800Y282667D01*
X1262883Y282167D01*
X1263217Y281583D01*
X1263717Y281167D01*
X1264383Y281000D01*
X1264883Y281083D01*
X1265467Y281417D01*
X1265800Y281750D01*
G01X1269900Y286000D02*
Y281000D01*
G01X1268733Y284333D02*
X1271067D01*
G01X1274083Y281000D02*
Y286000D01*
G01Y283583D02*
X1274500Y284000D01*
X1274917Y284250D01*
X1275583Y284333D01*
X1276083Y284250D01*
X1276667Y283917D01*
X1276917Y283417D01*
Y281000D01*
G01X1280017Y281917D02*
X1282183D01*
G01Y283417D02*
X1280017D01*
G01X1285117Y283083D02*
X1285700Y283667D01*
X1286200Y284000D01*
X1286867Y284167D01*
X1287450Y284000D01*
X1287867Y283667D01*
X1288200Y283167D01*
X1288283Y282583D01*
X1288200Y282083D01*
X1287867Y281583D01*
X1287367Y281167D01*
X1286783Y281000D01*
X1286117Y281167D01*
X1285533Y281667D01*
X1285200Y282417D01*
X1285117Y283250D01*
X1285283Y284333D01*
X1285533Y284917D01*
X1285950Y285500D01*
X1286533Y285917D01*
X1287117Y286000D01*
X1287700Y285833D01*
X1288117Y285417D01*
G01X1291383Y282667D02*
X1293383D01*
G01X1292300Y283750D02*
Y281583D01*
G01X1296400Y280833D02*
X1299400Y286000D01*
G01X1302417Y282667D02*
X1304583D01*
G01X1307267Y281750D02*
X1307767Y281333D01*
X1308350Y281083D01*
X1309100Y281000D01*
X1309850Y281167D01*
X1310433Y281500D01*
X1310850Y282083D01*
X1310933Y282750D01*
X1310767Y283417D01*
X1310350Y283833D01*
X1309767Y284167D01*
X1309183Y284250D01*
X1308600Y284167D01*
X1307850Y283833D01*
X1308100Y286000D01*
X1310350D01*
G01X1312200Y281000D02*
Y284333D01*
G01Y283417D02*
X1312450Y283833D01*
X1312867Y284167D01*
X1313450Y284333D01*
X1314033Y284167D01*
X1314450Y283833D01*
X1314700Y283417D01*
Y281000D01*
G01Y283417D02*
X1314950Y283833D01*
X1315367Y284167D01*
X1315950Y284333D01*
X1316533Y284167D01*
X1316950Y283833D01*
X1317200Y283333D01*
Y281000D01*
G01X1320300Y284333D02*
Y281000D01*
G01Y285667D02*
X1320133Y285750D01*
Y285917D01*
X1320300Y286000D01*
X1320467Y285917D01*
Y285750D01*
X1320300Y285667D01*
G01X1325900Y281000D02*
Y286000D01*
G01X1234540Y850500D02*
Y782000D01*
G01X1242793Y785443D02*
X1241960Y786277D01*
X1241543Y787110D01*
Y790443D01*
X1241960Y791277D01*
X1242793Y792110D01*
G01X1248810Y787110D02*
Y792110D01*
X1247810Y791110D01*
G01Y787110D02*
X1249810D01*
G01X1254410Y786943D02*
X1254243Y787027D01*
Y787193D01*
X1254410Y787277D01*
X1254577Y787193D01*
Y787027D01*
X1254410Y786943D01*
G01X1258427Y791277D02*
X1258927Y791777D01*
X1259510Y792027D01*
X1260177Y792110D01*
X1261010Y791943D01*
X1261593Y791527D01*
X1261760Y791027D01*
X1261677Y790527D01*
X1261343Y790110D01*
X1259677Y789277D01*
X1258927Y788693D01*
X1258427Y787860D01*
X1258260Y787110D01*
X1261760D01*
G01X1263110D02*
Y790443D01*
G01Y789527D02*
X1263360Y789943D01*
X1263777Y790277D01*
X1264360Y790443D01*
X1264943Y790277D01*
X1265360Y789943D01*
X1265610Y789527D01*
Y787110D01*
G01Y789527D02*
X1265860Y789943D01*
X1266277Y790277D01*
X1266860Y790443D01*
X1267443Y790277D01*
X1267860Y789943D01*
X1268110Y789443D01*
Y787110D01*
G01X1268710D02*
Y790443D01*
G01Y789527D02*
X1268960Y789943D01*
X1269377Y790277D01*
X1269960Y790443D01*
X1270543Y790277D01*
X1270960Y789943D01*
X1271210Y789527D01*
Y787110D01*
G01Y789527D02*
X1271460Y789943D01*
X1271877Y790277D01*
X1272460Y790443D01*
X1273043Y790277D01*
X1273460Y789943D01*
X1273710Y789443D01*
Y787110D01*
G01X1280243D02*
Y792110D01*
X1282410Y787943D01*
X1284577Y792110D01*
Y787110D01*
G01X1289510D02*
Y790443D01*
G01Y789860D02*
X1289177Y790193D01*
X1288677Y790360D01*
X1288093Y790443D01*
X1287510Y790277D01*
X1287010Y789943D01*
X1286677Y789443D01*
X1286510Y788777D01*
X1286677Y788110D01*
X1287010Y787610D01*
X1287510Y787277D01*
X1288093Y787110D01*
X1288677Y787193D01*
X1289177Y787443D01*
X1289510Y787777D01*
G01X1292360Y790443D02*
X1294860Y787110D01*
G01Y790443D02*
X1292360Y787110D01*
G01X1299627Y785443D02*
X1300460Y786277D01*
X1300877Y787110D01*
Y790443D01*
X1300460Y791277D01*
X1299627Y792110D01*
G01X1244877Y797230D02*
X1241543Y798897D01*
X1244877Y800563D01*
G01X1247727Y798147D02*
X1249893D01*
G01Y799647D02*
X1247727D01*
G01X1254410Y802230D02*
X1253743Y802063D01*
X1253243Y801647D01*
X1252910Y801147D01*
X1252660Y800480D01*
X1252577Y799730D01*
X1252660Y798980D01*
X1252910Y798313D01*
X1253243Y797813D01*
X1253743Y797397D01*
X1254410Y797230D01*
X1255077Y797397D01*
X1255577Y797813D01*
X1255910Y798313D01*
X1256160Y798980D01*
X1256243Y799730D01*
X1256160Y800480D01*
X1255910Y801147D01*
X1255577Y801647D01*
X1255077Y802063D01*
X1254410Y802230D01*
G01X1260010Y797063D02*
X1259843Y797147D01*
Y797313D01*
X1260010Y797397D01*
X1260177Y797313D01*
Y797147D01*
X1260010Y797063D01*
G01X1265443Y797230D02*
X1265610Y798313D01*
X1265860Y799230D01*
X1266193Y800063D01*
X1266610Y800980D01*
X1267277Y802230D01*
X1263943D01*
G01X1269377Y797980D02*
X1269877Y797563D01*
X1270460Y797313D01*
X1271210Y797230D01*
X1271960Y797397D01*
X1272543Y797730D01*
X1272960Y798313D01*
X1273043Y798980D01*
X1272877Y799647D01*
X1272460Y800063D01*
X1271877Y800397D01*
X1271293Y800480D01*
X1270710Y800397D01*
X1269960Y800063D01*
X1270210Y802230D01*
X1272460D01*
G01X1275310Y797063D02*
X1278310Y802230D01*
G01X1275310D02*
X1274810Y802063D01*
X1274560Y801813D01*
X1274393Y801313D01*
X1274560Y800813D01*
X1274810Y800563D01*
X1275310Y800397D01*
X1275810Y800563D01*
X1276060Y800813D01*
X1276227Y801313D01*
X1276060Y801813D01*
X1275810Y802063D01*
X1275310Y802230D01*
G01X1278310Y798897D02*
X1277810Y798730D01*
X1277560Y798480D01*
X1277393Y797980D01*
X1277560Y797480D01*
X1277810Y797230D01*
X1278310Y797063D01*
X1278810Y797230D01*
X1279060Y797480D01*
X1279227Y797980D01*
X1279060Y798480D01*
X1278810Y798730D01*
X1278310Y798897D01*
G01X1241083Y811667D02*
X1243083D01*
G01X1242000Y812750D02*
Y810583D01*
G01X1246100Y809833D02*
X1249100Y815000D01*
G01X1252117Y811667D02*
X1254283D01*
G01X1257217Y814167D02*
X1257717Y814667D01*
X1258300Y814917D01*
X1258967Y815000D01*
X1259800Y814833D01*
X1260383Y814417D01*
X1260550Y813917D01*
X1260467Y813417D01*
X1260133Y813000D01*
X1258467Y812167D01*
X1257717Y811583D01*
X1257217Y810750D01*
X1257050Y810000D01*
X1260550D01*
G01X1261900D02*
Y813333D01*
G01Y812417D02*
X1262150Y812833D01*
X1262567Y813167D01*
X1263150Y813333D01*
X1263733Y813167D01*
X1264150Y812833D01*
X1264400Y812417D01*
Y810000D01*
G01Y812417D02*
X1264650Y812833D01*
X1265067Y813167D01*
X1265650Y813333D01*
X1266233Y813167D01*
X1266650Y812833D01*
X1266900Y812333D01*
Y810000D01*
G01X1270000Y813333D02*
Y810000D01*
G01Y814667D02*
X1269833Y814750D01*
Y814917D01*
X1270000Y815000D01*
X1270167Y814917D01*
Y814750D01*
X1270000Y814667D01*
G01X1275600Y810000D02*
Y815000D01*
G01X1241083Y826667D02*
X1243083D01*
G01X1242000Y827750D02*
Y825583D01*
G01X1246100Y824833D02*
X1249100Y830000D01*
G01X1252117Y826667D02*
X1254283D01*
G01X1256967Y825750D02*
X1257467Y825333D01*
X1258050Y825083D01*
X1258800Y825000D01*
X1259550Y825167D01*
X1260133Y825500D01*
X1260550Y826083D01*
X1260633Y826750D01*
X1260467Y827417D01*
X1260050Y827833D01*
X1259467Y828167D01*
X1258883Y828250D01*
X1258300Y828167D01*
X1257550Y827833D01*
X1257800Y830000D01*
X1260050D01*
G01X1261900Y825000D02*
Y828333D01*
G01Y827417D02*
X1262150Y827833D01*
X1262567Y828167D01*
X1263150Y828333D01*
X1263733Y828167D01*
X1264150Y827833D01*
X1264400Y827417D01*
Y825000D01*
G01Y827417D02*
X1264650Y827833D01*
X1265067Y828167D01*
X1265650Y828333D01*
X1266233Y828167D01*
X1266650Y827833D01*
X1266900Y827333D01*
Y825000D01*
G01X1270000Y828333D02*
Y825000D01*
G01Y829667D02*
X1269833Y829750D01*
Y829917D01*
X1270000Y830000D01*
X1270167Y829917D01*
Y829750D01*
X1270000Y829667D01*
G01X1275600Y825000D02*
Y830000D01*
G01X1241083Y841667D02*
X1243083D01*
G01X1242000Y842750D02*
Y840583D01*
G01X1246100Y839833D02*
X1249100Y845000D01*
G01X1252117Y841667D02*
X1254283D01*
G01X1256967Y840750D02*
X1257467Y840333D01*
X1258050Y840083D01*
X1258800Y840000D01*
X1259550Y840167D01*
X1260133Y840500D01*
X1260550Y841083D01*
X1260633Y841750D01*
X1260467Y842417D01*
X1260050Y842833D01*
X1259467Y843167D01*
X1258883Y843250D01*
X1258300Y843167D01*
X1257550Y842833D01*
X1257800Y845000D01*
X1260050D01*
G01X1261900Y840000D02*
Y843333D01*
G01Y842417D02*
X1262150Y842833D01*
X1262567Y843167D01*
X1263150Y843333D01*
X1263733Y843167D01*
X1264150Y842833D01*
X1264400Y842417D01*
Y840000D01*
G01Y842417D02*
X1264650Y842833D01*
X1265067Y843167D01*
X1265650Y843333D01*
X1266233Y843167D01*
X1266650Y842833D01*
X1266900Y842333D01*
Y840000D01*
G01X1270000Y843333D02*
Y840000D01*
G01Y844667D02*
X1269833Y844750D01*
Y844917D01*
X1270000Y845000D01*
X1270167Y844917D01*
Y844750D01*
X1270000Y844667D01*
G01X1275600Y840000D02*
Y845000D01*
G01X1343000Y850610D02*
Y782110D01*
G54D12*
G01X865852Y712354D02*
Y635354D01*
G01X872727Y628479D02*
Y721979D01*
G01X857602Y628479D02*
X872727D01*
G01X857602Y635354D02*
Y628479D01*
G01X865852Y635354D02*
X843852D01*
G01D02*
Y712354D01*
G01D02*
X865852D01*
G01X857602Y721979D02*
Y715104D01*
G01X872727Y721979D02*
X857602D01*
G01X898852Y712354D02*
Y635354D01*
G01D02*
X942852D01*
G01X907102Y628479D02*
Y635354D01*
G01X891977Y628479D02*
X907102D01*
G01X891977Y721979D02*
Y628479D01*
G01X942852Y712354D02*
X898852D01*
G01X907102Y715104D02*
Y721979D01*
G01D02*
X891977D01*
G01X934602Y628479D02*
X949727D01*
G01X934602Y635354D02*
Y628479D01*
G01Y721979D02*
Y715104D01*
G01X949727Y721979D02*
X934602D01*
G01X968977Y628479D02*
X984102D01*
G01X968977Y721979D02*
Y628479D01*
G01X949727D02*
Y721979D01*
G01X942852Y635354D02*
Y712354D01*
G01X984102Y721979D02*
X968977D01*
G01X984102Y628479D02*
Y635354D01*
G01X975852Y712354D02*
Y635354D01*
G01D02*
X1019852D01*
G01Y712354D02*
X975852D01*
G01X984102Y715104D02*
Y721979D01*
G01X1026727Y628479D02*
Y719229D01*
G01X1019852Y635354D02*
Y712354D01*
G01X1011602Y628479D02*
X1026727D01*
G01X1011602Y635354D02*
Y628479D01*
G01Y719229D02*
Y712354D01*
G01X1026727Y719229D02*
X1011602D01*
G01X1061102Y628479D02*
Y635354D01*
G01X1045977Y628479D02*
X1061102D01*
G01X1045977Y719229D02*
Y628479D01*
G01X1052852Y712354D02*
Y635354D01*
G01D02*
X1096852D01*
G01X1061102Y712354D02*
Y719229D01*
G01X1096852Y712354D02*
X1052852D01*
G01X1061102Y719229D02*
X1045977D01*
G01X1096852Y635354D02*
Y712354D01*
G01X1088602Y628479D02*
X1122977D01*
G01X1088602Y635354D02*
Y628479D01*
G01Y719229D02*
Y712354D01*
G01X1138102Y719229D02*
X1103727D01*
G01D02*
X1088602D01*
G01X1129852Y712354D02*
Y635354D01*
G01D02*
X1173852D01*
G01X1138102Y628479D02*
Y635354D01*
G01X1122977Y628479D02*
X1138102D01*
G01X1173852Y712354D02*
X1129852D01*
G01X1138102D02*
Y719229D01*
G01X1165602Y628479D02*
X1180727D01*
G01X1165602Y635354D02*
Y628479D01*
G01X1173852Y635354D02*
Y712354D01*
G01X1165602Y719229D02*
Y712354D01*
G01X1180727Y719229D02*
X1165602D01*
G01X1206852Y712354D02*
Y635354D01*
G01D02*
X1250852D01*
G01X1199977Y628479D02*
X1215102D01*
G01X1199977Y719229D02*
Y628479D01*
G01X1180727D02*
Y719229D01*
G01X1250852Y712354D02*
X1206852D01*
G01X1215102Y719229D02*
X1199977D01*
G01X1215102Y628479D02*
Y635354D01*
G01Y712354D02*
Y719229D01*
G01X1250852Y635354D02*
Y712354D01*
G54D13*
G01X292090Y340830D02*
Y357830D01*
G01X303090Y319830D02*
Y303830D01*
G01X341590Y319830D02*
Y303830D01*
G01X352590Y340830D02*
Y357830D01*
G01X356482Y330153D02*
X352452Y324663D01*
X356652Y324643D01*
G01X345680Y327680D02*
G02X350362Y319860I-4190J-7820D01*
G01X348190Y321780D01*
X351420Y321950D01*
X350460Y319850D01*
G01X439562Y301543D02*
X435532Y296053D01*
X439732Y296033D01*
G54D14*
G01X875080Y677966D02*
X873002Y680044D01*
G01X874045Y676668D02*
X873002Y677711D01*
G01X873215Y675163D02*
X873002Y675377D01*
G01Y676905D02*
X891702Y695603D01*
G01X873002Y679238D02*
X891702Y697938D01*
G01X873002Y681571D02*
X891702Y700271D01*
G01X873002Y674644D02*
Y719229D01*
G01Y674645D02*
Y674644D01*
G01X891701Y674645D02*
G03X873003I-9349J-3541D01*
G01X891702Y696346D02*
X873002Y715046D01*
G01X891702Y694013D02*
X873002Y712712D01*
G01X891702Y691679D02*
X873002Y710379D01*
G01X891702Y689346D02*
X873002Y708046D01*
G01X891702Y687012D02*
X873002Y705711D01*
G01X891702Y684678D02*
X873002Y703378D01*
G01X891702Y682345D02*
X873002Y701045D01*
G01X891702Y680012D02*
X873002Y698711D01*
G01X857327Y714387D02*
X853752Y717961D01*
G01X856750Y712629D02*
X853752Y715628D01*
G01X854417Y712629D02*
X853752Y713295D01*
G01X873002Y690905D02*
X891702Y709604D01*
G01X873002Y693238D02*
X891702Y711938D01*
G01X873002Y695572D02*
X891702Y714272D01*
G01X873002Y697906D02*
X891702Y716605D01*
G01X873002Y700239D02*
X891702Y718939D01*
G01X873002Y702572D02*
X896258Y725829D01*
G01X873002Y704906D02*
X893925Y725829D01*
G01X873002Y707239D02*
X885106Y719344D01*
G01X873002Y709572D02*
X882382Y718952D01*
G01X873002Y711907D02*
X880270Y719174D01*
G01X873002Y714240D02*
X878496Y719734D01*
G01X855058Y712629D02*
X857327Y714899D01*
G01X853752Y713657D02*
X857327Y717232D01*
G01X853752Y712629D02*
Y723240D01*
G01X857327Y712629D02*
X853752D01*
G01X857327Y719504D02*
Y712629D01*
G01X891702Y677678D02*
X873002Y696378D01*
G01X887198Y679848D02*
X873002Y694045D01*
G01X883703Y681010D02*
X873002Y691711D01*
G01X881330Y681049D02*
X873002Y689377D01*
G01X879392Y680653D02*
X873002Y687044D01*
G01X877738Y679974D02*
X873002Y684711D01*
G01X876310Y679069D02*
X873002Y682377D01*
G01Y683905D02*
X891702Y702604D01*
G01X873002Y686238D02*
X891702Y704938D01*
G01X873002Y688571D02*
X891702Y707271D01*
G01X856340Y725829D02*
X872925D01*
G01X874327Y723054D02*
X871552Y725829D01*
G01X891702Y703346D02*
X869219Y725829D01*
G01X891702Y701013D02*
X866886Y725829D01*
G01X891702Y698679D02*
X873002Y717379D01*
G01X871152Y719229D02*
X864552Y725829D01*
G01X868819Y719229D02*
X862219Y725829D01*
G01X866485Y719229D02*
X859885Y725829D01*
G01X864151Y719229D02*
X857551Y725829D01*
G01X861818Y719229D02*
X855779Y725267D01*
G01X859485Y719229D02*
X854613Y724101D01*
G01X857327Y719053D02*
X853752Y722628D01*
G01X857327Y716720D02*
X853752Y720295D01*
G01X873002Y716573D02*
X876971Y720542D01*
G01X873002Y718907D02*
X875655Y721560D01*
G01X870991Y719229D02*
X874536Y722775D01*
G01X868658Y719229D02*
X873618Y724189D01*
G01X866324Y719229D02*
X872924Y725829D01*
G01X863991Y719229D02*
X870591Y725829D01*
G01X861658Y719229D02*
X868258Y725829D01*
G01X859323Y719229D02*
X865923Y725829D01*
G01X853752Y715991D02*
X863590Y725829D01*
G01X853752Y718324D02*
X861257Y725829D01*
G01X853752Y720657D02*
X858923Y725829D01*
G01X853752Y722991D02*
X856590Y725829D01*
G01X872925D02*
G03X891779I9427J3024D01*
G01X853752Y723240D02*
X856340Y725829D01*
G01X857602Y719229D02*
X857327Y719504D01*
G01X873002Y719229D02*
X857602D01*
G01X891702Y675345D02*
X891096Y675951D01*
G01X890957Y676193D02*
X891702Y676936D01*
G01X889988Y677557D02*
X891702Y679270D01*
G01X888823Y678725D02*
X891702Y681604D01*
G01X887462Y679697D02*
X891702Y683937D01*
G01X885887Y680455D02*
X891702Y686270D01*
G01X884054Y680956D02*
X891702Y688604D01*
G01X881854Y681089D02*
X891702Y690937D01*
G01Y674644D02*
X891701Y674645D01*
G01X891702Y719229D02*
Y674644D01*
G01X878929Y680497D02*
X891702Y693270D01*
G01X908086Y712629D02*
X907377Y713339D01*
G01X891702Y715014D02*
X886738Y719977D01*
G01X891702Y712680D02*
X885053Y719328D01*
G01X891702Y710347D02*
X883070Y718978D01*
G01X891702Y708014D02*
X880607Y719107D01*
G01X907377Y713613D02*
X919592Y725828D01*
G01X891702Y705679D02*
X876553Y720829D01*
G01X891779Y725829D02*
X949925D01*
G01X919754Y712629D02*
X906554Y725829D01*
G01X917420Y712629D02*
X904221Y725829D01*
G01X915087Y712629D02*
X901887Y725829D01*
G01X912754Y712629D02*
X907377Y718006D01*
G01X905840Y719543D02*
X899554Y725829D01*
G01X910421Y712629D02*
X907377Y715673D01*
G01X903507Y719543D02*
X897221Y725829D01*
G01X901173Y719543D02*
X894886Y725829D01*
G01X898840Y719543D02*
X892553Y725829D01*
G01X896507Y719543D02*
X891342Y724707D01*
G01X894172Y719543D02*
X890494Y723221D01*
G01X891927Y719455D02*
X889440Y721942D01*
G01X891702Y717347D02*
X888191Y720857D01*
G01X907377Y715946D02*
X917259Y725829D01*
G01X907377Y718280D02*
X914926Y725829D01*
G01X906307Y719543D02*
X912592Y725828D01*
G01X903972Y719543D02*
X910259Y725829D01*
G01X901639Y719543D02*
X907926Y725829D01*
G01X899306Y719543D02*
X905593Y725829D01*
G01X896972Y719543D02*
X903258Y725829D01*
G01X894639Y719543D02*
X900925Y725829D01*
G01X892306Y719543D02*
X898592Y725829D01*
G01X892015Y719543D02*
X891702Y719229D01*
G01X907157Y719543D02*
X892015D01*
G01X907377Y719504D02*
X907157Y719543D01*
G01X934327Y635053D02*
X934300Y635079D01*
G01X934327Y632720D02*
X931967Y635079D01*
G01X934327Y630387D02*
X930752Y633961D01*
G01X933037Y624933D02*
X936307Y628204D01*
G01X931869Y626100D02*
X934327Y628556D01*
G01X930752Y627315D02*
X934327Y630890D01*
G01X930752Y629649D02*
X934327Y633224D01*
G01X930752Y631983D02*
X933848Y635079D01*
G01X930752Y634316D02*
X931515Y635079D01*
G01X934327Y628204D02*
X950002D01*
G01X934327Y635079D02*
Y628204D01*
G01X930752Y635079D02*
X934327D01*
G01X930752Y627218D02*
Y635079D01*
G01X942417Y624629D02*
X938842Y628204D01*
G01X940084Y624629D02*
X936509Y628204D01*
G01X937750Y624629D02*
X930752Y631627D01*
G01X935417Y624629D02*
X930752Y629294D01*
G01X939733Y624629D02*
X943307Y628204D01*
G01X937399Y624629D02*
X940974Y628203D01*
G01X935066Y624629D02*
X938640Y628203D01*
G01X985362Y624629D02*
X933340D01*
G01D02*
X930752Y627218D01*
G01X934327Y714390D02*
X922888Y725829D01*
G01X933755Y712629D02*
X920555Y725829D01*
G01X931422Y712629D02*
X918222Y725829D01*
G01X929088Y712629D02*
X915888Y725829D01*
G01X926754Y712629D02*
X913554Y725829D01*
G01X932061Y712629D02*
X934327Y714894D01*
G01X929728Y712629D02*
X934327Y717228D01*
G01X927395Y712629D02*
X940595Y725829D01*
G01X925062Y712629D02*
X938260Y725829D01*
G01X922727Y712629D02*
X935927Y725829D01*
G01X920394Y712629D02*
X933594Y725829D01*
G01X918061Y712629D02*
X931260Y725829D01*
G01X915727Y712629D02*
X928927Y725829D01*
G01X913394Y712629D02*
X926593Y725828D01*
G01X934327Y719504D02*
Y712629D01*
G01X924420D02*
X911221Y725829D01*
G01X922087Y712629D02*
X908887Y725829D01*
G01X911061Y712629D02*
X924260Y725829D01*
G01X908727Y712629D02*
X921927Y725829D01*
G01X907377Y712629D02*
Y719504D01*
G01X934327Y712629D02*
X907377D01*
G01X945548Y719504D02*
X939223Y725829D01*
G01X943214Y719504D02*
X936889Y725829D01*
G01X940881Y719504D02*
X934556Y725829D01*
G01X938546Y719504D02*
X932223Y725829D01*
G01X936213Y719504D02*
X929888Y725829D01*
G01X934327Y719058D02*
X927555Y725829D01*
G01X934327Y716725D02*
X925222Y725829D01*
G01X938936Y719504D02*
X945261Y725829D01*
G01X936603Y719504D02*
X942928Y725829D01*
G01X950002Y719504D02*
X934327D01*
G01X968702Y647348D02*
X950002Y666048D01*
G01X968702Y645013D02*
X950002Y663713D01*
G01X968702Y642680D02*
X950002Y661380D01*
G01X968702Y640347D02*
X950002Y659047D01*
G01X968702Y638014D02*
X950002Y656713D01*
G01X968702Y635680D02*
X950002Y654380D01*
G01X968702Y633347D02*
X950002Y652047D01*
G01X968702Y631014D02*
X950002Y649713D01*
G01X968702Y628679D02*
X950002Y647379D01*
G01Y630232D02*
X968702Y648932D01*
G01X950002Y632565D02*
X968702Y651265D01*
G01X950002Y634898D02*
X968702Y653598D01*
G01X950002Y637232D02*
X968702Y655931D01*
G01X950002Y639565D02*
X968702Y658265D01*
G01X950002Y641898D02*
X968702Y660598D01*
G01X950002Y644232D02*
X968702Y662931D01*
G01X950002Y646565D02*
X968702Y665265D01*
G01Y628204D02*
X984377D01*
G01X968702Y719504D02*
Y628204D01*
G01X950002D02*
Y719504D01*
G01X977419Y624629D02*
X973844Y628204D01*
G01X975085Y624629D02*
X971511Y628204D01*
G01X972752Y624629D02*
X969177Y628204D01*
G01X970419Y624629D02*
X950002Y645046D01*
G01X968086Y624629D02*
X950002Y642712D01*
G01X965752Y624629D02*
X950002Y640379D01*
G01X963419Y624629D02*
X950002Y638046D01*
G01X961085Y624629D02*
X950002Y635712D01*
G01X958751Y624629D02*
X950002Y633379D01*
G01X956418Y624629D02*
X950002Y631046D01*
G01X954085Y624629D02*
X950002Y628711D01*
G01X951751Y624629D02*
X948176Y628204D01*
G01X974734Y624629D02*
X978309Y628204D01*
G01X972401Y624629D02*
X975976Y628204D01*
G01X970068Y624629D02*
X973643Y628204D01*
G01X967734Y624629D02*
X971309Y628204D01*
G01X965401Y624629D02*
X968976Y628204D01*
G01X963068Y624629D02*
X968702Y630263D01*
G01X960733Y624629D02*
X968702Y632597D01*
G01X958400Y624629D02*
X968702Y634931D01*
G01X956067Y624629D02*
X968702Y637264D01*
G01X953733Y624629D02*
X968702Y639597D01*
G01X951400Y624629D02*
X968702Y641931D01*
G01X949067Y624629D02*
X968702Y644264D01*
G01X946733Y624629D02*
X968702Y646597D01*
G01X949418Y624629D02*
X945843Y628204D01*
G01X947085Y624629D02*
X943510Y628204D01*
G01X944750Y624629D02*
X941175Y628204D01*
G01X944400Y624629D02*
X947975Y628204D01*
G01X942066Y624629D02*
X945640Y628203D01*
G01X968702Y680015D02*
X950002Y698715D01*
G01X968702Y677682D02*
X950002Y696382D01*
G01X968702Y675349D02*
X950002Y694048D01*
G01X968702Y673015D02*
X950002Y691715D01*
G01X968702Y670682D02*
X950002Y689382D01*
G01X968702Y668349D02*
X950002Y687048D01*
G01X968702Y666015D02*
X950002Y684715D01*
G01X968702Y663681D02*
X950002Y682381D01*
G01X968702Y661348D02*
X950002Y680047D01*
G01X968702Y659014D02*
X950002Y677714D01*
G01Y658233D02*
X968702Y676932D01*
G01X950002Y660566D02*
X968702Y679266D01*
G01X950002Y662899D02*
X968702Y681599D01*
G01X950002Y665234D02*
X968702Y683932D01*
G01X950002Y667567D02*
X968702Y686267D01*
G01X950002Y669900D02*
X968702Y688600D01*
G01X950002Y672234D02*
X968702Y690933D01*
G01X950002Y674567D02*
X968702Y693267D01*
G01X950002Y676900D02*
X968702Y695600D01*
G01X950002Y679233D02*
X968702Y697933D01*
G01X950002Y681567D02*
X968702Y700267D01*
G01Y656681D02*
X950002Y675381D01*
G01X968702Y654348D02*
X950002Y673048D01*
G01X968702Y652014D02*
X950002Y670714D01*
G01X968702Y649681D02*
X950002Y668381D01*
G01Y648899D02*
X968702Y667599D01*
G01X950002Y651233D02*
X968702Y669932D01*
G01X950002Y653566D02*
X968702Y672266D01*
G01X950002Y655899D02*
X968702Y674599D01*
G01Y715017D02*
X963741Y719978D01*
G01X968702Y712684D02*
X962057Y719329D01*
G01X968702Y710350D02*
X960073Y718978D01*
G01X968702Y708017D02*
X957613Y719106D01*
G01X968702Y705684D02*
X953567Y720819D01*
G01X968702Y698683D02*
X950002Y717383D01*
G01X968702Y696350D02*
X950002Y715049D01*
G01X968702Y694016D02*
X950002Y712716D01*
G01X968702Y691683D02*
X950002Y710383D01*
G01Y690901D02*
X968702Y709601D01*
G01X950002Y693234D02*
X968702Y711934D01*
G01X950002Y695568D02*
X968702Y714267D01*
G01X950002Y697901D02*
X968702Y716601D01*
G01X950002Y700234D02*
X968702Y718934D01*
G01X950002Y702569D02*
X973262Y725828D01*
G01X950002Y704902D02*
X970929Y725829D01*
G01X950002Y707235D02*
X962112Y719345D01*
G01X950002Y709569D02*
X959386Y718952D01*
G01X950002Y711902D02*
X957273Y719173D01*
G01X950002Y714235D02*
X955499Y719733D01*
G01X968702Y689350D02*
X950002Y708049D01*
G01X968702Y687016D02*
X950002Y705716D01*
G01X968702Y684683D02*
X950002Y703383D01*
G01X968702Y682350D02*
X950002Y701048D01*
G01Y683901D02*
X968702Y702601D01*
G01X950002Y686234D02*
X968702Y704934D01*
G01X950002Y688568D02*
X968702Y707268D01*
G01Y703350D02*
X946222Y725829D01*
G01X968702Y701017D02*
X943889Y725829D01*
G01X968779D02*
X985362D01*
G01X980549Y719504D02*
X974224Y725829D01*
G01X978216Y719504D02*
X971891Y725829D01*
G01X975883Y719504D02*
X969558Y725829D01*
G01X973548Y719504D02*
X968343Y724709D01*
G01X971215Y719504D02*
X967496Y723223D01*
G01X968882Y719504D02*
X966442Y721943D01*
G01X968702Y717350D02*
X965193Y720859D01*
G01X951317Y723067D02*
X948556Y725829D01*
G01X973938Y719504D02*
X980263Y725829D01*
G01X971605Y719504D02*
X977930Y725829D01*
G01X969271Y719504D02*
X975596Y725829D01*
G01X950002Y716569D02*
X953974Y720540D01*
G01X950002Y718903D02*
X952657Y721558D01*
G01X948269Y719504D02*
X951539Y722772D01*
G01X984377Y719504D02*
X968702D01*
G01X949925Y725829D02*
G03X968779I9427J3024D01*
G01X947881Y719504D02*
X941556Y725829D01*
G01X945936Y719504D02*
X950619Y724187D01*
G01X943603Y719504D02*
X949925Y725826D01*
G01X941270Y719504D02*
X947595Y725829D01*
G01X987952Y632764D02*
X985637Y635078D01*
G01X987952Y630431D02*
X984377Y634006D01*
G01X987952Y628098D02*
X984377Y631673D01*
G01X987225Y626490D02*
X984377Y629338D01*
G01X986058Y625324D02*
X983178Y628204D01*
G01X984377Y629605D02*
X987952Y633180D01*
G01X984377Y631938D02*
X987517Y635079D01*
G01X984377Y634272D02*
X985184Y635079D01*
G01X987952D02*
Y627218D01*
G01X984377Y635079D02*
X987952D01*
G01X984377Y628204D02*
Y635079D01*
G01X984420Y624629D02*
X980845Y628204D01*
G01X984069Y624629D02*
X987952Y628512D01*
G01X981735Y624629D02*
X987952Y630845D01*
G01X979402Y624629D02*
X982977Y628204D01*
G01X987952Y627218D02*
X985362Y624629D01*
G01X982086D02*
X978512Y628204D01*
G01X979752Y624629D02*
X976177Y628204D01*
G01X977068Y624629D02*
X980642Y628204D01*
G01X987952Y714435D02*
X984377Y718009D01*
G01X987424Y712629D02*
X984377Y715676D01*
G01X985091Y712629D02*
X984377Y713343D01*
G01X985731Y712629D02*
X987952Y714850D01*
G01X984377Y713608D02*
X987952Y717183D01*
G01X984377Y712629D02*
Y719504D01*
G01X987952Y712629D02*
X984377D01*
G01X987952Y723240D02*
Y712629D01*
G01Y721436D02*
X983558Y725829D01*
G01X987952Y719102D02*
X981224Y725829D01*
G01X984377Y715942D02*
X987952Y719517D01*
G01X984377Y718276D02*
X987952Y721851D01*
G01X983271Y719504D02*
X987480Y723712D01*
G01X980938Y719504D02*
X986313Y724879D01*
G01X985362Y725829D02*
X987952Y723240D01*
G01Y716769D02*
X978891Y725829D01*
G01X982883Y719504D02*
X976558Y725829D01*
G01X978605Y719504D02*
X984930Y725829D01*
G01X976271Y719504D02*
X982596Y725829D01*
G01X1108990Y632879D02*
X1122702Y646590D01*
G01X1106657Y632879D02*
X1122702Y648923D01*
G01X1104324Y632879D02*
X1122702Y651257D01*
G01X1104002Y634890D02*
X1122702Y653590D01*
G01X1104002Y637224D02*
X1122702Y655923D01*
G01X1104002Y639557D02*
X1122702Y658257D01*
G01X1104002Y641890D02*
X1122702Y660590D01*
G01X1104002Y644225D02*
X1122702Y662924D01*
G01X1104002Y646558D02*
X1122702Y665258D01*
G01Y633354D02*
X1104002Y652054D01*
G01X1120844Y632879D02*
X1104002Y649720D01*
G01X1118510Y632879D02*
X1104002Y647387D01*
G01X1116177Y632879D02*
X1104002Y645054D01*
G01X1113844Y632879D02*
X1104002Y642720D01*
G01X1111509Y632879D02*
X1104002Y640387D01*
G01X1109176Y632879D02*
X1104002Y638054D01*
G01X1106843Y632879D02*
X1104002Y635721D01*
G01X1104509Y632879D02*
X1104002Y633386D01*
G01X1122702Y632879D02*
X1104002D01*
G01D02*
Y714829D01*
G01Y658224D02*
X1122702Y676924D01*
G01X1104002Y660559D02*
X1122702Y679259D01*
G01X1104002Y662892D02*
X1122702Y681592D01*
G01X1104002Y665225D02*
X1122702Y683925D01*
G01X1104002Y667559D02*
X1122702Y686258D01*
G01X1104002Y669892D02*
X1122702Y688592D01*
G01X1104002Y672225D02*
X1122702Y690925D01*
G01X1104002Y674559D02*
X1122702Y693258D01*
G01X1104002Y676892D02*
X1122702Y695592D01*
G01X1104002Y679226D02*
X1122702Y697926D01*
G01X1104002Y681560D02*
X1122702Y700259D01*
G01Y666022D02*
X1104002Y684722D01*
G01X1122702Y663689D02*
X1104002Y682389D01*
G01X1122702Y661356D02*
X1104002Y680056D01*
G01X1122702Y659023D02*
X1104002Y677722D01*
G01X1122702Y656689D02*
X1104002Y675389D01*
G01X1122702Y654356D02*
X1104002Y673056D01*
G01X1122702Y652023D02*
X1104002Y670721D01*
G01X1122702Y649688D02*
X1104002Y668388D01*
G01X1122702Y647355D02*
X1104002Y666055D01*
G01Y648891D02*
X1122702Y667591D01*
G01X1104002Y651225D02*
X1122702Y669924D01*
G01X1104002Y653558D02*
X1122702Y672258D01*
G01X1104002Y655891D02*
X1122702Y674591D01*
G01Y645022D02*
X1104002Y663721D01*
G01X1122702Y642688D02*
X1104002Y661388D01*
G01X1122702Y640355D02*
X1104002Y659055D01*
G01X1122702Y638022D02*
X1104002Y656721D01*
G01X1122702Y635688D02*
X1104002Y654388D01*
G01Y690893D02*
X1122702Y709593D01*
G01X1104002Y693226D02*
X1122702Y711926D01*
G01X1104002Y695561D02*
X1122702Y714259D01*
G01X1104002Y697894D02*
X1120937Y714829D01*
G01X1104002Y700227D02*
X1118604Y714829D01*
G01X1104002Y702561D02*
X1116270Y714829D01*
G01X1104002Y704894D02*
X1113937Y714829D01*
G01X1104002Y707227D02*
X1111604Y714829D01*
G01X1104002Y709561D02*
X1109270Y714829D01*
G01X1104002Y711894D02*
X1106937Y714829D01*
G01X1104002Y714228D02*
X1104604Y714829D01*
G01X1122702Y701024D02*
X1108897Y714829D01*
G01X1122702Y698691D02*
X1106564Y714829D01*
G01X1122702Y696358D02*
X1104231Y714829D01*
G01X1122702Y694024D02*
X1104002Y712724D01*
G01X1122702Y691691D02*
X1104002Y710391D01*
G01X1122702Y689358D02*
X1104002Y708057D01*
G01X1122702Y687023D02*
X1104002Y705723D01*
G01X1122702Y684690D02*
X1104002Y703390D01*
G01X1122702Y682357D02*
X1104002Y701056D01*
G01X1122702Y680023D02*
X1104002Y698723D01*
G01Y714829D02*
X1122702D01*
G01X1104002Y683893D02*
X1122702Y702593D01*
G01X1104002Y686226D02*
X1122702Y704926D01*
G01X1104002Y688560D02*
X1122702Y707259D01*
G01Y677690D02*
X1104002Y696390D01*
G01X1122702Y675357D02*
X1104002Y694057D01*
G01X1122702Y673023D02*
X1104002Y691723D01*
G01X1122702Y670690D02*
X1104002Y689390D01*
G01X1122702Y668356D02*
X1104002Y687056D01*
G01X1120658Y632879D02*
X1122702Y634922D01*
G01X1118325Y632879D02*
X1122702Y637256D01*
G01X1115991Y632879D02*
X1122702Y639589D01*
G01X1113658Y632879D02*
X1122702Y641922D01*
G01X1111325Y632879D02*
X1122702Y644257D01*
G01Y714829D02*
Y632879D01*
G01Y712692D02*
X1120565Y714829D01*
G01X1122702Y710359D02*
X1118231Y714829D01*
G01X1122702Y708025D02*
X1115897Y714829D01*
G01X1122702Y705692D02*
X1113564Y714829D01*
G01X1122702Y703358D02*
X1111231Y714829D01*
G01X1197662Y632879D02*
X1199702Y634919D01*
G01X1195328Y632879D02*
X1199702Y637252D01*
G01X1192995Y632879D02*
X1199702Y639586D01*
G01X1190662Y632879D02*
X1199702Y641919D01*
G01X1188328Y632879D02*
X1199702Y644252D01*
G01X1185995Y632879D02*
X1199702Y646585D01*
G01X1183662Y632879D02*
X1199702Y648919D01*
G01X1181327Y632879D02*
X1199702Y651253D01*
G01X1181002Y634887D02*
X1199702Y653586D01*
G01X1181002Y637220D02*
X1199702Y655920D01*
G01X1181002Y639553D02*
X1199702Y658253D01*
G01X1181002Y641887D02*
X1199702Y660586D01*
G01X1181002Y644220D02*
X1199702Y662920D01*
G01X1181002Y646553D02*
X1199702Y665253D01*
G01Y647360D02*
X1181002Y666059D01*
G01X1199702Y645025D02*
X1181002Y663725D01*
G01X1199702Y642692D02*
X1181002Y661392D01*
G01X1199702Y640359D02*
X1181002Y659058D01*
G01X1199702Y638025D02*
X1181002Y656725D01*
G01X1199702Y635692D02*
X1181002Y654392D01*
G01X1199702Y633359D02*
X1181002Y652058D01*
G01X1197847Y632879D02*
X1181002Y649725D01*
G01X1195514Y632879D02*
X1181002Y647392D01*
G01X1193181Y632879D02*
X1181002Y645057D01*
G01X1190847Y632879D02*
X1181002Y642724D01*
G01X1188514Y632879D02*
X1181002Y640391D01*
G01X1186181Y632879D02*
X1181002Y638057D01*
G01X1183846Y632879D02*
X1181002Y635724D01*
G01X1181513Y632879D02*
X1181002Y633391D01*
G01X1199702Y632879D02*
X1181002D01*
G01X1199702Y714829D02*
Y632879D01*
G01X1181002D02*
Y714829D01*
G01Y658221D02*
X1199702Y676921D01*
G01X1181002Y660554D02*
X1199702Y679254D01*
G01X1181002Y662888D02*
X1199702Y681587D01*
G01X1181002Y665221D02*
X1199702Y683921D01*
G01X1181002Y667555D02*
X1199702Y686255D01*
G01X1181002Y669888D02*
X1199702Y688588D01*
G01X1181002Y672222D02*
X1199702Y690922D01*
G01X1181002Y674555D02*
X1199702Y693255D01*
G01X1181002Y676888D02*
X1199702Y695588D01*
G01X1181002Y679222D02*
X1199702Y697922D01*
G01X1181002Y681555D02*
X1199702Y700255D01*
G01Y680027D02*
X1181002Y698727D01*
G01X1199702Y677694D02*
X1181002Y696393D01*
G01X1199702Y675360D02*
X1181002Y694060D01*
G01X1199702Y673027D02*
X1181002Y691727D01*
G01X1199702Y670694D02*
X1181002Y689393D01*
G01X1199702Y668360D02*
X1181002Y687060D01*
G01X1199702Y666027D02*
X1181002Y684727D01*
G01X1199702Y663694D02*
X1181002Y682392D01*
G01X1199702Y661359D02*
X1181002Y680059D01*
G01X1199702Y659026D02*
X1181002Y677726D01*
G01Y648888D02*
X1199702Y667586D01*
G01X1181002Y651221D02*
X1199702Y669921D01*
G01X1181002Y653554D02*
X1199702Y672254D01*
G01X1181002Y655888D02*
X1199702Y674587D01*
G01Y656693D02*
X1181002Y675393D01*
G01X1199702Y654359D02*
X1181002Y673059D01*
G01X1199702Y652026D02*
X1181002Y670726D01*
G01X1199702Y649693D02*
X1181002Y668393D01*
G01Y690889D02*
X1199702Y709589D01*
G01X1181002Y693223D02*
X1199702Y711922D01*
G01X1181002Y695556D02*
X1199702Y714256D01*
G01X1181002Y697889D02*
X1197941Y714829D01*
G01X1181002Y700223D02*
X1195608Y714829D01*
G01X1181002Y702557D02*
X1193275Y714829D01*
G01X1181002Y704890D02*
X1190940Y714829D01*
G01X1181002Y707224D02*
X1188607Y714829D01*
G01X1181002Y709557D02*
X1186274Y714829D01*
G01X1181002Y711890D02*
X1183940Y714829D01*
G01X1181002Y714224D02*
X1181607Y714829D01*
G01X1199702Y712695D02*
X1197568Y714829D01*
G01X1199702Y710362D02*
X1195235Y714829D01*
G01X1199702Y708029D02*
X1192902Y714829D01*
G01X1199702Y705696D02*
X1190569Y714829D01*
G01X1199702Y703362D02*
X1188234Y714829D01*
G01X1199702Y701029D02*
X1185901Y714829D01*
G01X1199702Y698696D02*
X1183568Y714829D01*
G01X1199702Y696361D02*
X1181234Y714829D01*
G01X1199702Y694028D02*
X1181002Y712728D01*
G01X1199702Y691695D02*
X1181002Y710394D01*
G01Y714829D02*
X1199702D01*
G01X1181002Y683888D02*
X1199702Y702588D01*
G01X1181002Y686223D02*
X1199702Y704922D01*
G01X1181002Y688556D02*
X1199702Y707256D01*
G01Y689361D02*
X1181002Y708061D01*
G01X1199702Y687028D02*
X1181002Y705728D01*
G01X1199702Y684695D02*
X1181002Y703394D01*
G01X1199702Y682361D02*
X1181002Y701061D01*
M02*
